Component Report
E:/<user>/9332_F0TG_MB_C/brd/0417/9332_F0TG_MB_C_V02_0417_0820.brd
Wed Apr 19 14:47:37 2023
Total Components:  8335
REFDES,COMP_DEVICE_TYPE,COMP_VALUE,COMP_TOL,COMP_PACKAGE,SYM_X,SYM_Y,SYM_ROTATE,SYM_MIRROR,EMBEDDED_STATUS,EMBEDDED_ATTACH,EMBEDDED_LAYER
BATTERY_BT2,"TP_TP-EMPTY,TP30",,,TP30,1009.39,-765.54,270.000,NO,,,
BIOS_LABEL,"TP_TP-EMPTY,TP30",,,TP30,61.09,16730.58,0.000,NO,,,
BT2,"CONN2_AAABAT029Y19-CONN2_AAA-BAT-029-Y19,THLF,IO,DA",,,BATTERY_AAA-BAT-029-Y19,11563.78,1338.66,270.000,NO,,,
C1,"Q_CAP_0402-0.1UF,25V,10%,X7R,CH4104K1B00",0.1UF,10%,C0402,12384.54,4472.55,0.000,NO,,,
C2,"Q_CAP_0402-0.1UF,25V,10%,X7R,CH4104K1B00",0.1UF,10%,C0402,9173.77,8834.54,270.000,YES,,,
C3,"Q_CAP_0402-0.1UF,25V,10%,X7R,CH4104K1B00",0.1UF,10%,C0402,9155.00,8585.00,90.000,YES,,,
C4,"Q_CAP_0402-0.1UF,25V,10%,X7R,CH4104K1B00",0.1UF,10%,C0402,16545.13,17101.84,270.000,NO,,,
C5,"Q_CAP_0402-0.1UF,25V,10%,X7R,CH4104K1B00",0.1UF,10%,C0402,17286.33,17218.40,270.000,NO,,,
C6,"Q_CAP_0402-0.1UF,25V,10%,EMPTY,CH4104K1B00",NA,10%,C0402,4208.31,16221.59,90.000,YES,,,
C7,"Q_CAP_0402-0.1UF,25V,10%,X7R,CH4104K1B00",0.1UF,10%,C0402,16893.83,17251.68,270.000,YES,,,
C8,"Q_CAP_0402-0.1UF,25V,10%,X7R,CH4104K1B00",0.1UF,10%,C0402,13860.45,17120.38,180.000,NO,,,
C9,"Q_CAP_C0402-1UF,25V,10%,EMPTY,CH5104KEB02",NA,10%,C0402,9090.00,9140.00,90.000,YES,,,
C10,"Q_CAP_0402-0.1UF,25V,10%,X7R,CH4104K1B00",0.1UF,10%,C0402,8291.68,4979.12,0.000,NO,,,
C11,"Q_CAP_0402-0.1UF,25V,10%,X7R,CH4104K1B00",0.1UF,10%,C0402,9167.63,9883.57,270.000,YES,,,
C12,"Q_CAP_0402-0.1UF,25V,10%,X7R,CH4104K1B00",0.1UF,10%,C0402,6589.67,16415.22,180.000,YES,,,
C13,"Q_CAP_0402-0.1UF,25V,10%,X7R,CH4104K1B00",0.1UF,10%,C0402,6472.58,17162.70,270.000,YES,,,
C14,"Q_CAP_0402-0.1UF,25V,10%,X7R,CH4104K1B00",0.1UF,10%,C0402,6472.58,17022.70,270.000,YES,,,
C15,"Q_CAP_0402-0.1UF,25V,10%,X7R,CH4104K1B00",0.1UF,10%,C0402,14066.33,16221.67,0.000,NO,,,
C16,"Q_CAP_0402-0.1UF,25V,10%,X7R,CH4104K1B00",0.1UF,10%,C0402,11910.37,16938.50,180.000,NO,,,
C17,"Q_CAP_0402-0.1UF,25V,10%,X7R,CH4104K1B00",0.1UF,10%,C0402,12102.54,17294.36,90.000,NO,,,
C18,"Q_CAP_0402-0.1UF,25V,10%,X7R,CH4104K1B00",0.1UF,10%,C0402,13904.93,16703.91,0.000,NO,,,
C19,"Q_CAP_0402-0.1UF,25V,10%,X7R,CH4104K1B00",0.1UF,10%,C0402,12063.79,16938.59,180.000,NO,,,
C20,"Q_CAP_C0402-0.1UF,16V,10%,X7R,CH4103K1B08",0.1UF,10%,C0402,6073.93,2600.10,180.000,NO,,,
C21,"Q_CAP_0402-0.1UF,25V,10%,X7R,CH4104K1B00",0.1UF,10%,C0402,17338.65,576.51,0.000,YES,,,
C22,"Q_CAP_C0402-0.01UF,50V,10%,EMPTY,CH31006KB18",NA,10%,C0402,12115.81,948.46,0.000,NO,,,
C23,"Q_CAP_0402-0.1UF,25V,10%,X7R,CH4104K1B00",0.1UF,10%,C0402,9296.03,8839.21,270.000,YES,,,
C24,"Q_CAP_C0402-10UF,6.3V,20%,EMPTY,CH6101MEB01",NA,20%,C0402,9180.00,9235.00,270.000,YES,,,
C25,"Q_CAP_0402-0.1UF,25V,10%,X7R,CH4104K1B00",0.1UF,10%,C0402,9485.00,9325.00,90.000,YES,,,
C26,"Q_CAP_0402-0.1UF,25V,10%,X7R,CH4104K1B00",0.1UF,10%,C0402,9340.00,8625.00,90.000,YES,,,
C27,"Q_CAP_0402-0.1UF,25V,10%,X7R,CH4104K1B00",0.1UF,10%,C0402,17338.65,536.51,180.000,NO,,,
C28,"Q_CAP_C0402-10UF,6.3V,20%,X6S,CH6101MEB01",10UF,20%,C0402,3956.05,16110.22,180.000,NO,,,
C29,"Q_CAP_C0402-0.22UF,25V,10%,X7R,CH4224K1B01",0.22UF,10%,C0402,8245.00,5100.00,90.000,NO,,,
C30,"Q_CAP_0402-0.1UF,25V,10%,X7R,CH4104K1B00",0.1UF,10%,C0402,15710.93,8040.63,0.000,YES,,,
C31,"Q_CAP_0402-0.1UF,25V,10%,X7R,CH4104K1B00",0.1UF,10%,C0402,4642.28,700.16,0.000,NO,,,
C32,"Q_CAP_0402-0.1UF,25V,10%,X7R,CH4104K1B00",0.1UF,10%,C0402,3848.24,16631.20,90.000,NO,,,
C33,"Q_CAP_0402-0.1UF,25V,10%,X7R,CH4104K1B00",0.1UF,10%,C0402,12596.07,1760.51,0.000,NO,,,
C34,"Q_CAP_C0805-22UF,16V,20%,X6S,CH6223MEA00",22UF,20%,C0805_H57,17335.96,630.51,0.000,YES,,,
C35,"Q_CAP_0402-100PF,50V,5%,EMPTY,CH11006JB18",NA,5%,C0402,12949.75,1344.09,180.000,YES,,,
C36,"Q_CAP_0402-0.1UF,25V,10%,X7R,CH4104K1B00",0.1UF,10%,C0402,18165.80,1518.34,0.000,NO,,,
C37,"Q_CAP_0402-0.1UF,25V,10%,X7R,CH4104K1B00",0.1UF,10%,C0402,12596.07,1805.51,0.000,NO,,,
C38,"Q_CAP_0402-0.1UF,25V,10%,X7R,CH4104K1B00",0.1UF,10%,C0402,3651.96,1301.65,0.000,NO,,,
C39,"Q_CAP_C0402-1UF,25V,10%,X6S,CH5104KEB02",1UF,10%,C0402,3673.15,2193.61,0.000,NO,,,
C40,"Q_CAP_C0402-0.01UF,50V,10%,EMPTY,CH31006KB18",NA,10%,C0402,3185.99,958.52,180.000,NO,,,
C41,"Q_CAP_DIFFBUS_C0201-DIFF BUS_0.22UF,6.3V,20%,X6S,SA",,,C0201_DIFF-BUS,15684.62,693.87,90.000,NO,,,
C42,"Q_CAP_0402-0.1UF,25V,10%,X7R,CH4104K1B00",0.1UF,10%,C0402,7119.07,6048.53,270.000,NO,,,
C43,"Q_CAP_0402-0.1UF,25V,10%,X7R,CH4104K1B00",0.1UF,10%,C0402,7118.45,5892.17,270.000,NO,,,
C44,"Q_CAP_DIFFBUS_C0201-DIFF BUS_0.22UF,6.3V,20%,X6S,SA",,,C0201_DIFF-BUS,16160.62,693.87,90.000,NO,,,
C45,"Q_CAP_C0402-1UF,25V,10%,X6S,CH5104KEB02",1UF,10%,C0402,11734.29,935.56,0.000,NO,,,
C46,"Q_CAP_DIFFBUS_C0201-DIFF BUS_0.22UF,6.3V,20%,X6S,SA",,,C0201_DIFF-BUS,16234.62,633.87,90.000,NO,,,
C47,"Q_CAP_DIFFBUS_C0201-DIFF BUS_0.22UF,6.3V,20%,X6S,SA",,,C0201_DIFF-BUS,16392.66,693.87,90.000,NO,,,
C48,"Q_CAP_DIFFBUS_C0201-DIFF BUS_0.22UF,6.3V,20%,X6S,SA",,,C0201_DIFF-BUS,5387.44,14975.82,0.000,NO,,,
C49,"Q_CAP_DIFFBUS_C0201-DIFF BUS_0.22UF,6.3V,20%,X6S,SA",,,C0201_DIFF-BUS,5387.44,14939.82,0.000,NO,,,
C50,"Q_CAP_DIFFBUS_C0201-DIFF BUS_0.22UF,6.3V,20%,X6S,SA",,,C0201_DIFF-BUS,5387.44,14805.82,0.000,NO,,,
C51,"Q_CAP_DIFFBUS_C0201-DIFF BUS_0.22UF,6.3V,20%,X6S,SA",,,C0201_DIFF-BUS,5387.44,14841.82,0.000,NO,,,
C52,"Q_CAP_DIFFBUS_C0201-DIFF BUS_0.22UF,6.3V,20%,X6S,SA",,,C0201_DIFF-BUS,5375.24,14589.45,270.000,NO,,,
C53,"Q_CAP_DIFFBUS_C0201-DIFF BUS_0.22UF,6.3V,20%,X6S,SA",,,C0201_DIFF-BUS,5339.24,14589.45,270.000,NO,,,
C54,"Q_CAP_DIFFBUS_C0201-DIFF BUS_0.22UF,6.3V,20%,X6S,SA",,,C0201_DIFF-BUS,5241.24,14589.45,270.000,NO,,,
C55,"Q_CAP_DIFFBUS_C0201-DIFF BUS_0.22UF,6.3V,20%,X6S,SA",,,C0201_DIFF-BUS,5205.24,14589.45,270.000,NO,,,
C56,"Q_CAP_DIFFBUS_C0201-DIFF BUS_0.22UF,6.3V,20%,X6S,SA",,,C0201_DIFF-BUS,1416.57,693.84,90.000,NO,,,
C57,"Q_CAP_C0805-10UF,16V,10%,EMPTY,CH6103KEA00",NA,10%,C0805_H57,15903.99,5624.88,270.000,NO,,,
C58,"Q_CAP_0402-0.1UF,25V,10%,X7R,CH4104K1B00",0.1UF,10%,C0402,4284.77,16083.70,0.000,YES,,,
C59,"Q_CAP_0402-100PF,50V,5%,EMPTY,CH11006JB18",NA,5%,C0402,12431.93,1282.39,180.000,NO,,,
C60,"Q_CAP_C0805-10UF,16V,10%,EMPTY,CH6103KEA00",NA,10%,C0805_H57,17579.70,2589.27,270.000,NO,,,
C61,"Q_CAP_C0402-100NF,50V,10%,X7R,CH4106K1B01",100NF,10%,C0402,17476.10,3051.06,0.000,NO,,,
C62,"Q_CAP_C0402-220PF,50V,5%,C0G,CH12206JB00",220PF,5%,C0402,12155.81,873.46,90.000,NO,,,
C63,"Q_CAP_C0402-220PF,50V,5%,C0G,CH12206JB00",220PF,5%,C0402,12234.55,873.46,90.000,NO,,,
C64,"Q_CAP_0402-0.1UF,25V,10%,EMPTY,CH4104K1B00",NA,10%,C0402,9187.80,16647.62,90.000,YES,,,
C65,"Q_CAP_0402-0.1UF,25V,10%,EMPTY,CH4104K1B00",NA,10%,C0402,9237.98,16647.62,90.000,YES,,,
C66,"Q_CAP_0402-0.1UF,25V,10%,EMPTY,CH4104K1B00",NA,10%,C0402,9477.98,16647.62,90.000,YES,,,
C67,"Q_CAP_0402-0.1UF,25V,10%,EMPTY,CH4104K1B00",NA,10%,C0402,9317.98,16647.62,90.000,YES,,,
C68,"Q_CAP_0402-0.1UF,25V,10%,X7R,CH4104K1B00",0.1UF,10%,C0402,4435.00,16187.00,0.000,NO,,,
C69,"Q_CAP_0402-0.1UF,25V,10%,X7R,CH4104K1B00",0.1UF,10%,C0402,10954.89,16976.04,270.000,NO,,,
C70,"Q_CAP_0402-0.1UF,25V,10%,X7R,CH4104K1B00",0.1UF,10%,C0402,10945.14,17174.16,270.000,NO,,,
C71,"Q_CAP_C0402-4.7PF,50V,0.1P,NPO,CH-4716TB06",4.7PF,0.10%,C0402,328.47,5360.40,90.000,NO,,,
C72,"Q_CAP_0402-0.1UF,25V,10%,X7R,CH4104K1B00",0.1UF,10%,C0402,14598.96,599.88,90.000,NO,,,
C73,"Q_CAP_0402-0.1UF,25V,10%,X7R,CH4104K1B00",0.1UF,10%,C0402,11605.11,739.39,180.000,NO,,,
C74,"Q_CAP_0402-0.1UF,25V,10%,EMPTY,CH4104K1B00",NA,10%,C0402,9397.98,16647.62,90.000,YES,,,
C75,"Q_CAP_0402-0.1UF,25V,10%,X7R,CH4104K1B00",0.1UF,10%,C0402,4258.20,16151.68,0.000,YES,,,
C76,"Q_CAP_C0402-10UF,6.3V,20%,X6S,CH6101MEB01",10UF,20%,C0402,11203.03,16779.35,90.000,NO,,,
C77,"Q_CAP_C0402-10UF,6.3V,20%,X6S,CH6101MEB01",10UF,20%,C0402,11050.00,16780.00,90.000,NO,,,
C78,"Q_CAP_0402-0.1UF,25V,10%,X7R,CH4104K1B00",0.1UF,10%,C0402,11167.14,16495.13,180.000,YES,,,
C79,"Q_CAP_0402-0.1UF,25V,10%,X7R,CH4104K1B00",0.1UF,10%,C0402,11338.07,16497.75,0.000,YES,,,
C80,"Q_CAP_0402-0.1UF,25V,10%,X7R,CH4104K1B00",0.1UF,10%,C0402,11295.00,16370.00,270.000,YES,,,
C81,"Q_CAP_0402-0.1UF,25V,10%,X7R,CH4104K1B00",0.1UF,10%,C0402,11229.65,16388.03,270.000,YES,,,
C82,"Q_CAP_C0402-10UF,6.3V,20%,X6S,CH6101MEB01",10UF,20%,C0402,4435.00,16227.00,0.000,NO,,,
C83,"Q_CAP_C0402-10UF,6.3V,20%,X6S,CH6101MEB01",10UF,20%,C0402,4210.00,16390.00,180.000,NO,,,
C84,"Q_CAP_0402-0.1UF,25V,10%,X7R,CH4104K1B00",0.1UF,10%,C0402,4210.00,16340.00,180.000,NO,,,
C85,"Q_CAP_C0402-0.001UF,50V,10%,X7R,CH30106KB19",0.001UF,10%,C0402,15974.53,2252.50,0.000,NO,,,
C86,"Q_CAP_C0402-0.01UF,50V,10%,EMPTY,CH31006KB18",NA,10%,C0402,5027.76,2092.85,180.000,NO,,,
C87,"Q_CAP_C0402-0.001UF,50V,10%,X7R,CH30106KB19",0.001UF,10%,C0402,15136.44,2479.25,90.000,NO,,,
C88,"Q_CAP_0402-0.1UF,25V,10%,X7R,CH4104K1B00",0.1UF,10%,C0402,12100.05,7637.65,0.000,YES,,,
C89,"Q_CAP_C0805-10UF,25V,10%,X6S,CH6104KEA00",10UF,10%,C0805_H61,12101.11,7585.04,0.000,YES,,,
C90,"Q_CAP_0402-0.1UF,25V,10%,X7R,CH4104K1B00",0.1UF,10%,C0402,3956.05,16070.22,180.000,NO,,,
C91,"Q_CAP_C0402-12PF,50V,5%,C0G,CH01206JB05",12PF,5%,C0402,4983.85,1096.99,270.000,NO,,,
C92,"Q_CAP_0402-0.1UF,25V,10%,X7R,CH4104K1B00",0.1UF,10%,C0402,11774.35,7637.65,0.000,YES,,,
C93,"Q_CAP_0402-15PF,50V,5%,C0G,CH01506JB06",15PF,5%,C0402,4983.14,1169.18,90.000,NO,,,
C94,"Q_CAP_C0402-4.7PF,50V,0.1P,NPO,CH-4716TB06",4.7PF,0.10%,C0402,327.74,5273.70,270.000,NO,,,
C95,"Q_CAP_0402-0.1UF,25V,10%,X7R,CH4104K1B00",0.1UF,10%,C0402,537.42,5332.65,90.000,YES,,,
C96,"Q_CAP_0402-0.1UF,25V,10%,X7R,CH4104K1B00",0.1UF,10%,C0402,11477.35,7637.65,0.000,YES,,,
C97,"Q_CAP_0402-0.1UF,25V,10%,X7R,CH4104K1B00",0.1UF,10%,C0402,592.22,5282.05,0.000,YES,,,
C98,"Q_CAP_0402-0.1UF,25V,10%,X7R,CH4104K1B00",0.1UF,10%,C0402,4115.03,16154.00,180.000,YES,,,
C99,"Q_CAP_0402-0.1UF,25V,10%,X7R,CH4104K1B00",0.1UF,10%,C0402,4114.76,16101.61,180.000,YES,,,
C100,"Q_CAP_0402-0.1UF,25V,10%,X7R,CH4104K1B00",0.1UF,10%,C0402,11180.34,7637.65,0.000,YES,,,
C101,"Q_CAP_0402-1000PF,50V,5%,EMPTY,TMP_QCH21006JB10",NA,5%,C0402,17284.63,16814.65,180.000,NO,,,
C102,"Q_CAP_C0805-100UF,4V,20%,X6S,CH710KMEA01",100UF,20%,C0805_H61,4061.94,15239.53,270.000,YES,,,
C103,"Q_CAP_C0805-100UF,4V,20%,X6S,CH710KMEA01",100UF,20%,C0805_H61,3993.86,15239.53,270.000,YES,,,
C104,"Q_CAP_0402-0.1UF,25V,10%,X7R,CH4104K1B00",0.1UF,10%,C0402,10883.33,7637.65,0.000,YES,,,
C105,"Q_CAP_0402-0.1UF,25V,10%,EMPTY,CH4104K1B00",NA,10%,C0402,8956.23,11378.43,180.000,NO,,,
C106,"Q_CAP_0402-0.1UF,25V,10%,X7R,CH4104K1B00",0.1UF,10%,C0402,11462.38,4898.19,0.000,NO,,,
C107,"Q_CAP_0402-1000PF,50V,5%,EMPTY,TMP_QCH21006JB10",NA,5%,C0402,768.06,15979.07,270.000,NO,,,
C108,"Q_CAP_0402-0.1UF,25V,10%,X7R,CH4104K1B00",0.1UF,10%,C0402,10586.32,7637.65,0.000,YES,,,
C109,"Q_CAP_0402-1000PF,50V,5%,X7R,TMP_QCH21006JB10",1000PF,5%,C0402,8912.07,11410.58,0.000,YES,,,
C110,"Q_CAP_C0402-22UF,4V,20%,X6S,CH622KMEB02",22UF,20%,C0402_H32,4075.61,15214.20,90.000,NO,,,
C111,"Q_CAP_C0402-22UF,4V,20%,X6S,CH622KMEB02",22UF,20%,C0402_H32,4016.59,15214.20,90.000,NO,,,
C112,"Q_CAP_0402-0.1UF,25V,10%,X7R,CH4104K1B00",0.1UF,10%,C0402,17851.67,7637.65,0.000,YES,,,
C113,"Q_CAP_C0805-100UF,4V,20%,X6S,CH710KMEA01",100UF,20%,C0805_H61,2781.32,15239.53,270.000,YES,,,
C114,"Q_CAP_C0805-100UF,4V,20%,X6S,CH710KMEA01",100UF,20%,C0805_H61,2713.24,15239.53,270.000,YES,,,
C115,"Q_CAP_C0402-22UF,4V,20%,X6S,CH622KMEB02",22UF,20%,C0402_H32,2794.99,15214.20,90.000,NO,,,
C116,"Q_CAP_0402-0.1UF,25V,10%,X7R,CH4104K1B00",0.1UF,10%,C0402,16366.63,7637.65,0.000,YES,,,
C117,"Q_CAP_C0402-22UF,4V,20%,X6S,CH622KMEB02",22UF,20%,C0402_H32,2735.97,15214.20,90.000,NO,,,
C118,"Q_CAP_C0402-10UF,6.3V,20%,X6S,CH6101MEB01",10UF,20%,C0402,2876.71,15226.22,270.000,YES,,,
C119,"Q_CAP_C0402-10UF,6.3V,20%,X6S,CH6101MEB01",10UF,20%,C0402,2243.75,15376.38,90.000,YES,,,
C120,"Q_CAP_0402-0.1UF,25V,10%,X7R,CH4104K1B00",0.1UF,10%,C0402,16663.64,7637.65,0.000,YES,,,
C121,"Q_CAP_0402-4.7UF,6.3V,20%,X6S,CH5471MEB01",4.7UF,20%,C0402,2196.51,15376.38,90.000,YES,,,
C122,"Q_CAP_0402-4.7UF,6.3V,20%,X6S,CH5471MEB01",4.7UF,20%,C0402,2836.71,15226.22,270.000,YES,,,
C123,"Q_CAP_0201-1UF,4V,20%,X6S,CH-10KMEE00",1UF,20%,C0201,2154.27,15276.03,270.000,YES,,,
C124,"Q_CAP_0402-0.1UF,25V,10%,X7R,CH4104K1B00",0.1UF,10%,C0402,16960.65,7637.65,0.000,YES,,,
C125,"Q_CAP_0201-1UF,4V,20%,X6S,CH-10KMEE00",1UF,20%,C0201,2290.49,15227.03,90.000,YES,,,
C126,"Q_CAP_0201-1UF,4V,20%,X6S,CH-10KMEE00",1UF,20%,C0201,2201.52,15276.03,270.000,YES,,,
C127,"Q_CAP_C0402-10UF,6.3V,20%,X6S,CH6101MEB01",10UF,20%,C0402,4117.33,15226.22,270.000,YES,,,
C128,"Q_CAP_0402-0.1UF,25V,10%,X7R,CH4104K1B00",0.1UF,10%,C0402,17257.66,7637.65,0.000,YES,,,
C129,"Q_CAP_C0201-0.1UF,10V,10%,X7S,CH4102K6E00",0.1UF,10%,C0201,2248.76,15276.03,270.000,YES,,,
C130,"Q_CAP_C0201-0.1UF,10V,10%,X7S,CH4102K6E00",0.1UF,10%,C0201,2296.00,15276.03,270.000,YES,,,
C131,"Q_CAP_C0201-0.1UF,10V,10%,X7S,CH4102K6E00",0.1UF,10%,C0201,2243.25,15227.03,90.000,YES,,,
C132,"Q_CAP_0402-0.1UF,25V,10%,X7R,CH4104K1B00",0.1UF,10%,C0402,17554.67,7637.65,0.000,YES,,,
C133,"Q_CAP_C0201-0.1UF,10V,10%,X7S,CH4102K6E00",0.1UF,10%,C0201,2196.01,15227.03,90.000,YES,,,
C134,"Q_CAP_C0201-0.1UF,10V,10%,X7S,CH4102K6E00",0.1UF,10%,C0201,2148.76,15227.03,90.000,YES,,,
C135,"Q_CAP_0201-1UF,4V,20%,X6S,CH-10KMEE00",1UF,20%,C0201,1865.30,15227.03,90.000,YES,,,
C136,"Q_CAP_0402-0.1UF,25V,10%,X7R,CH4104K1B00",0.1UF,10%,C0402,2338.63,7637.66,0.000,YES,,,
C137,"Q_CAP_C0201-0.1UF,10V,10%,X7S,CH4102K6E00",0.1UF,10%,C0201,2343.25,15276.03,270.000,YES,,,
C138,"Q_CAP_0201-1UF,4V,20%,X6S,CH-10KMEE00",1UF,20%,C0201,1959.79,15227.03,90.000,YES,,,
C139,"Q_CAP_C0201-0.1UF,10V,10%,X7S,CH4102K6E00",0.1UF,10%,C0201,2101.52,15227.03,90.000,YES,,,
C140,"Q_CAP_0402-0.1UF,25V,10%,X7R,CH4104K1B00",0.1UF,10%,C0402,2012.62,7637.66,0.000,YES,,,
C141,"Q_CAP_C0201-0.1UF,10V,10%,X7S,CH4102K6E00",0.1UF,10%,C0201,1918.05,15276.03,270.000,YES,,,
C142,"Q_CAP_C0805-10UF,25V,10%,X6S,CH6104KEA00",10UF,10%,C0805_H61,11939.69,7585.04,180.000,YES,,,
C143,"Q_CAP_C0805-10UF,25V,10%,X6S,CH6104KEA00",10UF,10%,C0805_H61,11804.10,7585.04,0.000,YES,,,
C144,"Q_CAP_0402-0.1UF,25V,10%,X7R,CH4104K1B00",0.1UF,10%,C0402,1715.62,7636.66,0.000,YES,,,
C145,"Q_CAP_C0805-10UF,25V,10%,X6S,CH6104KEA00",10UF,10%,C0805_H61,11642.68,7585.04,180.000,YES,,,
C146,"Q_CAP_C0805-10UF,25V,10%,X6S,CH6104KEA00",10UF,10%,C0805_H61,11345.68,7585.04,180.000,YES,,,
C147,"Q_CAP_C0805-10UF,25V,10%,X6S,CH6104KEA00",10UF,10%,C0805_H61,11507.10,7585.04,0.000,YES,,,
C148,"Q_CAP_0402-0.1UF,25V,10%,X7R,CH4104K1B00",0.1UF,10%,C0402,1418.92,7637.00,0.000,YES,,,
C149,"Q_CAP_C0805-10UF,25V,10%,X6S,CH6104KEA00",10UF,10%,C0805_H61,11048.67,7585.04,180.000,YES,,,
C150,"Q_CAP_C0805-10UF,25V,10%,X6S,CH6104KEA00",10UF,10%,C0805_H61,11210.09,7585.04,0.000,YES,,,
C151,"Q_CAP_C0805-10UF,25V,10%,X6S,CH6104KEA00",10UF,10%,C0805_H61,10913.08,7585.04,0.000,YES,,,
C152,"Q_CAP_0402-0.1UF,25V,10%,X7R,CH4104K1B00",0.1UF,10%,C0402,1120.60,7637.66,0.000,YES,,,
C153,"Q_CAP_C0805-10UF,25V,10%,X6S,CH6104KEA00",10UF,10%,C0805_H61,10751.66,7585.04,180.000,YES,,,
C154,"Q_CAP_C0805-10UF,25V,10%,X6S,CH6104KEA00",10UF,10%,C0805_H61,10616.07,7585.04,0.000,YES,,,
C155,"Q_CAP_C0805-10UF,25V,10%,X6S,CH6104KEA00",10UF,10%,C0805_H61,10454.65,7585.04,180.000,YES,,,
C156,"Q_CAP_0402-0.1UF,25V,10%,X7R,CH4104K1B00",0.1UF,10%,C0402,823.59,7637.66,0.000,YES,,,
C157,"Q_CAP_C0805-10UF,25V,10%,X6S,CH6104KEA00",10UF,10%,C0805_H61,16234.96,7585.04,180.000,YES,,,
C158,"Q_CAP_C0805-10UF,25V,10%,X6S,CH6104KEA00",10UF,10%,C0805_H61,16396.38,7585.04,0.000,YES,,,
C159,"Q_CAP_C0805-10UF,25V,10%,X6S,CH6104KEA00",10UF,10%,C0805_H61,16693.39,7585.04,0.000,YES,,,
C160,"Q_CAP_0402-0.1UF,25V,10%,X7R,CH4104K1B00",0.1UF,10%,C0402,6605.21,7637.66,0.000,YES,,,
C161,"Q_CAP_C0805-10UF,25V,10%,X6S,CH6104KEA00",10UF,10%,C0805_H61,16531.97,7585.04,180.000,YES,,,
C162,"Q_CAP_C0805-10UF,25V,10%,X6S,CH6104KEA00",10UF,10%,C0805_H61,16828.98,7585.04,180.000,YES,,,
C163,"Q_CAP_C0805-10UF,25V,10%,X6S,CH6104KEA00",10UF,10%,C0805_H61,16990.40,7585.04,0.000,YES,,,
C164,"Q_CAP_0402-0.1UF,25V,10%,X7R,CH4104K1B00",0.1UF,10%,C0402,6902.22,7637.66,0.000,YES,,,
C165,"Q_CAP_C0805-10UF,25V,10%,X6S,CH6104KEA00",10UF,10%,C0805_H61,17125.99,7585.04,180.000,YES,,,
C166,"Q_CAP_C0805-10UF,25V,10%,X6S,CH6104KEA00",10UF,10%,C0805_H61,17287.41,7585.04,0.000,YES,,,
C167,"Q_CAP_C0805-10UF,25V,10%,X6S,CH6104KEA00",10UF,10%,C0805_H61,17422.99,7585.04,180.000,YES,,,
C168,"Q_CAP_0402-0.1UF,25V,10%,X7R,CH4104K1B00",0.1UF,10%,C0402,7199.23,7637.66,0.000,YES,,,
C169,"Q_CAP_C0805-10UF,25V,10%,X6S,CH6104KEA00",10UF,10%,C0805_H61,17584.41,7585.04,0.000,YES,,,
C170,"Q_CAP_C0805-10UF,25V,10%,X6S,CH6104KEA00",10UF,10%,C0805_H61,17881.42,7585.04,0.000,YES,,,
C171,"Q_CAP_C0805-10UF,25V,10%,X6S,CH6104KEA00",10UF,10%,C0805_H61,17720.00,7585.04,180.000,YES,,,
C172,"Q_CAP_0402-0.1UF,25V,10%,X7R,CH4104K1B00",0.1UF,10%,C0402,7496.24,7637.66,0.000,YES,,,
C173,"Q_CAP_C0805-10UF,25V,10%,X6S,CH6104KEA00",10UF,10%,C0805_H61,2178.27,7585.05,180.000,YES,,,
C174,"Q_CAP_C0805-10UF,25V,10%,X6S,CH6104KEA00",10UF,10%,C0805_H61,2339.69,7585.05,0.000,YES,,,
C175,"Q_CAP_C0805-10UF,25V,10%,X6S,CH6104KEA00",10UF,10%,C0805_H61,1881.26,7585.05,180.000,YES,,,
C176,"Q_CAP_0402-0.1UF,25V,10%,X7R,CH4104K1B00",0.1UF,10%,C0402,7794.75,7637.66,0.000,YES,,,
C177,"Q_CAP_C0805-10UF,25V,10%,X6S,CH6104KEA00",10UF,10%,C0805_H61,2042.68,7585.05,0.000,YES,,,
C178,"Q_CAP_C0805-10UF,25V,10%,X6S,CH6104KEA00",10UF,10%,C0805_H61,1584.26,7585.05,180.000,YES,,,
C179,"Q_CAP_C0805-10UF,25V,10%,X6S,CH6104KEA00",10UF,10%,C0805_H61,1745.68,7585.05,0.000,YES,,,
C180,"Q_CAP_0402-0.1UF,25V,10%,X7R,CH4104K1B00",0.1UF,10%,C0402,8118.95,7637.65,0.000,YES,,,
C181,"Q_CAP_C0805-10UF,25V,10%,X6S,CH6104KEA00",10UF,10%,C0805_H61,1448.67,7585.05,0.000,YES,,,
C182,"Q_CAP_C0805-10UF,25V,10%,X6S,CH6104KEA00",10UF,10%,C0805_H61,1287.25,7585.05,180.000,YES,,,
C183,"Q_CAP_C0805-10UF,25V,10%,X6S,CH6104KEA00",10UF,10%,C0805_H61,1151.66,7585.05,0.000,YES,,,
C184,"Q_CAP_C0201-0.1UF,10V,10%,X7S,CH4102K6E00",0.1UF,10%,C0201,1965.30,15276.03,270.000,YES,,,
C185,"Q_CAP_0201-1UF,4V,20%,X6S,CH-10KMEE00",1UF,20%,C0201,2338.24,15390.13,90.000,YES,,,
C186,"Q_CAP_0201-1UF,4V,20%,X6S,CH-10KMEE00",1UF,20%,C0201,1857.20,15177.20,270.000,YES,,,
C187,"Q_CAP_0201-1UF,4V,20%,X6S,CH-10KMEE00",1UF,20%,C0201,2384.98,15227.03,90.000,YES,,,
C188,"Q_CAP_0201-1UF,4V,20%,X6S,CH-10KMEE00",1UF,20%,C0201,2573.96,15227.03,90.000,YES,,,
C189,"Q_CAP_C0201-0.1UF,10V,10%,X7S,CH4102K6E00",0.1UF,10%,C0201,2107.03,15276.03,270.000,YES,,,
C190,"Q_CAP_0201-1UF,4V,20%,X6S,CH-10KMEE00",1UF,20%,C0201,2432.23,15227.03,90.000,YES,,,
C191,"Q_CAP_C0201-0.1UF,10V,10%,X7S,CH4102K6E00",0.1UF,10%,C0201,2059.78,15276.03,270.000,YES,,,
C192,"Q_CAP_C0201-0.1UF,10V,10%,X7S,CH4102K6E00",0.1UF,10%,C0201,2532.23,15276.03,270.000,YES,,,
C193,"Q_CAP_C0402-100NF,50V,10%,X7R,CH4106K1B01",100NF,10%,C0402,11734.29,895.56,0.000,NO,,,
C194,"Q_CAP_C0402-0.1UF,16V,10%,X7R,CH4103K1B08",0.1UF,10%,C0402,5361.77,2452.05,90.000,NO,,,
C195,"Q_CAP_0402-4.7UF,6.3V,20%,X6S,CH5471MEB01",4.7UF,20%,C0402,3477.13,15376.38,90.000,YES,,,
C196,"Q_CAP_0402-1000PF,50V,5%,EMPTY,TMP_QCH21006JB10",NA,5%,C0402,16312.28,14361.48,180.000,NO,,,
C197,"Q_CAP_0402-1000PF,50V,5%,X7R,TMP_QCH21006JB10",1000PF,5%,C0402,16312.28,14322.48,180.000,NO,,,
C198,"Q_CAP_C0201-0.1UF,10V,10%,X7S,CH4102K6E00",0.1UF,10%,C0201,2390.49,15276.03,270.000,YES,,,
C199,"Q_CAP_C0402-10UF,6.3V,20%,X6S,CH6101MEB01",10UF,20%,C0402,3524.37,15376.38,90.000,YES,,,
C200,"Q_CAP_0402-4.7UF,6.3V,20%,X6S,CH5471MEB01",4.7UF,20%,C0402,4157.33,15226.22,270.000,YES,,,
C201,"Q_CAP_0201-1UF,4V,20%,X6S,CH-10KMEE00",1UF,20%,C0201,2054.27,15227.03,90.000,YES,,,
C202,"Q_CAP_0201-1UF,4V,20%,X6S,CH-10KMEE00",1UF,20%,C0201,3482.14,15276.03,270.000,YES,,,
C203,"Q_CAP_0201-1UF,4V,20%,X6S,CH-10KMEE00",1UF,20%,C0201,3571.11,15227.03,90.000,YES,,,
C204,"Q_CAP_0201-1UF,4V,20%,X6S,CH-10KMEE00",1UF,20%,C0201,3434.89,15276.03,270.000,YES,,,
C205,"Q_CAP_C0201-0.1UF,10V,10%,X7S,CH4102K6E00",0.1UF,10%,C0201,3429.38,15227.03,90.000,YES,,,
C206,"Q_CAP_C0201-0.1UF,10V,10%,X7S,CH4102K6E00",0.1UF,10%,C0201,3576.62,15276.03,270.000,YES,,,
C207,"Q_CAP_C0402-0.001UF,50V,10%,EMPTY,CH30106KB19",NA,10%,C0402,14771.77,8074.88,90.000,YES,,,
C208,"Q_CAP_C0402-0.001UF,50V,10%,EMPTY,CH30106KB19",NA,10%,C0402,14981.77,8209.88,90.000,YES,,,
C209,"Q_CAP_C0402-0.001UF,50V,10%,EMPTY,CH30106KB19",NA,10%,C0402,14781.77,8209.88,90.000,YES,,,
C210,"Q_CAP_C0402-0.001UF,50V,10%,EMPTY,CH30106KB19",NA,10%,C0402,14821.77,8209.88,90.000,YES,,,
C211,"Q_CAP_C0402-0.001UF,50V,10%,EMPTY,CH30106KB19",NA,10%,C0402,14941.77,8209.88,90.000,YES,,,
C212,"Q_CAP_C0402-0.001UF,50V,10%,EMPTY,CH30106KB19",NA,10%,C0402,14891.77,8074.88,90.000,YES,,,
C213,"Q_CAP_C0402-3.9P,50V,0.1P,NPO,CH-3916TB01",3.9P,0.1P,C0402,15592.63,12376.62,0.000,YES,,,
C214,"Q_CAP_C0402-3.9P,50V,0.1P,NPO,CH-3916TB01",3.9P,0.1P,C0402,15662.63,12376.62,180.000,YES,,,
C215,"Q_CAP_C0402-8.2PF,50V,0.1P,NP0,CH-8216TB09",8.2PF,0.1P,C0402,15778.03,12398.66,0.000,YES,,,
C216,"Q_CAP_C0402-8.2PF,50V,0.1P,NP0,CH-8216TB09",8.2PF,0.1P,C0402,15848.03,12398.66,180.000,YES,,,
C217,"Q_CAP_C0201-0.1UF,10V,10%,X7S,CH4102K6E00",0.1UF,10%,C0201,3523.87,15227.03,90.000,YES,,,
C218,"Q_CAP_0402-0.1UF,25V,10%,X7R,CH4104K1B00",0.1UF,10%,C0402,15809.24,13431.98,90.000,YES,,,
C219,"Q_CAP_0402-0.1UF,25V,10%,X7R,CH4104K1B00",0.1UF,10%,C0402,13696.84,1005.09,0.000,NO,,,
C220,"Q_CAP_C0805-100UF,4V,20%,X6S,CH710KMEA01",100UF,20%,C0805_H61,2750.46,15425.75,180.000,YES,,,
C221,"Q_CAP_0402-4.7UF,6.3V,20%,X6S,CH5471MEB01",4.7UF,20%,C0402,1830.21,15407.12,270.000,YES,,,
C222,"Q_CAP_0201-1UF,4V,20%,X6S,CH-10KMEE00",1UF,20%,C0201,2479.47,15227.03,90.000,YES,,,
C223,"Q_CAP_0402-0.1UF,25V,10%,X7R,CH4104K1B00",0.1UF,10%,C0402,15426.97,5635.87,90.000,NO,,,
C224,"Q_CAP_0402-0.1UF,25V,10%,X7R,CH4104K1B00",0.1UF,10%,C0402,3302.29,5660.86,0.000,NO,,,
C225,"Q_CAP_C0805-100UF,4V,20%,X6S,CH710KMEA01",100UF,20%,C0805_H61,2750.46,15357.21,180.000,YES,,,
C226,"Q_CAP_0402-0.1UF,25V,10%,X7R,CH4104K1B00",0.1UF,10%,C0402,15809.24,13576.78,90.000,YES,,,
C227,"Q_CAP_0402-4.7UF,6.3V,20%,X6S,CH5471MEB01",4.7UF,20%,C0402,1960.29,15376.38,90.000,YES,,,
C228,"Q_CAP_C0201-0.1UF,10V,10%,X7S,CH4102K6E00",0.1UF,10%,C0201,2484.98,15276.03,270.000,YES,,,
C229,"Q_CAP_C0805-100UF,4V,20%,X6S,CH710KMEA01",100UF,20%,C0805_H61,1910.38,15764.54,270.000,NO,,,
C230,"Q_CAP_C0402-0.001UF,50V,10%,EMPTY,CH30106KB19",NA,10%,C0402,6076.71,7843.88,270.000,YES,,,
C231,"Q_CAP_C0402-0.001UF,50V,10%,EMPTY,CH30106KB19",NA,10%,C0402,6116.71,7843.88,270.000,YES,,,
C232,"Q_CAP_C0402-0.001UF,50V,10%,EMPTY,CH30106KB19",NA,10%,C0402,5955.71,7951.88,270.000,YES,,,
C233,"Q_CAP_C0402-0.001UF,50V,10%,EMPTY,CH30106KB19",NA,10%,C0402,5994.71,7951.88,270.000,YES,,,
C234,"Q_CAP_C0402-0.001UF,50V,10%,EMPTY,CH30106KB19",NA,10%,C0402,5797.71,8018.88,270.000,YES,,,
C235,"Q_CAP_C0402-0.001UF,50V,10%,EMPTY,CH30106KB19",NA,10%,C0402,5836.71,8019.88,270.000,YES,,,
C236,"Q_CAP_C0402-2.7PF,50V,0.1PF,NPO,CH-276B0B00",2.7PF,0.1PF,C0402,5831.59,12380.75,0.000,YES,,,
C237,"Q_CAP_C0402-2.7PF,50V,0.1PF,NPO,CH-276B0B00",2.7PF,0.1PF,C0402,5901.59,12380.75,180.000,YES,,,
C238,"Q_CAP_0402-10PF,50V,1%,NPO,TMP_QCH0106F0B00",10PF,1%,C0402,5979.71,12454.88,90.000,YES,,,
C239,"Q_CAP_0402-10PF,50V,1%,NPO,TMP_QCH0106F0B00",10PF,1%,C0402,6121.71,12442.88,90.000,YES,,,
C240,"Q_CAP_C0805-100UF,4V,20%,X6S,CH710KMEA01",100UF,20%,C0805_H61,1884.33,15659.52,0.000,NO,,,
C241,"Q_CAP_0402-4.7UF,6.3V,20%,X6S,CH5471MEB01",4.7UF,20%,C0402,2385.48,15376.38,90.000,YES,,,
C242,"Q_CAP_0402-1000PF,50V,5%,X7R,TMP_QCH21006JB10",1000PF,5%,C0402,3759.43,5356.96,270.000,NO,,,
C243,"Q_CAP_0201-1UF,4V,20%,X6S,CH-10KMEE00",1UF,20%,C0201,1912.54,15227.03,90.000,YES,,,
C244,"Q_CAP_C0402-22UF,4V,20%,X6S,CH622KMEB02",22UF,20%,C0402_H32,2291.00,15376.38,90.000,YES,,,
C245,"Q_CAP_C0402-22UF,4V,20%,X6S,CH622KMEB02",22UF,20%,C0402_H32,13906.77,9664.88,0.000,YES,,,
C246,"Q_CAP_C0402-22UF,4V,20%,X6S,CH622KMEB02",22UF,20%,C0402_H32,14328.01,9817.65,0.000,YES,,,
C247,"Q_CAP_C0805-100UF,4V,20%,X6S,CH710KMEA01",100UF,20%,C0805_H61,1884.59,15590.98,0.000,NO,,,
C248,"Q_CAP_0402-1000PF,50V,5%,EMPTY,TMP_QCH21006JB10",NA,5%,C0402,3551.57,5584.15,0.000,YES,,,
C249,"Q_CAP_0402-1000PF,50V,5%,X7R,TMP_QCH21006JB10",1000PF,5%,C0402,3551.57,5624.15,0.000,YES,,,
C250,"Q_CAP_C0402-10UF,6.3V,20%,X6S,CH6101MEB01",10UF,20%,C0402,1865.79,15376.38,90.000,YES,,,
C251,"Q_CAP_C0402-22UF,4V,20%,X6S,CH622KMEB02",22UF,20%,C0402_H32,14163.01,9687.65,90.000,YES,,,
C252,"Q_CAP_C0402-22UF,4V,20%,X6S,CH622KMEB02",22UF,20%,C0402_H32,13976.77,9664.88,180.000,YES,,,
C253,"Q_CAP_C0201-0.1UF,10V,10%,X7S,CH4102K6E00",0.1UF,10%,C0201,2579.47,15276.03,270.000,YES,,,
C254,"Q_CAP_C0402-10UF,6.3V,20%,X6S,CH6101MEB01",10UF,20%,C0402,2007.53,15376.38,90.000,YES,,,
C255,"Q_CAP_C0402-22UF,4V,20%,X6S,CH622KMEB02",22UF,20%,C0402_H32,2054.78,15376.38,90.000,YES,,,
C256,"Q_CAP_0402-4.7UF,6.3V,20%,X6S,CH5471MEB01",4.7UF,20%,C0402,2102.02,15376.38,90.000,YES,,,
C257,"Q_CAP_0201-1UF,4V,20%,X6S,CH-10KMEE00",1UF,20%,C0201,1788.13,15238.20,0.000,YES,,,
C258,"Q_CAP_0402-4.7UF,6.3V,20%,X6S,CH5471MEB01",4.7UF,20%,C0402,2527.22,15376.38,90.000,YES,,,
C259,"Q_CAP_C0402-22UF,4V,20%,X6S,CH622KMEB02",22UF,20%,C0402_H32,1913.04,15376.38,90.000,YES,,,
C260,"Q_CAP_C0201-0.1UF,10V,10%,X7S,CH4102K6E00",0.1UF,10%,C0201,2012.54,15276.03,270.000,YES,,,
C261,"Q_CAP_C0402-10UF,6.3V,20%,X6S,CH6101MEB01",10UF,20%,C0402,2149.26,15376.38,90.000,YES,,,
C262,"Q_CAP_C0402-22UF,4V,20%,X6S,CH622KMEB02",22UF,20%,C0402_H32,2627.77,15376.38,90.000,YES,,,
C263,"Q_CAP_C0402-22UF,4V,20%,X6S,CH622KMEB02",22UF,20%,C0402_H32,13978.01,9782.65,180.000,YES,,,
C264,"Q_CAP_C0201-0.1UF,10V,10%,X7S,CH4102K6E00",0.1UF,10%,C0201,2654.23,15266.48,180.000,YES,,,
C265,"Q_CAP_0201-1UF,4V,20%,X6S,CH-10KMEE00",1UF,20%,C0201,2007.03,15227.03,90.000,YES,,,
C266,"Q_CAP_C0201-0.1UF,10V,10%,X7S,CH4102K6E00",0.1UF,10%,C0201,2337.74,15227.03,90.000,YES,,,
C267,"Q_CAP_C0402-22UF,4V,20%,X6S,CH622KMEB02",22UF,20%,C0402_H32,14346.77,9664.88,0.000,YES,,,
C268,"Q_CAP_C0402-22UF,4V,20%,X6S,CH622KMEB02",22UF,20%,C0402_H32,14031.77,9817.65,180.000,YES,,,
C269,"Q_CAP_C0402-10UF,6.3V,20%,X6S,CH6101MEB01",10UF,20%,C0402,2574.46,15376.38,90.000,YES,,,
C270,"Q_CAP_C0402-22UF,4V,20%,X6S,CH622KMEB02",22UF,20%,C0402_H32,14018.97,9852.65,0.000,YES,,,
C271,"Q_CAP_C0402-22UF,4V,20%,X6S,CH622KMEB02",22UF,20%,C0402_H32,14478.01,9877.65,0.000,YES,,,
C272,"Q_CAP_C0402-22UF,4V,20%,X6S,CH622KMEB02",22UF,20%,C0402_H32,14698.01,9817.65,0.000,YES,,,
C273,"Q_CAP_C0402-22UF,4V,20%,X6S,CH622KMEB02",22UF,20%,C0402_H32,13961.77,9817.65,180.000,YES,,,
C274,"Q_CAP_C0402-22UF,4V,20%,X6S,CH622KMEB02",22UF,20%,C0402_H32,14628.01,9817.65,0.000,YES,,,
C275,"Q_CAP_C0402-22UF,4V,20%,X6S,CH622KMEB02",22UF,20%,C0402_H32,13639.77,9782.65,180.000,YES,,,
C276,"Q_CAP_C0402-22UF,4V,20%,X6S,CH622KMEB02",22UF,20%,C0402_H32,13811.77,9877.65,180.000,YES,,,
C277,"Q_CAP_C0402-22UF,4V,20%,X6S,CH622KMEB02",22UF,20%,C0402_H32,14421.77,9664.88,180.000,YES,,,
C278,"Q_CAP_C0402-22UF,4V,20%,X6S,CH622KMEB02",22UF,20%,C0402_H32,13886.77,9817.65,180.000,YES,,,
C279,"Q_CAP_C0402-22UF,4V,20%,X6S,CH622KMEB02",22UF,20%,C0402_H32,14088.01,9852.65,0.000,YES,,,
C280,"Q_CAP_0201-1UF,4V,20%,X6S,CH-10KMEE00",1UF,20%,C0201,2621.41,15227.03,90.000,YES,,,
C281,"Q_CAP_C0201-0.1UF,10V,10%,X7S,CH4102K6E00",0.1UF,10%,C0201,1775.59,15299.57,90.000,YES,,,
C282,"Q_CAP_C0201-0.1UF,10V,10%,X7S,CH4102K6E00",0.1UF,10%,C0201,1870.81,15276.03,270.000,YES,,,
C283,"Q_CAP_C0201-0.1UF,10V,10%,X7S,CH4102K6E00",0.1UF,10%,C0201,2437.74,15276.03,270.000,YES,,,
C284,"Q_CAP_C0402-22UF,4V,20%,X6S,CH622KMEB02",22UF,20%,C0402_H32,2479.97,15376.38,90.000,YES,,,
C285,"Q_CAP_0201-1UF,4V,20%,X6S,CH-10KMEE00",1UF,20%,C0201,2526.72,15227.03,90.000,YES,,,
C286,"Q_CAP_C0402-10UF,6.3V,20%,X6S,CH6101MEB01",10UF,20%,C0402,2432.73,15376.38,90.000,YES,,,
C287,"Q_CAP_C0201-0.1UF,10V,10%,X7S,CH4102K6E00",0.1UF,10%,C0201,3529.38,15276.03,270.000,YES,,,
C288,"Q_CAP_C0201-0.1UF,10V,10%,X7S,CH4102K6E00",0.1UF,10%,C0201,3476.63,15227.03,90.000,YES,,,
C289,"Q_CAP_0201-1UF,4V,20%,X6S,CH-10KMEE00",1UF,20%,C0201,3854.58,15227.03,90.000,YES,,,
C290,"Q_CAP_C0201-0.1UF,10V,10%,X7S,CH4102K6E00",0.1UF,10%,C0201,3387.65,15276.03,270.000,YES,,,
C291,"Q_CAP_C0201-0.1UF,10V,10%,X7S,CH4102K6E00",0.1UF,10%,C0201,3860.09,15276.03,270.000,YES,,,
C292,"Q_CAP_C0201-0.1UF,10V,10%,X7S,CH4102K6E00",0.1UF,10%,C0201,3382.14,15227.03,90.000,YES,,,
C293,"Q_CAP_0201-1UF,4V,20%,X6S,CH-10KMEE00",1UF,20%,C0201,3137.82,15177.20,270.000,YES,,,
C294,"Q_CAP_0201-1UF,4V,20%,X6S,CH-10KMEE00",1UF,20%,C0201,3287.65,15227.03,90.000,YES,,,
C295,"Q_CAP_0402-10PF,50V,5%,EMPTY,CH01006JB08",NA,5%,C0402,3471.57,5864.15,180.000,NO,,,
C296,"Q_CAP_0402-10PF,50V,5%,EMPTY,CH01006JB08",NA,5%,C0402,3380.00,5785.00,0.000,YES,,,
C297,"Q_CAP_0402-10PF,50V,5%,EMPTY,CH01006JB08",NA,5%,C0402,3380.00,5825.00,0.000,YES,,,
C298,"Q_CAP_0402-10PF,50V,5%,EMPTY,CH01006JB08",NA,5%,C0402,14602.57,5769.77,0.000,YES,,,
C299,"Q_CAP_0402-10PF,50V,5%,EMPTY,CH01006JB08",NA,5%,C0402,14602.57,5689.77,0.000,YES,,,
C300,"Q_CAP_C0201-0.1UF,10V,10%,X7S,CH4102K6E00",0.1UF,10%,C0201,3618.36,15227.03,90.000,YES,,,
C301,"Q_CAP_0201-1UF,4V,20%,X6S,CH-10KMEE00",1UF,20%,C0201,3068.75,15238.20,0.000,YES,,,
C302,"Q_CAP_0402-10PF,50V,5%,EMPTY,CH01006JB08",NA,5%,C0402,14602.57,5729.77,0.000,YES,,,
C303,"Q_CAP_0402-10PF,50V,5%,EMPTY,CH01006JB08",NA,5%,C0402,11895.00,14010.00,180.000,NO,,,
C304,"Q_CAP_0402-10PF,50V,5%,EMPTY,CH01006JB08",NA,5%,C0402,11895.00,14100.00,180.000,NO,,,
C305,"Q_CAP_0402-10PF,50V,5%,EMPTY,CH01006JB08",NA,5%,C0402,11895.00,14055.00,180.000,NO,,,
C306,"Q_CAP_0201-1UF,4V,20%,X6S,CH-10KMEE00",1UF,20%,C0201,3334.89,15227.03,90.000,YES,,,
C307,"Q_CAP_0201-1UF,4V,20%,X6S,CH-10KMEE00",1UF,20%,C0201,3760.09,15227.03,90.000,YES,,,
C308,"Q_CAP_0402-10PF,50V,5%,EMPTY,CH01006JB08",NA,5%,C0402,885.00,14125.00,180.000,NO,,,
C309,"Q_CAP_0402-10PF,50V,5%,EMPTY,CH01006JB08",NA,5%,C0402,885.00,14215.00,180.000,NO,,,
C310,"Q_CAP_0402-10PF,50V,5%,EMPTY,CH01006JB08",NA,5%,C0402,885.00,14170.00,180.000,NO,,,
C311,"Q_CAP_C0201-0.1UF,10V,10%,X7S,CH4102K6E00",0.1UF,10%,C0201,3623.87,15276.03,270.000,YES,,,
C312,"Q_CAP_C0201-0.1UF,10V,10%,X7S,CH4102K6E00",0.1UF,10%,C0201,3056.21,15299.57,90.000,YES,,,
C313,"Q_CAP_C0201-0.1UF,10V,10%,X7S,CH4102K6E00",0.1UF,10%,C0201,3340.40,15276.03,270.000,YES,,,
C314,"Q_CAP_0201-1UF,4V,20%,X6S,CH-10KMEE00",1UF,20%,C0201,3712.85,15227.03,90.000,YES,,,
C315,"Q_CAP_0201-1UF,4V,20%,X6S,CH-10KMEE00",1UF,20%,C0201,3665.60,15227.03,90.000,YES,,,
C316,"Q_CAP_C0201-0.1UF,10V,10%,X7S,CH4102K6E00",0.1UF,10%,C0201,3671.11,15276.03,270.000,YES,,,
C317,"Q_CAP_C0805-100UF,4V,20%,X6S,CH710KMEA01",100UF,20%,C0805_H61,4031.08,15357.21,180.000,YES,,,
C318,"Q_CAP_C0402-22UF,4V,20%,X6S,CH622KMEB02",22UF,20%,C0402_H32,3335.40,15376.38,90.000,YES,,,
C319,"Q_CAP_C0201-0.1UF,10V,10%,X7S,CH4102K6E00",0.1UF,10%,C0201,3245.92,15276.03,270.000,YES,,,
C320,"Q_CAP_C0805-100UF,4V,20%,X6S,CH710KMEA01",100UF,20%,C0805_H61,2950.68,15377.46,0.000,YES,,,
C321,"Q_CAP_C0402-10UF,6.3V,20%,X6S,CH6101MEB01",10UF,20%,C0402,3288.15,15376.38,90.000,YES,,,
C322,"Q_CAP_C0201-0.1UF,10V,10%,X7S,CH4102K6E00",0.1UF,10%,C0201,3198.67,15276.03,270.000,YES,,,
C323,"Q_CAP_C0805-100UF,4V,20%,X6S,CH710KMEA01",100UF,20%,C0805_H61,2852.86,15341.46,90.000,YES,,,
C324,"Q_CAP_C0805-100UF,4V,20%,X6S,CH710KMEA01",100UF,20%,C0805_H61,2950.42,15308.92,0.000,YES,,,
C325,"Q_CAP_0402-4.7UF,6.3V,20%,X6S,CH5471MEB01",4.7UF,20%,C0402,3240.91,15376.38,90.000,YES,,,
C326,"Q_CAP_0201-1UF,4V,20%,X6S,CH-10KMEE00",1UF,20%,C0201,3145.92,15227.03,90.000,YES,,,
C327,"Q_CAP_C0402-22UF,4V,20%,X6S,CH622KMEB02",22UF,20%,C0402_H32,3571.62,15376.38,90.000,YES,,,
C328,"Q_CAP_C0805-100UF,4V,20%,X6S,CH710KMEA01",100UF,20%,C0805_H61,4031.08,15425.75,180.000,YES,,,
C329,"Q_CAP_C0402-22UF,4V,20%,X6S,CH622KMEB02",22UF,20%,C0402_H32,3193.66,15376.38,90.000,YES,,,
C330,"Q_CAP_0201-1UF,4V,20%,X6S,CH-10KMEE00",1UF,20%,C0201,3193.16,15227.03,90.000,YES,,,
C331,"Q_CAP_0402-4.7UF,6.3V,20%,X6S,CH5471MEB01",4.7UF,20%,C0402,3807.84,15376.38,90.000,YES,,,
C332,"Q_CAP_C0402-10UF,6.3V,20%,X6S,CH6101MEB01",10UF,20%,C0402,3146.41,15376.38,90.000,YES,,,
C333,"Q_CAP_C0402-10UF,6.3V,20%,X6S,CH6101MEB01",10UF,20%,C0402,3429.88,15376.38,90.000,YES,,,
C334,"Q_CAP_C0201-0.1UF,10V,10%,X7S,CH4102K6E00",0.1UF,10%,C0201,3293.16,15276.03,270.000,YES,,,
C335,"Q_CAP_C0402-22UF,4V,20%,X6S,CH622KMEB02",22UF,20%,C0402_H32,3760.59,15376.38,90.000,YES,,,
C336,"Q_CAP_0402-4.7UF,6.3V,20%,X6S,CH5471MEB01",4.7UF,20%,C0402,3110.83,15407.12,270.000,YES,,,
C337,"Q_CAP_0201-1UF,4V,20%,X6S,CH-10KMEE00",1UF,20%,C0201,3240.41,15227.03,90.000,YES,,,
C338,"Q_CAP_0402-4.7UF,6.3V,20%,X6S,CH5471MEB01",4.7UF,20%,C0402,3382.64,15376.38,90.000,YES,,,
C339,"Q_CAP_C0402-10UF,6.3V,20%,X6S,CH6101MEB01",10UF,20%,C0402,3713.35,15376.38,90.000,YES,,,
C340,"Q_CAP_C0201-0.1UF,10V,10%,X7S,CH4102K6E00",0.1UF,10%,C0201,3812.85,15276.03,270.000,YES,,,
C341,"Q_CAP_C0201-0.1UF,10V,10%,X7S,CH4102K6E00",0.1UF,10%,C0201,3151.43,15276.03,270.000,YES,,,
C342,"Q_CAP_0201-1UF,4V,20%,X6S,CH-10KMEE00",1UF,20%,C0201,3618.86,15390.13,90.000,YES,,,
C343,"Q_CAP_0402-4.7UF,6.3V,20%,X6S,CH5471MEB01",4.7UF,20%,C0402,3666.10,15376.38,90.000,YES,,,
C344,"Q_CAP_C0201-0.1UF,10V,10%,X7S,CH4102K6E00",0.1UF,10%,C0201,3765.60,15276.03,270.000,YES,,,
C345,"Q_CAP_0402-0.1UF,25V,10%,EMPTY,CH4104K1B00",NA,10%,C0402,8487.62,5259.88,90.000,NO,,,
C346,"Q_CAP_0201-1UF,4V,20%,X6S,CH-10KMEE00",1UF,20%,C0201,3807.34,15227.03,90.000,YES,,,
C347,"Q_CAP_0402-0.1UF,25V,10%,X7R,CH4104K1B00",0.1UF,10%,C0402,3871.84,4744.95,270.000,NO,,,
C348,"Q_CAP_0402-0.1UF,25V,10%,EMPTY,CH4104K1B00",NA,10%,C0402,8062.71,13519.88,0.000,NO,,,
C349,"Q_CAP_C0201-0.1UF,10V,10%,X7S,CH4102K6E00",0.1UF,10%,C0201,3934.85,15266.48,180.000,YES,,,
C350,"Q_CAP_C0201-0.1UF,10V,10%,X7S,CH4102K6E00",0.1UF,10%,C0201,3718.36,15276.03,270.000,YES,,,
C351,"Q_CAP_C0402-22UF,4V,20%,X6S,CH622KMEB02",22UF,20%,C0402_H32,3908.39,15376.38,90.000,YES,,,
C352,"Q_CAP_C0402-0.1UF,16V,10%,X7R,CH4103K1B08",0.1UF,10%,C0402,7088.00,4201.20,90.000,YES,,,
C353,"Q_CAP_0201-1UF,4V,20%,X6S,CH-10KMEE00",1UF,20%,C0201,3902.03,15227.03,90.000,YES,,,
C354,"Q_CAP_C0402-10UF,6.3V,20%,X6S,CH6101MEB01",10UF,20%,C0402,3855.08,15376.38,90.000,YES,,,
C355,"Q_CAP_C0402-0.1UF,16V,10%,X7R,CH4103K1B08",0.1UF,10%,C0402,7178.44,4528.44,180.000,YES,,,
C356,"Q_CAP_C0402-0.1UF,16V,10%,X7R,CH4103K1B08",0.1UF,10%,C0402,7429.61,4482.79,0.000,YES,,,
C357,"Q_CAP_C0402-0.1UF,16V,10%,X7R,CH4103K1B08",0.1UF,10%,C0402,7178.44,4482.79,180.000,YES,,,
C358,"Q_CAP_C0402-0.1UF,16V,10%,X7R,CH4103K1B08",0.1UF,10%,C0402,7350.86,4467.04,90.000,YES,,,
C359,"Q_CAP_C0402-0.1UF,16V,10%,X7R,CH4103K1B08",0.1UF,10%,C0402,7257.18,4467.04,90.000,YES,,,
C360,"Q_CAP_C0402-0.1UF,16V,10%,X7R,CH4103K1B08",0.1UF,10%,C0402,7429.61,4576.49,0.000,YES,,,
C361,"Q_CAP_C0402-0.1UF,16V,10%,X7R,CH4103K1B08",0.1UF,10%,C0402,7429.61,4528.44,0.000,YES,,,
C362,"Q_CAP_C0402-0.1UF,16V,10%,X7R,CH4103K1B08",0.1UF,10%,C0402,7301.52,4467.04,90.000,YES,,,
C363,"Q_CAP_C0402-220PF,50V,5%,C0G,CH12206JB00",220PF,5%,C0402,14468.69,1098.61,270.000,NO,,,
C364,"Q_CAP_C0402-220PF,50V,5%,C0G,CH12206JB00",220PF,5%,C0402,14345.13,1114.00,270.000,NO,,,
C365,"Q_CAP_C0201-0.1UF,10V,10%,X7S,CH4102K6E00",0.1UF,10%,C0201,9785.00,13075.00,0.000,YES,,,
C366,"Q_CAP_C0805-100UF,4V,20%,X6S,CH710KMEA01",100UF,20%,C0805_H61,6822.00,15178.00,90.000,NO,,,
C367,"Q_CAP_C0805-100UF,4V,20%,X6S,CH710KMEA01",100UF,20%,C0805_H61,6702.00,15212.00,0.000,NO,,,
C368,"Q_CAP_C0402-22UF,4V,20%,X6S,CH622KMEB02",22UF,20%,C0402_H32,6881.20,15180.26,90.000,NO,,,
C369,"Q_CAP_C0402-22UF,4V,20%,X6S,CH622KMEB02",22UF,20%,C0402_H32,6658.32,15290.00,90.000,NO,,,
C370,"Q_CAP_C0402-10UF,6.3V,20%,X6S,CH6101MEB01",10UF,20%,C0402,6817.77,15265.26,0.000,NO,,,
C371,"Q_CAP_0402-4.7UF,6.3V,20%,X6S,CH5471MEB01",4.7UF,20%,C0402,6118.86,15376.38,90.000,YES,,,
C372,"Q_CAP_C0402-10UF,6.3V,20%,X6S,CH6101MEB01",10UF,20%,C0402,6166.10,15376.38,90.000,YES,,,
C373,"Q_CAP_0402-4.7UF,6.3V,20%,X6S,CH5471MEB01",4.7UF,20%,C0402,6817.77,15305.26,0.000,NO,,,
C374,"Q_CAP_0201-1UF,4V,20%,X6S,CH-10KMEE00",1UF,20%,C0201,6076.62,15276.03,270.000,YES,,,
C375,"Q_CAP_0201-1UF,4V,20%,X6S,CH-10KMEE00",1UF,20%,C0201,6212.84,15227.03,90.000,YES,,,
C376,"Q_CAP_0201-1UF,4V,20%,X6S,CH-10KMEE00",1UF,20%,C0201,6123.87,15276.03,270.000,YES,,,
C377,"Q_CAP_C0201-0.1UF,10V,10%,X7S,CH4102K6E00",0.1UF,10%,C0201,6118.36,15227.03,90.000,YES,,,
C378,"Q_CAP_C0201-0.1UF,10V,10%,X7S,CH4102K6E00",0.1UF,10%,C0201,6218.35,15276.03,270.000,YES,,,
C379,"Q_CAP_C0201-0.1UF,10V,10%,X7S,CH4102K6E00",0.1UF,10%,C0201,6171.11,15276.03,270.000,YES,,,
C380,"Q_CAP_C0201-0.1UF,10V,10%,X7S,CH4102K6E00",0.1UF,10%,C0201,6165.60,15227.03,90.000,YES,,,
C381,"Q_CAP_C0201-0.1UF,10V,10%,X7S,CH4102K6E00",0.1UF,10%,C0201,6071.11,15227.03,90.000,YES,,,
C382,"Q_CAP_0201-1UF,4V,20%,X6S,CH-10KMEE00",1UF,20%,C0201,6496.31,15227.03,90.000,YES,,,
C383,"Q_CAP_C0201-0.1UF,10V,10%,X7S,CH4102K6E00",0.1UF,10%,C0201,6029.38,15276.03,270.000,YES,,,
C384,"Q_CAP_0201-1UF,4V,20%,X6S,CH-10KMEE00",1UF,20%,C0201,5710.48,15238.20,0.000,YES,,,
C385,"Q_CAP_C0201-0.1UF,10V,10%,X7S,CH4102K6E00",0.1UF,10%,C0201,6023.87,15227.03,90.000,YES,,,
C386,"Q_CAP_0201-1UF,4V,20%,X6S,CH-10KMEE00",1UF,20%,C0201,5779.55,15177.20,270.000,YES,,,
C387,"Q_CAP_0201-1UF,4V,20%,X6S,CH-10KMEE00",1UF,20%,C0201,6354.58,15227.03,90.000,YES,,,
C388,"Q_CAP_C0201-0.1UF,10V,10%,X7S,CH4102K6E00",0.1UF,10%,C0201,6265.60,15276.03,270.000,YES,,,
C389,"Q_CAP_0201-1UF,4V,20%,X6S,CH-10KMEE00",1UF,20%,C0201,5929.38,15227.03,90.000,YES,,,
C390,"Q_CAP_0201-1UF,4V,20%,X6S,CH-10KMEE00",1UF,20%,C0201,5976.62,15227.03,90.000,YES,,,
C391,"Q_CAP_0201-1UF,4V,20%,X6S,CH-10KMEE00",1UF,20%,C0201,6401.82,15227.03,90.000,YES,,,
C392,"Q_CAP_C0201-0.1UF,10V,10%,X7S,CH4102K6E00",0.1UF,10%,C0201,6260.09,15227.03,90.000,YES,,,
C393,"Q_CAP_C0201-0.1UF,10V,10%,X7S,CH4102K6E00",0.1UF,10%,C0201,5697.94,15299.57,90.000,YES,,,
C394,"Q_CAP_0201-1UF,4V,20%,X6S,CH-10KMEE00",1UF,20%,C0201,6307.33,15227.03,90.000,YES,,,
C395,"Q_CAP_C0201-0.1UF,10V,10%,X7S,CH4102K6E00",0.1UF,10%,C0201,6501.82,15276.03,270.000,YES,,,
C396,"Q_CAP_C0201-0.1UF,10V,10%,X7S,CH4102K6E00",0.1UF,10%,C0201,5982.13,15276.03,270.000,YES,,,
C397,"Q_CAP_C0201-0.1UF,10V,10%,X7S,CH4102K6E00",0.1UF,10%,C0201,6312.84,15276.03,270.000,YES,,,
C398,"Q_CAP_C0805-100UF,4V,20%,X6S,CH710KMEA01",100UF,20%,C0805_H61,6701.33,15435.99,0.000,NO,,,
C399,"Q_CAP_C0402-22UF,4V,20%,X6S,CH622KMEB02",22UF,20%,C0402_H32,5977.13,15376.38,90.000,YES,,,
C400,"Q_CAP_C0201-0.1UF,10V,10%,X7S,CH4102K6E00",0.1UF,10%,C0201,6407.33,15276.03,270.000,YES,,,
C401,"Q_CAP_C0805-100UF,4V,20%,X6S,CH710KMEA01",100UF,20%,C0805_H61,6701.33,15367.45,0.000,NO,,,
C402,"Q_CAP_C0402-22UF,4V,20%,X6S,CH622KMEB02",22UF,20%,C0402_H32,6550.12,15376.38,90.000,YES,,,
C403,"Q_CAP_C0201-0.1UF,10V,10%,X7S,CH4102K6E00",0.1UF,10%,C0201,5934.89,15276.03,270.000,YES,,,
C404,"Q_CAP_C0805-100UF,4V,20%,X6S,CH710KMEA01",100UF,20%,C0805_H61,5494.59,15341.46,90.000,YES,,,
C405,"Q_CAP_C0805-100UF,4V,20%,X6S,CH710KMEA01",100UF,20%,C0805_H61,5592.41,15377.46,0.000,YES,,,
C406,"Q_CAP_0402-4.7UF,6.3V,20%,X6S,CH5471MEB01",4.7UF,20%,C0402,5882.64,15376.38,90.000,YES,,,
C407,"Q_CAP_0201-1UF,4V,20%,X6S,CH-10KMEE00",1UF,20%,C0201,5787.65,15227.03,90.000,YES,,,
C408,"Q_CAP_C0402-22UF,4V,20%,X6S,CH622KMEB02",22UF,20%,C0402_H32,6213.35,15376.38,90.000,YES,,,
C409,"Q_CAP_C0805-100UF,4V,20%,X6S,CH710KMEA01",100UF,20%,C0805_H61,5592.15,15308.92,0.000,YES,,,
C410,"Q_CAP_C0402-10UF,6.3V,20%,X6S,CH6101MEB01",10UF,20%,C0402,5788.14,15376.38,90.000,YES,,,
C411,"Q_CAP_C0201-0.1UF,10V,10%,X7S,CH4102K6E00",0.1UF,10%,C0201,5887.65,15276.03,270.000,YES,,,
C412,"Q_CAP_0402-4.7UF,6.3V,20%,X6S,CH5471MEB01",4.7UF,20%,C0402,6449.57,15376.38,90.000,YES,,,
C413,"Q_CAP_0402-4.7UF,6.3V,20%,X6S,CH5471MEB01",4.7UF,20%,C0402,5752.56,15407.12,270.000,YES,,,
C414,"Q_CAP_C0402-10UF,6.3V,20%,X6S,CH6101MEB01",10UF,20%,C0402,6071.61,15376.38,90.000,YES,,,
C415,"Q_CAP_0201-1UF,4V,20%,X6S,CH-10KMEE00",1UF,20%,C0201,5882.14,15227.03,90.000,YES,,,
C416,"Q_CAP_0402-4.7UF,6.3V,20%,X6S,CH5471MEB01",4.7UF,20%,C0402,6307.83,15376.38,90.000,YES,,,
C417,"Q_CAP_C0402-22UF,4V,20%,X6S,CH622KMEB02",22UF,20%,C0402_H32,5835.39,15376.38,90.000,YES,,,
C418,"Q_CAP_0201-1UF,4V,20%,X6S,CH-10KMEE00",1UF,20%,C0201,6543.76,15227.03,90.000,YES,,,
C419,"Q_CAP_0402-4.7UF,6.3V,20%,X6S,CH5471MEB01",4.7UF,20%,C0402,6024.37,15376.38,90.000,YES,,,
C420,"Q_CAP_C0402-10UF,6.3V,20%,X6S,CH6101MEB01",10UF,20%,C0402,6355.08,15376.38,90.000,YES,,,
C421,"Q_CAP_C0201-0.1UF,10V,10%,X7S,CH4102K6E00",0.1UF,10%,C0201,5793.16,15276.03,270.000,YES,,,
C422,"Q_CAP_0201-1UF,4V,20%,X6S,CH-10KMEE00",1UF,20%,C0201,6449.07,15227.03,90.000,YES,,,
C423,"Q_CAP_0201-1UF,4V,20%,X6S,CH-10KMEE00",1UF,20%,C0201,6260.59,15390.13,90.000,YES,,,
C424,"Q_CAP_C0402-22UF,4V,20%,X6S,CH622KMEB02",22UF,20%,C0402_H32,6402.32,15376.38,90.000,YES,,,
C425,"Q_CAP_0201-1UF,4V,20%,X6S,CH-10KMEE00",1UF,20%,C0201,5834.89,15227.03,90.000,YES,,,
C426,"Q_CAP_C0201-0.1UF,10V,10%,X7S,CH4102K6E00",0.1UF,10%,C0201,6499.60,15129.90,270.000,YES,,,
C427,"Q_CAP_C0201-0.1UF,10V,10%,X7S,CH4102K6E00",0.1UF,10%,C0201,6360.09,15276.03,270.000,YES,,,
C428,"Q_CAP_C0201-0.1UF,10V,10%,X7S,CH4102K6E00",0.1UF,10%,C0201,5840.40,15276.03,270.000,YES,,,
C429,"Q_CAP_C0402-10UF,6.3V,20%,X6S,CH6101MEB01",10UF,20%,C0402,5929.88,15376.38,90.000,YES,,,
C430,"Q_CAP_C0201-0.1UF,10V,10%,X7S,CH4102K6E00",0.1UF,10%,C0201,6454.58,15276.03,270.000,YES,,,
C431,"Q_CAP_C0402-10UF,6.3V,20%,X6S,CH6101MEB01",10UF,20%,C0402,6496.81,15376.38,90.000,YES,,,
C432,"Q_CAP_C0805-100UF,4V,20%,X6S,CH710KMEA01",100UF,20%,C0805_H61,5423.05,15239.53,270.000,YES,,,
C433,"Q_CAP_C0805-100UF,4V,20%,X6S,CH710KMEA01",100UF,20%,C0805_H61,5354.97,15239.53,270.000,YES,,,
C434,"Q_CAP_C0402-22UF,4V,20%,X6S,CH622KMEB02",22UF,20%,C0402_H32,5436.72,15214.20,90.000,NO,,,
C435,"Q_CAP_C0402-22UF,4V,20%,X6S,CH622KMEB02",22UF,20%,C0402_H32,5377.70,15214.20,90.000,NO,,,
C436,"Q_CAP_C0402-10UF,6.3V,20%,X6S,CH6101MEB01",10UF,20%,C0402,5518.44,15226.22,270.000,YES,,,
C437,"Q_CAP_C0402-10UF,6.3V,20%,X6S,CH6101MEB01",10UF,20%,C0402,4885.48,15376.38,90.000,YES,,,
C438,"Q_CAP_0402-4.7UF,6.3V,20%,X6S,CH5471MEB01",4.7UF,20%,C0402,4838.24,15376.38,90.000,YES,,,
C439,"Q_CAP_0402-4.7UF,6.3V,20%,X6S,CH5471MEB01",4.7UF,20%,C0402,5478.44,15226.22,270.000,YES,,,
C440,"Q_CAP_0201-1UF,4V,20%,X6S,CH-10KMEE00",1UF,20%,C0201,4796.00,15276.03,270.000,YES,,,
C441,"Q_CAP_0201-1UF,4V,20%,X6S,CH-10KMEE00",1UF,20%,C0201,4932.22,15227.03,90.000,YES,,,
C442,"Q_CAP_0201-1UF,4V,20%,X6S,CH-10KMEE00",1UF,20%,C0201,4843.25,15276.03,270.000,YES,,,
C443,"Q_CAP_C0201-0.1UF,10V,10%,X7S,CH4102K6E00",0.1UF,10%,C0201,4837.74,15227.03,90.000,YES,,,
C444,"Q_CAP_C0201-0.1UF,10V,10%,X7S,CH4102K6E00",0.1UF,10%,C0201,4937.73,15276.03,270.000,YES,,,
C445,"Q_CAP_C0201-0.1UF,10V,10%,X7S,CH4102K6E00",0.1UF,10%,C0201,4884.98,15227.03,90.000,YES,,,
C446,"Q_CAP_C0201-0.1UF,10V,10%,X7S,CH4102K6E00",0.1UF,10%,C0201,4790.49,15227.03,90.000,YES,,,
C447,"Q_CAP_C0201-0.1UF,10V,10%,X7S,CH4102K6E00",0.1UF,10%,C0201,4890.49,15276.03,270.000,YES,,,
C448,"Q_CAP_0201-1UF,4V,20%,X6S,CH-10KMEE00",1UF,20%,C0201,5215.69,15227.03,90.000,YES,,,
C449,"Q_CAP_C0201-0.1UF,10V,10%,X7S,CH4102K6E00",0.1UF,10%,C0201,4743.25,15227.03,90.000,YES,,,
C450,"Q_CAP_C0201-0.1UF,10V,10%,X7S,CH4102K6E00",0.1UF,10%,C0201,4607.03,15276.03,270.000,YES,,,
C451,"Q_CAP_C0201-0.1UF,10V,10%,X7S,CH4102K6E00",0.1UF,10%,C0201,4748.76,15276.03,270.000,YES,,,
C452,"Q_CAP_0201-1UF,4V,20%,X6S,CH-10KMEE00",1UF,20%,C0201,4601.52,15227.03,90.000,YES,,,
C453,"Q_CAP_0201-1UF,4V,20%,X6S,CH-10KMEE00",1UF,20%,C0201,5073.96,15227.03,90.000,YES,,,
C454,"Q_CAP_0201-1UF,4V,20%,X6S,CH-10KMEE00",1UF,20%,C0201,4979.97,15390.13,90.000,YES,,,
C455,"Q_CAP_0201-1UF,4V,20%,X6S,CH-10KMEE00",1UF,20%,C0201,4507.03,15227.03,90.000,YES,,,
C456,"Q_CAP_0201-1UF,4V,20%,X6S,CH-10KMEE00",1UF,20%,C0201,4696.00,15227.03,90.000,YES,,,
C457,"Q_CAP_C0201-0.1UF,10V,10%,X7S,CH4102K6E00",0.1UF,10%,C0201,4559.78,15276.03,270.000,YES,,,
C458,"Q_CAP_C0201-0.1UF,10V,10%,X7S,CH4102K6E00",0.1UF,10%,C0201,4984.98,15276.03,270.000,YES,,,
C459,"Q_CAP_0201-1UF,4V,20%,X6S,CH-10KMEE00",1UF,20%,C0201,4498.93,15177.20,270.000,YES,,,
C460,"Q_CAP_0201-1UF,4V,20%,X6S,CH-10KMEE00",1UF,20%,C0201,5026.71,15227.03,90.000,YES,,,
C461,"Q_CAP_0402-1000PF,50V,5%,X7R,TMP_QCH21006JB10",1000PF,5%,C0402,14475.27,5393.18,0.000,YES,,,
C462,"Q_CAP_C0201-0.1UF,10V,10%,X7S,CH4102K6E00",0.1UF,10%,C0201,5173.96,15276.03,270.000,YES,,,
C463,"Q_CAP_C0201-0.1UF,10V,10%,X7S,CH4102K6E00",0.1UF,10%,C0201,4701.51,15276.03,270.000,YES,,,
C464,"Q_CAP_C0201-0.1UF,10V,10%,X7S,CH4102K6E00",0.1UF,10%,C0201,5032.22,15276.03,270.000,YES,,,
C465,"Q_CAP_0402-1000PF,50V,5%,EMPTY,TMP_QCH21006JB10",NA,5%,C0402,14682.57,5649.77,0.000,YES,,,
C466,"Q_CAP_C0805-100UF,4V,20%,X6S,CH710KMEA01",100UF,20%,C0805_H61,5391.19,15357.21,180.000,YES,,,
C467,"Q_CAP_0402-1000PF,50V,5%,EMPTY,TMP_QCH21006JB10",NA,5%,C0402,14682.57,5489.77,0.000,YES,,,
C468,"Q_CAP_0402-1000PF,50V,5%,X7R,TMP_QCH21006JB10",1000PF,5%,C0402,14682.57,5529.77,0.000,YES,,,
C469,"Q_CAP_0402-4.7UF,6.3V,20%,X6S,CH5471MEB01",4.7UF,20%,C0402,4471.94,15407.12,270.000,YES,,,
C470,"Q_CAP_0201-1UF,4V,20%,X6S,CH-10KMEE00",1UF,20%,C0201,5168.45,15227.03,90.000,YES,,,
C471,"Q_CAP_C0805-100UF,4V,20%,X6S,CH710KMEA01",100UF,20%,C0805_H61,5391.19,15425.75,180.000,YES,,,
C472,"Q_CAP_0402-4.7UF,6.3V,20%,X6S,CH5471MEB01",4.7UF,20%,C0402,4602.02,15376.38,90.000,YES,,,
C473,"Q_CAP_C0201-0.1UF,10V,10%,X7S,CH4102K6E00",0.1UF,10%,C0201,5079.47,15276.03,270.000,YES,,,
C474,"Q_CAP_C0805-100UF,4V,20%,X6S,CH710KMEA01",100UF,20%,C0805_H61,4213.97,15341.46,90.000,YES,,,
C475,"Q_CAP_C0805-100UF,4V,20%,X6S,CH710KMEA01",100UF,20%,C0805_H61,4311.53,15308.92,0.000,YES,,,
C476,"Q_CAP_C0402-22UF,4V,20%,X6S,CH622KMEB02",22UF,20%,C0402_H32,4554.77,15376.38,90.000,YES,,,
C477,"Q_CAP_C0201-0.1UF,10V,10%,X7S,CH4102K6E00",0.1UF,10%,C0201,4654.27,15276.03,270.000,YES,,,
C478,"Q_CAP_C0402-22UF,4V,20%,X6S,CH622KMEB02",22UF,20%,C0402_H32,4932.73,15376.38,90.000,YES,,,
C479,"Q_CAP_C0805-100UF,4V,20%,X6S,CH710KMEA01",100UF,20%,C0805_H61,4311.79,15377.46,0.000,YES,,,
C480,"Q_CAP_C0402-10UF,6.3V,20%,X6S,CH6101MEB01",10UF,20%,C0402,4507.52,15376.38,90.000,YES,,,
C481,"Q_CAP_C0201-0.1UF,10V,10%,X7S,CH4102K6E00",0.1UF,10%,C0201,5295.96,15266.48,180.000,YES,,,
C482,"Q_CAP_C0402-10UF,6.3V,20%,X6S,CH6101MEB01",10UF,20%,C0402,5216.19,15376.38,90.000,YES,,,
C483,"Q_CAP_0402-4.7UF,6.3V,20%,X6S,CH5471MEB01",4.7UF,20%,C0402,5027.21,15376.38,90.000,YES,,,
C484,"Q_CAP_0402-4.7UF,6.3V,20%,X6S,CH5471MEB01",4.7UF,20%,C0402,4743.75,15376.38,90.000,YES,,,
C485,"Q_CAP_0201-1UF,4V,20%,X6S,CH-10KMEE00",1UF,20%,C0201,5263.14,15227.03,90.000,YES,,,
C486,"Q_CAP_C0402-22UF,4V,20%,X6S,CH622KMEB02",22UF,20%,C0402_H32,5269.50,15376.38,90.000,YES,,,
C487,"Q_CAP_C0402-22UF,4V,20%,X6S,CH622KMEB02",22UF,20%,C0402_H32,4696.51,15376.38,90.000,YES,,,
C488,"Q_CAP_0201-1UF,4V,20%,X6S,CH-10KMEE00",1UF,20%,C0201,4429.86,15238.20,0.000,YES,,,
C489,"Q_CAP_C0402-10UF,6.3V,20%,X6S,CH6101MEB01",10UF,20%,C0402,4790.99,15376.38,90.000,YES,,,
C490,"Q_CAP_C0402-10UF,6.3V,20%,X6S,CH6101MEB01",10UF,20%,C0402,4649.26,15376.38,90.000,YES,,,
C491,"Q_CAP_0201-1UF,4V,20%,X6S,CH-10KMEE00",1UF,20%,C0201,4554.27,15227.03,90.000,YES,,,
C492,"Q_CAP_0201-1UF,4V,20%,X6S,CH-10KMEE00",1UF,20%,C0201,5121.20,15227.03,90.000,YES,,,
C493,"Q_CAP_C0201-0.1UF,10V,10%,X7S,CH4102K6E00",0.1UF,10%,C0201,4979.47,15227.03,90.000,YES,,,
C494,"Q_CAP_0402-4.7UF,6.3V,20%,X6S,CH5471MEB01",4.7UF,20%,C0402,5168.95,15376.38,90.000,YES,,,
C495,"Q_CAP_C0201-0.1UF,10V,10%,X7S,CH4102K6E00",0.1UF,10%,C0201,5221.20,15276.03,270.000,YES,,,
C496,"Q_CAP_C0201-0.1UF,10V,10%,X7S,CH4102K6E00",0.1UF,10%,C0201,5126.71,15276.03,270.000,YES,,,
C497,"Q_CAP_0201-1UF,4V,20%,X6S,CH-10KMEE00",1UF,20%,C0201,4648.76,15227.03,90.000,YES,,,
C498,"Q_CAP_C0201-0.1UF,10V,10%,X7S,CH4102K6E00",0.1UF,10%,C0201,4429.97,15287.28,0.000,YES,,,
C499,"Q_CAP_C0402-10UF,6.3V,20%,X6S,CH6101MEB01",10UF,20%,C0402,5074.46,15376.38,90.000,YES,,,
C500,"Q_CAP_C0201-0.1UF,10V,10%,X7S,CH4102K6E00",0.1UF,10%,C0201,4512.54,15276.03,270.000,YES,,,
C501,"Q_CAP_C0402-22UF,4V,20%,X6S,CH622KMEB02",22UF,20%,C0402_H32,5121.70,15376.38,90.000,YES,,,
C502,"Q_CAP_C0805-100UF,4V,20%,X6S,CH710KMEA01",100UF,20%,C0805_H61,12860.05,15569.53,270.000,YES,,,
C503,"Q_CAP_C0805-100UF,4V,20%,X6S,CH710KMEA01",100UF,20%,C0805_H61,12791.97,15569.53,270.000,YES,,,
C504,"Q_CAP_C0402-22UF,4V,20%,X6S,CH622KMEB02",22UF,20%,C0402_H32,12873.72,15544.20,90.000,NO,,,
C505,"Q_CAP_C0402-22UF,4V,20%,X6S,CH622KMEB02",22UF,20%,C0402_H32,12814.70,15544.20,90.000,NO,,,
C506,"Q_CAP_C0402-10UF,6.3V,20%,X6S,CH6101MEB01",10UF,20%,C0402,12955.44,15556.22,270.000,YES,,,
C507,"Q_CAP_C0402-10UF,6.3V,20%,X6S,CH6101MEB01",10UF,20%,C0402,12322.48,15706.38,90.000,YES,,,
C508,"Q_CAP_0402-0.1UF,25V,10%,X7R,CH4104K1B00",0.1UF,10%,C0402,9254.68,2656.47,270.000,NO,,,
C509,"Q_CAP_C0805-10UF,25V,10%,X6S,CH6104KEA00",10UF,10%,C0805_H61,990.24,7585.05,180.000,YES,,,
C510,"Q_CAP_0402-4.7UF,6.3V,20%,X6S,CH5471MEB01",4.7UF,20%,C0402,12275.24,15706.38,90.000,YES,,,
C511,"Q_CAP_0402-4.7UF,6.3V,20%,X6S,CH5471MEB01",4.7UF,20%,C0402,12915.44,15556.22,270.000,YES,,,
C512,"Q_CAP_0201-1UF,4V,20%,X6S,CH-10KMEE00",1UF,20%,C0201,12233.00,15606.03,270.000,YES,,,
C513,"Q_CAP_0201-1UF,4V,20%,X6S,CH-10KMEE00",1UF,20%,C0201,12369.22,15557.03,90.000,YES,,,
C514,"Q_CAP_0201-1UF,4V,20%,X6S,CH-10KMEE00",1UF,20%,C0201,12280.25,15606.03,270.000,YES,,,
C515,"Q_CAP_C0201-0.1UF,10V,10%,X7S,CH4102K6E00",0.1UF,10%,C0201,12321.98,15557.03,90.000,YES,,,
C516,"Q_CAP_C0201-0.1UF,10V,10%,X7S,CH4102K6E00",0.1UF,10%,C0201,12374.73,15606.03,270.000,YES,,,
C517,"Q_CAP_C0201-0.1UF,10V,10%,X7S,CH4102K6E00",0.1UF,10%,C0201,12274.74,15557.03,90.000,YES,,,
C518,"Q_CAP_C0805-10UF,25V,10%,X6S,CH6104KEA00",10UF,10%,C0805_H61,693.23,7585.05,180.000,YES,,,
C519,"Q_CAP_C0201-0.1UF,10V,10%,X7S,CH4102K6E00",0.1UF,10%,C0201,12327.49,15606.03,270.000,YES,,,
C520,"Q_CAP_C0201-0.1UF,10V,10%,X7S,CH4102K6E00",0.1UF,10%,C0201,12227.49,15557.03,90.000,YES,,,
C521,"Q_CAP_0201-1UF,4V,20%,X6S,CH-10KMEE00",1UF,20%,C0201,11944.03,15557.03,90.000,YES,,,
C522,"Q_CAP_C0201-0.1UF,10V,10%,X7S,CH4102K6E00",0.1UF,10%,C0201,12185.76,15606.03,270.000,YES,,,
C523,"Q_CAP_C0201-0.1UF,10V,10%,X7S,CH4102K6E00",0.1UF,10%,C0201,11996.78,15606.03,270.000,YES,,,
C524,"Q_CAP_C0201-0.1UF,10V,10%,X7S,CH4102K6E00",0.1UF,10%,C0201,12421.98,15606.03,270.000,YES,,,
C525,"Q_CAP_0201-1UF,4V,20%,X6S,CH-10KMEE00",1UF,20%,C0201,12652.69,15557.03,90.000,YES,,,
C526,"Q_CAP_0201-1UF,4V,20%,X6S,CH-10KMEE00",1UF,20%,C0201,12038.52,15557.03,90.000,YES,,,
C527,"Q_CAP_C0805-10UF,25V,10%,X6S,CH6104KEA00",10UF,10%,C0805_H61,854.65,7585.05,0.000,YES,,,
C528,"Q_CAP_0201-1UF,4V,20%,X6S,CH-10KMEE00",1UF,20%,C0201,12416.97,15720.13,90.000,YES,,,
C529,"Q_CAP_0201-1UF,4V,20%,X6S,CH-10KMEE00",1UF,20%,C0201,12510.96,15557.03,90.000,YES,,,
C530,"Q_CAP_C0805-10UF,25V,10%,X6S,CH6104KEA00",10UF,10%,C0805_H61,6634.97,7585.05,0.000,YES,,,
C531,"Q_CAP_C0805-10UF,25V,10%,X6S,CH6104KEA00",10UF,10%,C0805_H61,6473.55,7585.05,180.000,YES,,,
C532,"Q_CAP_C0805-10UF,25V,10%,X6S,CH6104KEA00",10UF,10%,C0805_H61,6770.56,7585.05,180.000,YES,,,
C533,"Q_CAP_C0805-10UF,25V,10%,X6S,CH6104KEA00",10UF,10%,C0805_H61,6931.98,7585.05,0.000,YES,,,
C534,"Q_CAP_C0805-10UF,25V,10%,X6S,CH6104KEA00",10UF,10%,C0805_H61,7067.57,7585.05,180.000,YES,,,
C535,"Q_CAP_C0805-10UF,25V,10%,X6S,CH6104KEA00",10UF,10%,C0805_H61,7228.99,7585.05,0.000,YES,,,
C536,"Q_CAP_C0805-10UF,25V,10%,X6S,CH6104KEA00",10UF,10%,C0805_H61,7525.99,7585.05,0.000,YES,,,
C537,"Q_CAP_C0805-10UF,25V,10%,X6S,CH6104KEA00",10UF,10%,C0805_H61,7364.57,7585.05,180.000,YES,,,
C538,"Q_CAP_C0201-0.1UF,10V,10%,X7S,CH4102K6E00",0.1UF,10%,C0201,12138.51,15606.03,270.000,YES,,,
C539,"Q_CAP_0201-1UF,4V,20%,X6S,CH-10KMEE00",1UF,20%,C0201,11935.93,15507.20,270.000,YES,,,
C540,"Q_CAP_C0201-0.1UF,10V,10%,X7S,CH4102K6E00",0.1UF,10%,C0201,12180.25,15557.03,90.000,YES,,,
C541,"Q_CAP_C0201-0.1UF,10V,10%,X7S,CH4102K6E00",0.1UF,10%,C0201,12610.96,15606.03,270.000,YES,,,
C542,"Q_CAP_0201-1UF,4V,20%,X6S,CH-10KMEE00",1UF,20%,C0201,12133.00,15557.03,90.000,YES,,,
C543,"Q_CAP_C0201-0.1UF,10V,10%,X7S,CH4102K6E00",0.1UF,10%,C0201,12044.03,15606.03,270.000,YES,,,
C544,"Q_CAP_C0201-0.1UF,10V,10%,X7S,CH4102K6E00",0.1UF,10%,C0201,12469.22,15606.03,270.000,YES,,,
C545,"Q_CAP_0201-1UF,4V,20%,X6S,CH-10KMEE00",1UF,20%,C0201,12463.71,15557.03,90.000,YES,,,
C546,"Q_CAP_C0805-10UF,25V,10%,X6S,CH6104KEA00",10UF,10%,C0805_H61,7823.00,7585.05,0.000,YES,,,
C547,"Q_CAP_C0805-10UF,25V,10%,X6S,CH6104KEA00",10UF,10%,C0805_H61,7661.58,7585.05,180.000,YES,,,
C548,"Q_CAP_C0805-10UF,25V,10%,X6S,CH6104KEA00",10UF,10%,C0805_H61,8120.00,7585.04,0.000,YES,,,
C549,"Q_CAP_C0805-10UF,25V,10%,X6S,CH6104KEA00",10UF,10%,C0805_H61,7958.59,7585.04,180.000,YES,,,
C550,"Q_CAP_C0805-100UF,4V,20%,X6S,CH710KMEA01",100UF,20%,C0805_H61,12829.19,15755.75,180.000,YES,,,
C551,"Q_CAP_C0402-0.01UF,50V,10%,X7R,CH31006KB18",0.01UF,10%,C0402,15133.48,2580.38,270.000,NO,,,
C552,"Q_CAP_0402-0.1UF,25V,10%,X7R,CH4104K1B00",0.1UF,10%,C0402,6135.00,4400.00,0.000,NO,,,
C553,"Q_CAP_0402-0.1UF,25V,10%,X7R,CH4104K1B00",0.1UF,10%,C0402,12531.52,995.25,90.000,NO,,,
C554,"Q_CAP_0402-4.7UF,6.3V,20%,X6S,CH5471MEB01",4.7UF,20%,C0402,11908.94,15737.12,270.000,YES,,,
C555,"Q_CAP_0201-1UF,4V,20%,X6S,CH-10KMEE00",1UF,20%,C0201,11866.86,15568.20,0.000,YES,,,
C556,"Q_CAP_C0805-100UF,4V,20%,X6S,CH710KMEA01",100UF,20%,C0805_H61,11963.06,15989.52,0.000,NO,,,
C557,"Q_CAP_0402-4.7UF,6.3V,20%,X6S,CH5471MEB01",4.7UF,20%,C0402,12039.02,15706.38,90.000,YES,,,
C558,"Q_CAP_C0201-0.1UF,10V,10%,X7S,CH4102K6E00",0.1UF,10%,C0201,12091.27,15606.03,270.000,YES,,,
C559,"Q_CAP_C0805-100UF,4V,20%,X6S,CH710KMEA01",100UF,20%,C0805_H61,11989.11,16094.54,270.000,NO,,,
C560,"Q_CAP_C0805-100UF,4V,20%,X6S,CH710KMEA01",100UF,20%,C0805_H61,12829.19,15687.21,180.000,YES,,,
C561,"Q_CAP_C0402-10UF,6.3V,20%,X6S,CH6101MEB01",10UF,20%,C0402,11944.52,15706.38,90.000,YES,,,
C562,"Q_CAP_0201-1UF,4V,20%,X6S,CH-10KMEE00",1UF,20%,C0201,11991.27,15557.03,90.000,YES,,,
C563,"Q_CAP_C0402-22UF,4V,20%,X6S,CH622KMEB02",22UF,20%,C0402_H32,12369.73,15706.38,90.000,YES,,,
C564,"Q_CAP_C0805-100UF,4V,20%,X6S,CH710KMEA01",100UF,20%,C0805_H61,11963.32,15920.98,0.000,NO,,,
C565,"Q_CAP_C0402-22UF,4V,20%,X6S,CH622KMEB02",22UF,20%,C0402_H32,11991.77,15706.38,90.000,YES,,,
C566,"Q_CAP_C0201-0.1UF,10V,10%,X7S,CH4102K6E00",0.1UF,10%,C0201,12732.96,15596.48,180.000,YES,,,
C567,"Q_CAP_C0402-10UF,6.3V,20%,X6S,CH6101MEB01",10UF,20%,C0402,12653.19,15706.38,90.000,YES,,,
C568,"Q_CAP_C0402-22UF,4V,20%,X6S,CH622KMEB02",22UF,20%,C0402_H32,12133.51,15706.38,90.000,YES,,,
C569,"Q_CAP_0402-4.7UF,6.3V,20%,X6S,CH5471MEB01",4.7UF,20%,C0402,12180.75,15706.38,90.000,YES,,,
C570,"Q_CAP_0201-1UF,4V,20%,X6S,CH-10KMEE00",1UF,20%,C0201,12558.20,15557.03,90.000,YES,,,
C571,"Q_CAP_0402-4.7UF,6.3V,20%,X6S,CH5471MEB01",4.7UF,20%,C0402,12605.95,15706.38,90.000,YES,,,
C572,"Q_CAP_0402-4.7UF,6.3V,20%,X6S,CH5471MEB01",4.7UF,20%,C0402,12464.21,15706.38,90.000,YES,,,
C573,"Q_CAP_0201-1UF,4V,20%,X6S,CH-10KMEE00",1UF,20%,C0201,12605.45,15557.03,90.000,YES,,,
C574,"Q_CAP_C0402-10UF,6.3V,20%,X6S,CH6101MEB01",10UF,20%,C0402,12227.99,15706.38,90.000,YES,,,
C575,"Q_CAP_C0402-22UF,4V,20%,X6S,CH622KMEB02",22UF,20%,C0402_H32,12706.50,15706.38,90.000,YES,,,
C576,"Q_CAP_C0201-0.1UF,10V,10%,X7S,CH4102K6E00",0.1UF,10%,C0201,11854.32,15629.57,90.000,YES,,,
C577,"Q_CAP_0201-1UF,4V,20%,X6S,CH-10KMEE00",1UF,20%,C0201,12700.14,15557.03,90.000,YES,,,
C578,"Q_CAP_C0201-0.1UF,10V,10%,X7S,CH4102K6E00",0.1UF,10%,C0201,12416.47,15557.03,90.000,YES,,,
C579,"Q_CAP_C0402-10UF,6.3V,20%,X6S,CH6101MEB01",10UF,20%,C0402,12086.26,15706.38,90.000,YES,,,
C580,"Q_CAP_C0201-0.1UF,10V,10%,X7S,CH4102K6E00",0.1UF,10%,C0201,11949.54,15606.03,270.000,YES,,,
C581,"Q_CAP_0201-1UF,4V,20%,X6S,CH-10KMEE00",1UF,20%,C0201,12085.76,15557.03,90.000,YES,,,
C582,"Q_CAP_C0201-0.1UF,10V,10%,X7S,CH4102K6E00",0.1UF,10%,C0201,12563.71,15606.03,270.000,YES,,,
C583,"Q_CAP_C0201-0.1UF,10V,10%,X7S,CH4102K6E00",0.1UF,10%,C0201,12516.47,15606.03,270.000,YES,,,
C584,"Q_CAP_C0402-10UF,6.3V,20%,X6S,CH6101MEB01",10UF,20%,C0402,12511.46,15706.38,90.000,YES,,,
C585,"Q_CAP_C0201-0.1UF,10V,10%,X7S,CH4102K6E00",0.1UF,10%,C0201,12658.20,15606.03,270.000,YES,,,
C586,"Q_CAP_C0402-22UF,4V,20%,X6S,CH622KMEB02",22UF,20%,C0402_H32,12558.70,15706.38,90.000,YES,,,
C587,"Q_CAP_C0805-100UF,4V,20%,X6S,CH710KMEA01",100UF,20%,C0805_H61,14140.67,15569.53,270.000,YES,,,
C588,"Q_CAP_C0805-100UF,4V,20%,X6S,CH710KMEA01",100UF,20%,C0805_H61,14072.59,15569.53,270.000,YES,,,
C589,"Q_CAP_C0402-22UF,4V,20%,X6S,CH622KMEB02",22UF,20%,C0402_H32,14154.34,15544.20,90.000,NO,,,
C590,"Q_CAP_C0402-22UF,4V,20%,X6S,CH622KMEB02",22UF,20%,C0402_H32,14095.32,15544.20,90.000,NO,,,
C591,"Q_CAP_C0402-10UF,6.3V,20%,X6S,CH6101MEB01",10UF,20%,C0402,14196.06,15556.22,270.000,YES,,,
C592,"Q_CAP_0402-0.1UF,25V,10%,X7R,CH4104K1B00",0.1UF,10%,C0402,18172.99,4214.32,0.000,NO,,,
C593,"Q_CAP_0402-0.1UF,25V,10%,X7R,CH4104K1B00",0.1UF,10%,C0402,18177.99,4079.32,0.000,NO,,,
C594,"Q_CAP_0402-4.7UF,6.3V,20%,X6S,CH5471MEB01",4.7UF,20%,C0402,13555.86,15706.38,90.000,YES,,,
C595,"Q_CAP_C0402-10UF,6.3V,20%,X6S,CH6101MEB01",10UF,20%,C0402,13603.10,15706.38,90.000,YES,,,
C596,"Q_CAP_0402-4.7UF,6.3V,20%,X6S,CH5471MEB01",4.7UF,20%,C0402,14236.06,15556.22,270.000,YES,,,
C597,"Q_CAP_0201-1UF,4V,20%,X6S,CH-10KMEE00",1UF,20%,C0201,13513.62,15606.03,270.000,YES,,,
C598,"Q_CAP_0201-1UF,4V,20%,X6S,CH-10KMEE00",1UF,20%,C0201,13649.84,15557.03,90.000,YES,,,
C599,"Q_CAP_0201-1UF,4V,20%,X6S,CH-10KMEE00",1UF,20%,C0201,13560.87,15606.03,270.000,YES,,,
C600,"Q_CAP_C0201-0.1UF,10V,10%,X7S,CH4102K6E00",0.1UF,10%,C0201,13508.11,15557.03,90.000,YES,,,
C601,"Q_CAP_C0201-0.1UF,10V,10%,X7S,CH4102K6E00",0.1UF,10%,C0201,13655.35,15606.03,270.000,YES,,,
C602,"Q_CAP_C0201-0.1UF,10V,10%,X7S,CH4102K6E00",0.1UF,10%,C0201,13602.60,15557.03,90.000,YES,,,
C603,"Q_CAP_C0201-0.1UF,10V,10%,X7S,CH4102K6E00",0.1UF,10%,C0201,13555.36,15557.03,90.000,YES,,,
C604,"Q_CAP_C0402-0.001UF,50V,10%,X7R,CH30106KB19",0.001UF,10%,C0402,15253.19,2012.50,0.000,NO,,,
C605,"Q_CAP_C0402-0.001UF,50V,10%,X7R,CH30106KB19",0.001UF,10%,C0402,15136.44,2236.75,270.000,NO,,,
C606,"Q_CAP_C0201-0.1UF,10V,10%,X7S,CH4102K6E00",0.1UF,10%,C0201,13608.11,15606.03,270.000,YES,,,
C607,"Q_CAP_0201-1UF,4V,20%,X6S,CH-10KMEE00",1UF,20%,C0201,13366.38,15557.03,90.000,YES,,,
C608,"Q_CAP_C0201-0.1UF,10V,10%,X7S,CH4102K6E00",0.1UF,10%,C0201,13466.38,15606.03,270.000,YES,,,
C609,"Q_CAP_0201-1UF,4V,20%,X6S,CH-10KMEE00",1UF,20%,C0201,13933.31,15557.03,90.000,YES,,,
C610,"Q_CAP_C0201-0.1UF,10V,10%,X7S,CH4102K6E00",0.1UF,10%,C0201,13460.87,15557.03,90.000,YES,,,
C611,"Q_CAP_0402-0.1UF,25V,10%,X7R,CH4104K1B00",0.1UF,10%,C0402,9495.00,8750.00,270.000,YES,,,
C612,"Q_CAP_0402-0.1UF,25V,10%,X7R,CH4104K1B00",0.1UF,10%,C0402,9495.00,8820.00,90.000,YES,,,
C613,"Q_CAP_0201-1UF,4V,20%,X6S,CH-10KMEE00",1UF,20%,C0201,13838.82,15557.03,90.000,YES,,,
C614,"Q_CAP_C0201-0.1UF,10V,10%,X7S,CH4102K6E00",0.1UF,10%,C0201,13938.82,15606.03,270.000,YES,,,
C615,"Q_CAP_C0201-0.1UF,10V,10%,X7S,CH4102K6E00",0.1UF,10%,C0201,13702.60,15606.03,270.000,YES,,,
C616,"Q_CAP_C0201-0.1UF,10V,10%,X7S,CH4102K6E00",0.1UF,10%,C0201,13134.94,15629.57,90.000,YES,,,
C617,"Q_CAP_C0201-0.1UF,10V,10%,X7S,CH4102K6E00",0.1UF,10%,C0201,13419.13,15606.03,270.000,YES,,,
C618,"Q_CAP_0201-1UF,4V,20%,X6S,CH-10KMEE00",1UF,20%,C0201,13791.58,15557.03,90.000,YES,,,
C619,"Q_CAP_C0201-0.1UF,10V,10%,X7S,CH4102K6E00",0.1UF,10%,C0201,13697.09,15557.03,90.000,YES,,,
C620,"Q_CAP_0201-1UF,4V,20%,X6S,CH-10KMEE00",1UF,20%,C0201,13147.48,15568.20,0.000,YES,,,
C621,"Q_CAP_0201-1UF,4V,20%,X6S,CH-10KMEE00",1UF,20%,C0201,13413.62,15557.03,90.000,YES,,,
C622,"Q_CAP_0201-1UF,4V,20%,X6S,CH-10KMEE00",1UF,20%,C0201,13216.55,15507.20,270.000,YES,,,
C623,"Q_CAP_C0201-0.1UF,10V,10%,X7S,CH4102K6E00",0.1UF,10%,C0201,13749.84,15606.03,270.000,YES,,,
C624,"Q_CAP_0201-1UF,4V,20%,X6S,CH-10KMEE00",1UF,20%,C0201,13744.33,15557.03,90.000,YES,,,
C625,"Q_CAP_C0805-100UF,4V,20%,X6S,CH710KMEA01",100UF,20%,C0805_H61,14109.81,15755.75,180.000,YES,,,
C626,"Q_CAP_C0402-10UF,6.3V,20%,X6S,CH6101MEB01",10UF,20%,C0402,13366.88,15706.38,90.000,YES,,,
C627,"Q_CAP_C0201-0.1UF,10V,10%,X7S,CH4102K6E00",0.1UF,10%,C0201,13797.09,15606.03,270.000,YES,,,
C628,"Q_CAP_C0805-100UF,4V,20%,X6S,CH710KMEA01",100UF,20%,C0805_H61,14109.81,15687.21,180.000,YES,,,
C629,"Q_CAP_0402-0.1UF,25V,10%,X7R,CH4104K1B00",0.1UF,10%,C0402,12473.27,4681.52,0.000,NO,,,
C630,"Q_CAP_C0402-22UF,4V,20%,X6S,CH622KMEB02",22UF,20%,C0402_H32,13414.13,15706.38,90.000,YES,,,
C631,"Q_CAP_C0201-0.1UF,10V,10%,X7S,CH4102K6E00",0.1UF,10%,C0201,13891.58,15606.03,270.000,YES,,,
C632,"Q_CAP_C0805-100UF,4V,20%,X6S,CH710KMEA01",100UF,20%,C0805_H61,12931.59,15671.46,90.000,YES,,,
C633,"Q_CAP_C0805-100UF,4V,20%,X6S,CH710KMEA01",100UF,20%,C0805_H61,13029.41,15707.46,0.000,YES,,,
C634,"Q_CAP_C0402-22UF,4V,20%,X6S,CH622KMEB02",22UF,20%,C0402_H32,13272.39,15706.38,90.000,YES,,,
C635,"Q_CAP_C0201-0.1UF,10V,10%,X7S,CH4102K6E00",0.1UF,10%,C0201,13324.65,15606.03,270.000,YES,,,
C636,"Q_CAP_C0402-22UF,4V,20%,X6S,CH622KMEB02",22UF,20%,C0402_H32,13650.35,15706.38,90.000,YES,,,
C637,"Q_CAP_C0805-100UF,4V,20%,X6S,CH710KMEA01",100UF,20%,C0805_H61,13029.15,15638.92,0.000,YES,,,
C638,"Q_CAP_0402-4.7UF,6.3V,20%,X6S,CH5471MEB01",4.7UF,20%,C0402,13319.64,15706.38,90.000,YES,,,
C639,"Q_CAP_0402-0.1UF,25V,10%,X7R,CH4104K1B00",0.1UF,10%,C0402,18185.69,3955.52,0.000,NO,,,
C640,"Q_CAP_0402-0.1UF,25V,10%,X7R,CH4104K1B00",0.1UF,10%,C0402,7570.38,3157.60,270.000,YES,,,
C641,"Q_CAP_0402-0.1UF,25V,10%,X7R,CH4104K1B00",0.1UF,10%,C0402,8245.71,2880.63,180.000,YES,,,
C642,"Q_CAP_0402-1000PF,50V,5%,X7R,TMP_QCH21006JB10",1000PF,5%,C0402,6208.38,13789.64,180.000,NO,,,
C643,"Q_CAP_0201-1UF,4V,20%,X6S,CH-10KMEE00",1UF,20%,C0201,13886.07,15557.03,90.000,YES,,,
C644,"Q_CAP_0402-4.7UF,6.3V,20%,X6S,CH5471MEB01",4.7UF,20%,C0402,13744.83,15706.38,90.000,YES,,,
C645,"Q_CAP_C0402-10UF,6.3V,20%,X6S,CH6101MEB01",10UF,20%,C0402,13225.14,15706.38,90.000,YES,,,
C646,"Q_CAP_C0402-10UF,6.3V,20%,X6S,CH6101MEB01",10UF,20%,C0402,13508.61,15706.38,90.000,YES,,,
C647,"Q_CAP_0201-1UF,4V,20%,X6S,CH-10KMEE00",1UF,20%,C0201,13271.89,15557.03,90.000,YES,,,
C648,"Q_CAP_C0402-10UF,6.3V,20%,X6S,CH6101MEB01",10UF,20%,C0402,13792.08,15706.38,90.000,YES,,,
C649,"Q_CAP_0402-4.7UF,6.3V,20%,X6S,CH5471MEB01",4.7UF,20%,C0402,13189.56,15737.12,270.000,YES,,,
C650,"Q_CAP_C0201-0.1UF,10V,10%,X7S,CH4102K6E00",0.1UF,10%,C0201,13277.40,15606.03,270.000,YES,,,
C651,"Q_CAP_0402-4.7UF,6.3V,20%,X6S,CH5471MEB01",4.7UF,20%,C0402,13461.37,15706.38,90.000,YES,,,
C652,"Q_CAP_0402-4.7UF,6.3V,20%,X6S,CH5471MEB01",4.7UF,20%,C0402,13886.57,15706.38,90.000,YES,,,
C653,"Q_CAP_0201-1UF,4V,20%,X6S,CH-10KMEE00",1UF,20%,C0201,13980.76,15557.03,90.000,YES,,,
C654,"Q_CAP_0201-1UF,4V,20%,X6S,CH-10KMEE00",1UF,20%,C0201,13319.14,15557.03,90.000,YES,,,
C655,"Q_CAP_0201-1UF,4V,20%,X6S,CH-10KMEE00",1UF,20%,C0201,13697.59,15720.13,90.000,YES,,,
C656,"Q_CAP_C0402-22UF,4V,20%,X6S,CH622KMEB02",22UF,20%,C0402_H32,13839.32,15706.38,90.000,YES,,,
C657,"Q_CAP_C0201-0.1UF,10V,10%,X7S,CH4102K6E00",0.1UF,10%,C0201,13230.16,15606.03,270.000,YES,,,
C658,"Q_CAP_C0201-0.1UF,10V,10%,X7S,CH4102K6E00",0.1UF,10%,C0201,14013.58,15596.48,180.000,YES,,,
C659,"Q_CAP_C0201-0.1UF,10V,10%,X7S,CH4102K6E00",0.1UF,10%,C0201,13844.33,15606.03,270.000,YES,,,
C660,"Q_CAP_0201-1UF,4V,20%,X6S,CH-10KMEE00",1UF,20%,C0201,13224.65,15557.03,90.000,YES,,,
C661,"Q_CAP_C0402-10UF,6.3V,20%,X6S,CH6101MEB01",10UF,20%,C0402,13933.81,15706.38,90.000,YES,,,
C662,"Q_CAP_C0201-0.1UF,10V,10%,X7S,CH4102K6E00",0.1UF,10%,C0201,13371.89,15606.03,270.000,YES,,,
C663,"Q_CAP_C0402-22UF,4V,20%,X6S,CH622KMEB02",22UF,20%,C0402_H32,13987.12,15706.38,90.000,YES,,,
C664,"Q_CAP_C0201-0.1UF,10V,10%,X7S,CH4102K6E00",0.1UF,10%,C0201,11626.15,15922.13,270.000,NO,,,
C665,"Q_CAP_C0805-100UF,4V,20%,X6S,CH710KMEA01",100UF,20%,C0805_H61,16900.74,15508.00,90.000,NO,,,
C666,"Q_CAP_C0805-100UF,4V,20%,X6S,CH710KMEA01",100UF,20%,C0805_H61,16780.74,15542.00,0.000,NO,,,
C667,"Q_CAP_C0402-22UF,4V,20%,X6S,CH622KMEB02",22UF,20%,C0402_H32,16955.29,15467.68,270.000,NO,,,
C668,"Q_CAP_C0402-22UF,4V,20%,X6S,CH622KMEB02",22UF,20%,C0402_H32,16737.06,15620.00,90.000,NO,,,
C669,"Q_CAP_C0402-10UF,6.3V,20%,X6S,CH6101MEB01",10UF,20%,C0402,16896.51,15635.26,0.000,NO,,,
C670,"Q_CAP_0402-4.7UF,6.3V,20%,X6S,CH5471MEB01",4.7UF,20%,C0402,16197.60,15706.38,90.000,YES,,,
C671,"Q_CAP_C0402-10UF,6.3V,20%,X6S,CH6101MEB01",10UF,20%,C0402,16244.84,15706.38,90.000,YES,,,
C672,"Q_CAP_0402-4.7UF,6.3V,20%,X6S,CH5471MEB01",4.7UF,20%,C0402,16896.51,15595.26,0.000,NO,,,
C673,"Q_CAP_0201-1UF,4V,20%,X6S,CH-10KMEE00",1UF,20%,C0201,16202.61,15606.03,270.000,YES,,,
C674,"Q_CAP_0402-0.1UF,25V,10%,EMPTY,CH4104K1B00",NA,10%,C0402,12987.32,5416.34,180.000,NO,,,
C675,"Q_CAP_0402-0.1UF,25V,10%,EMPTY,CH4104K1B00",NA,10%,C0402,2927.05,5844.54,270.000,NO,,,
C676,"Q_CAP_0201-1UF,4V,20%,X6S,CH-10KMEE00",1UF,20%,C0201,16291.58,15557.03,90.000,YES,,,
C677,"Q_CAP_0201-1UF,4V,20%,X6S,CH-10KMEE00",1UF,20%,C0201,16155.36,15606.03,270.000,YES,,,
C678,"Q_CAP_DIFFBUS_C0201-DIFF BUS_0.22UF,6.3V,20%,X6S,SA",,,C0201_DIFF-BUS,610.57,633.84,90.000,NO,,,
C679,"Q_CAP_DIFFBUS_C0201-DIFF BUS_0.22UF,6.3V,20%,X6S,SA",,,C0201_DIFF-BUS,646.57,633.84,90.000,NO,,,
C680,"Q_CAP_DIFFBUS_C0201-DIFF BUS_0.22UF,6.3V,20%,X6S,SA",,,C0201_DIFF-BUS,720.57,693.84,90.000,NO,,,
C681,"Q_CAP_DIFFBUS_C0201-DIFF BUS_0.22UF,6.3V,20%,X6S,SA",,,C0201_DIFF-BUS,756.57,693.84,90.000,NO,,,
C682,"Q_CAP_DIFFBUS_C0201-DIFF BUS_0.22UF,6.3V,20%,X6S,SA",,,C0201_DIFF-BUS,830.57,633.84,90.000,NO,,,
C683,"Q_CAP_DIFFBUS_C0201-DIFF BUS_0.22UF,6.3V,20%,X6S,SA",,,C0201_DIFF-BUS,866.57,633.84,90.000,NO,,,
C684,"Q_CAP_DIFFBUS_C0201-DIFF BUS_0.22UF,6.3V,20%,X6S,SA",,,C0201_DIFF-BUS,940.57,693.84,90.000,NO,,,
C685,"Q_CAP_DIFFBUS_C0201-DIFF BUS_0.22UF,6.3V,20%,X6S,SA",,,C0201_DIFF-BUS,976.57,693.84,90.000,NO,,,
C686,"Q_CAP_DIFFBUS_C0201-DIFF BUS_0.22UF,6.3V,20%,X6S,SA",,,C0201_DIFF-BUS,1050.57,633.84,90.000,NO,,,
C687,"Q_CAP_DIFFBUS_C0201-DIFF BUS_0.22UF,6.3V,20%,X6S,SA",,,C0201_DIFF-BUS,1086.57,633.84,90.000,NO,,,
C688,"Q_CAP_DIFFBUS_C0201-DIFF BUS_0.22UF,6.3V,20%,X6S,SA",,,C0201_DIFF-BUS,1160.57,693.84,90.000,NO,,,
C689,"Q_CAP_DIFFBUS_C0201-DIFF BUS_0.22UF,6.3V,20%,X6S,SA",,,C0201_DIFF-BUS,1196.57,693.84,90.000,NO,,,
C690,"Q_CAP_DIFFBUS_C0201-DIFF BUS_0.22UF,6.3V,20%,X6S,SA",,,C0201_DIFF-BUS,1270.57,633.84,90.000,NO,,,
C691,"Q_CAP_DIFFBUS_C0201-DIFF BUS_0.22UF,6.3V,20%,X6S,SA",,,C0201_DIFF-BUS,1306.57,633.84,90.000,NO,,,
C692,"Q_CAP_DIFFBUS_C0201-DIFF BUS_0.22UF,6.3V,20%,X6S,SA",,,C0201_DIFF-BUS,1380.57,693.84,90.000,NO,,,
C693,"Q_CAP_0402-0.1UF,25V,10%,X7R,CH4104K1B00",0.1UF,10%,C0402,16849.42,2299.12,90.000,NO,,,
C694,"Q_CAP_DIFFBUS_C0201-DIFF BUS_0.22UF,6.3V,20%,X6S,SA",,,C0201_DIFF-BUS,1490.57,633.84,90.000,NO,,,
C695,"Q_CAP_DIFFBUS_C0201-DIFF BUS_0.22UF,6.3V,20%,X6S,SA",,,C0201_DIFF-BUS,1526.57,633.84,90.000,NO,,,
C696,"Q_CAP_DIFFBUS_C0201-DIFF BUS_0.22UF,6.3V,20%,X6S,SA",,,C0201_DIFF-BUS,1612.61,693.84,90.000,NO,,,
C697,"Q_CAP_DIFFBUS_C0201-DIFF BUS_0.22UF,6.3V,20%,X6S,SA",,,C0201_DIFF-BUS,1648.61,693.84,90.000,NO,,,
C698,"Q_CAP_DIFFBUS_C0201-DIFF BUS_0.22UF,6.3V,20%,X6S,SA",,,C0201_DIFF-BUS,1722.61,633.84,90.000,NO,,,
C699,"Q_CAP_DIFFBUS_C0201-DIFF BUS_0.22UF,6.3V,20%,X6S,SA",,,C0201_DIFF-BUS,1758.61,633.84,90.000,NO,,,
C700,"Q_CAP_DIFFBUS_C0201-DIFF BUS_0.22UF,6.3V,20%,X6S,SA",,,C0201_DIFF-BUS,1832.61,693.84,90.000,NO,,,
C701,"Q_CAP_DIFFBUS_C0201-DIFF BUS_0.22UF,6.3V,20%,X6S,SA",,,C0201_DIFF-BUS,1868.61,693.84,90.000,NO,,,
C702,"Q_CAP_DIFFBUS_C0201-DIFF BUS_0.22UF,6.3V,20%,X6S,SA",,,C0201_DIFF-BUS,1942.61,633.84,90.000,NO,,,
C703,"Q_CAP_DIFFBUS_C0201-DIFF BUS_0.22UF,6.3V,20%,X6S,SA",,,C0201_DIFF-BUS,1978.61,633.84,90.000,NO,,,
C704,"Q_CAP_DIFFBUS_C0201-DIFF BUS_0.22UF,6.3V,20%,X6S,SA",,,C0201_DIFF-BUS,2053.95,693.84,90.000,NO,,,
C705,"Q_CAP_DIFFBUS_C0201-DIFF BUS_0.22UF,6.3V,20%,X6S,SA",,,C0201_DIFF-BUS,2089.95,693.84,90.000,NO,,,
C706,"Q_CAP_DIFFBUS_C0201-DIFF BUS_0.22UF,6.3V,20%,X6S,SA",,,C0201_DIFF-BUS,2163.95,633.84,90.000,NO,,,
C707,"Q_CAP_DIFFBUS_C0201-DIFF BUS_0.22UF,6.3V,20%,X6S,SA",,,C0201_DIFF-BUS,2199.95,633.84,90.000,NO,,,
C708,"Q_CAP_DIFFBUS_C0201-DIFF BUS_0.22UF,6.3V,20%,X6S,SA",,,C0201_DIFF-BUS,2273.95,693.84,90.000,NO,,,
C709,"Q_CAP_DIFFBUS_C0201-DIFF BUS_0.22UF,6.3V,20%,X6S,SA",,,C0201_DIFF-BUS,2309.95,693.84,90.000,NO,,,
C710,"Q_CAP_DIFFBUS_C0201-DIFF BUS_0.22UF,6.3V,20%,X6S,SA",,,C0201_DIFF-BUS,4026.33,14975.82,0.000,NO,,,
C711,"Q_CAP_DIFFBUS_C0201-DIFF BUS_0.22UF,6.3V,20%,X6S,SA",,,C0201_DIFF-BUS,4026.33,14939.82,0.000,NO,,,
C712,"Q_CAP_DIFFBUS_C0201-DIFF BUS_0.22UF,6.3V,20%,X6S,SA",,,C0201_DIFF-BUS,4026.33,14805.82,0.000,NO,,,
C713,"Q_CAP_DIFFBUS_C0201-DIFF BUS_0.22UF,6.3V,20%,X6S,SA",,,C0201_DIFF-BUS,4026.33,14841.82,0.000,NO,,,
C714,"Q_CAP_DIFFBUS_C0201-DIFF BUS_0.22UF,6.3V,20%,X6S,SA",,,C0201_DIFF-BUS,4014.13,14589.45,270.000,NO,,,
C715,"Q_CAP_DIFFBUS_C0201-DIFF BUS_0.22UF,6.3V,20%,X6S,SA",,,C0201_DIFF-BUS,3978.13,14589.45,270.000,NO,,,
C716,"Q_CAP_DIFFBUS_C0201-DIFF BUS_0.22UF,6.3V,20%,X6S,SA",,,C0201_DIFF-BUS,3880.13,14589.45,270.000,NO,,,
C717,"Q_CAP_DIFFBUS_C0201-DIFF BUS_0.22UF,6.3V,20%,X6S,SA",,,C0201_DIFF-BUS,3844.13,14589.45,270.000,NO,,,
C718,"Q_CAP_DIFFBUS_C0201-DIFF BUS_0.22UF,6.3V,20%,X6S,SA",,,C0201_DIFF-BUS,3813.13,14686.45,270.000,NO,,,
C719,"Q_CAP_DIFFBUS_C0201-DIFF BUS_0.22UF,6.3V,20%,X6S,SA",,,C0201_DIFF-BUS,3777.13,14686.45,270.000,NO,,,
C720,"Q_CAP_DIFFBUS_C0201-DIFF BUS_0.22UF,6.3V,20%,X6S,SA",,,C0201_DIFF-BUS,3746.13,14783.45,270.000,NO,,,
C721,"Q_CAP_DIFFBUS_C0201-DIFF BUS_0.22UF,6.3V,20%,X6S,SA",,,C0201_DIFF-BUS,3710.13,14783.45,270.000,NO,,,
C722,"Q_CAP_DIFFBUS_C0201-DIFF BUS_0.22UF,6.3V,20%,X6S,SA",,,C0201_DIFF-BUS,3612.13,14589.45,270.000,NO,,,
C723,"Q_CAP_DIFFBUS_C0201-DIFF BUS_0.22UF,6.3V,20%,X6S,SA",,,C0201_DIFF-BUS,3576.13,14589.45,270.000,NO,,,
C724,"Q_CAP_DIFFBUS_C0201-DIFF BUS_0.22UF,6.3V,20%,X6S,SA",,,C0201_DIFF-BUS,3545.13,14686.45,270.000,NO,,,
C725,"Q_CAP_DIFFBUS_C0201-DIFF BUS_0.22UF,6.3V,20%,X6S,SA",,,C0201_DIFF-BUS,3509.13,14686.45,270.000,NO,,,
C726,"Q_CAP_DIFFBUS_C0201-DIFF BUS_0.22UF,6.3V,20%,X6S,SA",,,C0201_DIFF-BUS,3478.13,14783.45,270.000,NO,,,
C727,"Q_CAP_DIFFBUS_C0201-DIFF BUS_0.22UF,6.3V,20%,X6S,SA",,,C0201_DIFF-BUS,3442.13,14783.45,270.000,NO,,,
C728,"Q_CAP_DIFFBUS_C0201-DIFF BUS_0.22UF,6.3V,20%,X6S,SA",,,C0201_DIFF-BUS,3344.13,14589.45,270.000,NO,,,
C729,"Q_CAP_DIFFBUS_C0201-DIFF BUS_0.22UF,6.3V,20%,X6S,SA",,,C0201_DIFF-BUS,3308.13,14589.45,270.000,NO,,,
C730,"Q_CAP_DIFFBUS_C0201-DIFF BUS_0.22UF,6.3V,20%,X6S,SA",,,C0201_DIFF-BUS,3277.13,14686.45,270.000,NO,,,
C731,"Q_CAP_DIFFBUS_C0201-DIFF BUS_0.22UF,6.3V,20%,X6S,SA",,,C0201_DIFF-BUS,3241.13,14686.45,270.000,NO,,,
C732,"Q_CAP_DIFFBUS_C0201-DIFF BUS_0.22UF,6.3V,20%,X6S,SA",,,C0201_DIFF-BUS,3210.13,14783.45,270.000,NO,,,
C733,"Q_CAP_DIFFBUS_C0201-DIFF BUS_0.22UF,6.3V,20%,X6S,SA",,,C0201_DIFF-BUS,3174.13,14783.45,270.000,NO,,,
C734,"Q_CAP_DIFFBUS_C0201-DIFF BUS_0.22UF,6.3V,20%,X6S,SA",,,C0201_DIFF-BUS,3076.13,14589.45,270.000,NO,,,
C735,"Q_CAP_DIFFBUS_C0201-DIFF BUS_0.22UF,6.3V,20%,X6S,SA",,,C0201_DIFF-BUS,3040.13,14589.45,270.000,NO,,,
C736,"Q_CAP_DIFFBUS_C0201-DIFF BUS_0.22UF,6.3V,20%,X6S,SA",,,C0201_DIFF-BUS,3009.13,14686.45,270.000,NO,,,
C737,"Q_CAP_DIFFBUS_C0201-DIFF BUS_0.22UF,6.3V,20%,X6S,SA",,,C0201_DIFF-BUS,2973.13,14686.45,270.000,NO,,,
C738,"Q_CAP_DIFFBUS_C0201-DIFF BUS_0.22UF,6.3V,20%,X6S,SA",,,C0201_DIFF-BUS,2972.25,14836.90,180.000,NO,,,
C739,"Q_CAP_DIFFBUS_C0201-DIFF BUS_0.22UF,6.3V,20%,X6S,SA",,,C0201_DIFF-BUS,2972.25,14800.90,180.000,NO,,,
C740,"Q_CAP_DIFFBUS_C0201-DIFF BUS_0.22UF,6.3V,20%,X6S,SA",,,C0201_DIFF-BUS,2972.25,15018.90,180.000,NO,,,
C741,"Q_CAP_DIFFBUS_C0201-DIFF BUS_0.22UF,6.3V,20%,X6S,SA",,,C0201_DIFF-BUS,2972.25,15054.90,180.000,NO,,,
C742,"Q_CAP_DIFFBUS_C0201-DIFF BUS_0.22UF,6.3V,20%,X6S,SA",,,C0201_DIFF-BUS,6668.06,14975.82,0.000,NO,,,
C743,"Q_CAP_DIFFBUS_C0201-DIFF BUS_0.22UF,6.3V,20%,X6S,SA",,,C0201_DIFF-BUS,6668.06,14939.82,0.000,NO,,,
C744,"Q_CAP_DIFFBUS_C0201-DIFF BUS_0.22UF,6.3V,20%,X6S,SA",,,C0201_DIFF-BUS,6668.06,14841.82,0.000,NO,,,
C745,"Q_CAP_DIFFBUS_C0201-DIFF BUS_0.22UF,6.3V,20%,X6S,SA",,,C0201_DIFF-BUS,6668.06,14805.82,0.000,NO,,,
C746,"Q_CAP_DIFFBUS_C0201-DIFF BUS_0.22UF,6.3V,20%,X6S,SA",,,C0201_DIFF-BUS,6655.86,14589.45,270.000,NO,,,
C747,"Q_CAP_DIFFBUS_C0201-DIFF BUS_0.22UF,6.3V,20%,X6S,SA",,,C0201_DIFF-BUS,6619.86,14589.45,270.000,NO,,,
C748,"Q_CAP_DIFFBUS_C0201-DIFF BUS_0.22UF,6.3V,20%,X6S,SA",,,C0201_DIFF-BUS,6521.86,14589.45,270.000,NO,,,
C749,"Q_CAP_DIFFBUS_C0201-DIFF BUS_0.22UF,6.3V,20%,X6S,SA",,,C0201_DIFF-BUS,6485.86,14589.45,270.000,NO,,,
C750,"Q_CAP_DIFFBUS_C0201-DIFF BUS_0.22UF,6.3V,20%,X6S,SA",,,C0201_DIFF-BUS,6454.86,14686.45,270.000,NO,,,
C751,"Q_CAP_DIFFBUS_C0201-DIFF BUS_0.22UF,6.3V,20%,X6S,SA",,,C0201_DIFF-BUS,6418.86,14686.45,270.000,NO,,,
C752,"Q_CAP_DIFFBUS_C0201-DIFF BUS_0.22UF,6.3V,20%,X6S,SA",,,C0201_DIFF-BUS,6387.86,14783.45,270.000,NO,,,
C753,"Q_CAP_DIFFBUS_C0201-DIFF BUS_0.22UF,6.3V,20%,X6S,SA",,,C0201_DIFF-BUS,6351.86,14783.45,270.000,NO,,,
C754,"Q_CAP_DIFFBUS_C0201-DIFF BUS_0.22UF,6.3V,20%,X6S,SA",,,C0201_DIFF-BUS,6253.86,14589.45,270.000,NO,,,
C755,"Q_CAP_DIFFBUS_C0201-DIFF BUS_0.22UF,6.3V,20%,X6S,SA",,,C0201_DIFF-BUS,6217.86,14589.45,270.000,NO,,,
C756,"Q_CAP_DIFFBUS_C0201-DIFF BUS_0.22UF,6.3V,20%,X6S,SA",,,C0201_DIFF-BUS,6186.86,14686.45,270.000,NO,,,
C757,"Q_CAP_DIFFBUS_C0201-DIFF BUS_0.22UF,6.3V,20%,X6S,SA",,,C0201_DIFF-BUS,6150.86,14686.45,270.000,NO,,,
C758,"Q_CAP_DIFFBUS_C0201-DIFF BUS_0.22UF,6.3V,20%,X6S,SA",,,C0201_DIFF-BUS,6119.86,14783.45,270.000,NO,,,
C759,"Q_CAP_DIFFBUS_C0201-DIFF BUS_0.22UF,6.3V,20%,X6S,SA",,,C0201_DIFF-BUS,6083.86,14783.45,270.000,NO,,,
C760,"Q_CAP_DIFFBUS_C0201-DIFF BUS_0.22UF,6.3V,20%,X6S,SA",,,C0201_DIFF-BUS,5985.86,14589.45,270.000,NO,,,
C761,"Q_CAP_DIFFBUS_C0201-DIFF BUS_0.22UF,6.3V,20%,X6S,SA",,,C0201_DIFF-BUS,5949.86,14589.45,270.000,NO,,,
C762,"Q_CAP_DIFFBUS_C0201-DIFF BUS_0.22UF,6.3V,20%,X6S,SA",,,C0201_DIFF-BUS,5918.86,14686.45,270.000,NO,,,
C763,"Q_CAP_DIFFBUS_C0201-DIFF BUS_0.22UF,6.3V,20%,X6S,SA",,,C0201_DIFF-BUS,5882.86,14686.45,270.000,NO,,,
C764,"Q_CAP_DIFFBUS_C0201-DIFF BUS_0.22UF,6.3V,20%,X6S,SA",,,C0201_DIFF-BUS,5851.86,14783.45,270.000,NO,,,
C765,"Q_CAP_DIFFBUS_C0201-DIFF BUS_0.22UF,6.3V,20%,X6S,SA",,,C0201_DIFF-BUS,5815.86,14783.45,270.000,NO,,,
C766,"Q_CAP_DIFFBUS_C0201-DIFF BUS_0.22UF,6.3V,20%,X6S,SA",,,C0201_DIFF-BUS,5717.86,14589.45,270.000,NO,,,
C767,"Q_CAP_DIFFBUS_C0201-DIFF BUS_0.22UF,6.3V,20%,X6S,SA",,,C0201_DIFF-BUS,5681.86,14589.45,270.000,NO,,,
C768,"Q_CAP_DIFFBUS_C0201-DIFF BUS_0.22UF,6.3V,20%,X6S,SA",,,C0201_DIFF-BUS,5650.86,14686.45,270.000,NO,,,
C769,"Q_CAP_DIFFBUS_C0201-DIFF BUS_0.22UF,6.3V,20%,X6S,SA",,,C0201_DIFF-BUS,5614.86,14686.45,270.000,NO,,,
C770,"Q_CAP_DIFFBUS_C0201-DIFF BUS_0.22UF,6.3V,20%,X6S,SA",,,C0201_DIFF-BUS,5613.98,14836.90,180.000,NO,,,
C771,"Q_CAP_DIFFBUS_C0201-DIFF BUS_0.22UF,6.3V,20%,X6S,SA",,,C0201_DIFF-BUS,5613.98,14800.90,180.000,NO,,,
C772,"Q_CAP_DIFFBUS_C0201-DIFF BUS_0.22UF,6.3V,20%,X6S,SA",,,C0201_DIFF-BUS,5613.98,15018.90,180.000,NO,,,
C773,"Q_CAP_DIFFBUS_C0201-DIFF BUS_0.22UF,6.3V,20%,X6S,SA",,,C0201_DIFF-BUS,5613.98,15054.90,180.000,NO,,,
C774,"Q_CAP_C0201-0.1UF,10V,10%,X7S,CH4102K6E00",0.1UF,10%,C0201,16197.10,15557.03,90.000,YES,,,
C775,"Q_CAP_C0201-0.1UF,10V,10%,X7S,CH4102K6E00",0.1UF,10%,C0201,16297.09,15606.03,270.000,YES,,,
C776,"Q_CAP_C0201-0.1UF,10V,10%,X7S,CH4102K6E00",0.1UF,10%,C0201,16249.85,15606.03,270.000,YES,,,
C777,"Q_CAP_C0201-0.1UF,10V,10%,X7S,CH4102K6E00",0.1UF,10%,C0201,16244.34,15557.03,90.000,YES,,,
C778,"Q_CAP_C0201-0.1UF,10V,10%,X7S,CH4102K6E00",0.1UF,10%,C0201,16149.85,15557.03,90.000,YES,,,
C779,"Q_CAP_0201-1UF,4V,20%,X6S,CH-10KMEE00",1UF,20%,C0201,15858.29,15507.20,270.000,YES,,,
C780,"Q_CAP_C0201-0.1UF,10V,10%,X7S,CH4102K6E00",0.1UF,10%,C0201,16102.61,15557.03,90.000,YES,,,
C781,"Q_CAP_0201-1UF,4V,20%,X6S,CH-10KMEE00",1UF,20%,C0201,15789.22,15568.20,0.000,YES,,,
C782,"Q_CAP_C0201-0.1UF,10V,10%,X7S,CH4102K6E00",0.1UF,10%,C0201,16108.12,15606.03,270.000,YES,,,
C783,"Q_CAP_0201-1UF,4V,20%,X6S,CH-10KMEE00",1UF,20%,C0201,16008.12,15557.03,90.000,YES,,,
C784,"Q_CAP_C0201-0.1UF,10V,10%,X7S,CH4102K6E00",0.1UF,10%,C0201,15776.68,15629.57,90.000,YES,,,
C785,"Q_CAP_C0201-0.1UF,10V,10%,X7S,CH4102K6E00",0.1UF,10%,C0201,16344.34,15606.03,270.000,YES,,,
C786,"Q_CAP_0201-1UF,4V,20%,X6S,CH-10KMEE00",1UF,20%,C0201,16575.05,15557.03,90.000,YES,,,
C787,"Q_CAP_0201-1UF,4V,20%,X6S,CH-10KMEE00",1UF,20%,C0201,16055.36,15557.03,90.000,YES,,,
C788,"Q_CAP_0201-1UF,4V,20%,X6S,CH-10KMEE00",1UF,20%,C0201,16480.56,15557.03,90.000,YES,,,
C789,"Q_CAP_C0201-0.1UF,10V,10%,X7S,CH4102K6E00",0.1UF,10%,C0201,16338.83,15557.03,90.000,YES,,,
C790,"Q_CAP_C0201-0.1UF,10V,10%,X7S,CH4102K6E00",0.1UF,10%,C0201,16580.56,15606.03,270.000,YES,,,
C791,"Q_CAP_C0201-0.1UF,10V,10%,X7S,CH4102K6E00",0.1UF,10%,C0201,16060.87,15606.03,270.000,YES,,,
C792,"Q_CAP_0201-1UF,4V,20%,X6S,CH-10KMEE00",1UF,20%,C0201,16433.32,15557.03,90.000,YES,,,
C793,"Q_CAP_0201-1UF,4V,20%,X6S,CH-10KMEE00",1UF,20%,C0201,16386.07,15557.03,90.000,YES,,,
C794,"Q_CAP_C0201-0.1UF,10V,10%,X7S,CH4102K6E00",0.1UF,10%,C0201,16391.58,15606.03,270.000,YES,,,
C795,"Q_CAP_C0805-100UF,4V,20%,X6S,CH710KMEA01",100UF,20%,C0805_H61,16780.07,15765.99,0.000,NO,,,
C796,"Q_CAP_C0402-10UF,6.3V,20%,X6S,CH6101MEB01",10UF,20%,C0402,16008.62,15706.38,90.000,YES,,,
C797,"Q_CAP_0201-1UF,4V,20%,X6S,CH-10KMEE00",1UF,20%,C0201,15913.63,15557.03,90.000,YES,,,
C798,"Q_CAP_C0805-100UF,4V,20%,X6S,CH710KMEA01",100UF,20%,C0805_H61,16780.07,15697.45,0.000,NO,,,
C799,"Q_CAP_C0402-22UF,4V,20%,X6S,CH622KMEB02",22UF,20%,C0402_H32,16055.87,15706.38,90.000,YES,,,
C800,"Q_CAP_C0201-0.1UF,10V,10%,X7S,CH4102K6E00",0.1UF,10%,C0201,15919.14,15606.03,270.000,YES,,,
C801,"Q_CAP_C0805-100UF,4V,20%,X6S,CH710KMEA01",100UF,20%,C0805_H61,15573.33,15671.46,90.000,YES,,,
C802,"Q_CAP_C0805-100UF,4V,20%,X6S,CH710KMEA01",100UF,20%,C0805_H61,15670.89,15638.92,0.000,YES,,,
C803,"Q_CAP_C0402-10UF,6.3V,20%,X6S,CH6101MEB01",10UF,20%,C0402,15866.88,15706.38,90.000,YES,,,
C804,"Q_CAP_C0201-0.1UF,10V,10%,X7S,CH4102K6E00",0.1UF,10%,C0201,16486.07,15606.03,270.000,YES,,,
C805,"Q_CAP_C0402-22UF,4V,20%,X6S,CH622KMEB02",22UF,20%,C0402_H32,16292.09,15706.38,90.000,YES,,,
C806,"Q_CAP_DIFFBUS_C0201-DIFF BUS_0.22UF,6.3V,20%,X6S,SA",,,C0201_DIFF-BUS,2745.71,14975.82,0.000,NO,,,
C807,"Q_CAP_DIFFBUS_C0201-DIFF BUS_0.22UF,6.3V,20%,X6S,SA",,,C0201_DIFF-BUS,2745.71,14939.82,0.000,NO,,,
C808,"Q_CAP_DIFFBUS_C0201-DIFF BUS_0.22UF,6.3V,20%,X6S,SA",,,C0201_DIFF-BUS,2745.71,14841.82,0.000,NO,,,
C809,"Q_CAP_DIFFBUS_C0201-DIFF BUS_0.22UF,6.3V,20%,X6S,SA",,,C0201_DIFF-BUS,2745.71,14805.82,0.000,NO,,,
C810,"Q_CAP_DIFFBUS_C0201-DIFF BUS_0.22UF,6.3V,20%,X6S,SA",,,C0201_DIFF-BUS,2697.51,14589.45,270.000,NO,,,
C811,"Q_CAP_DIFFBUS_C0201-DIFF BUS_0.22UF,6.3V,20%,X6S,SA",,,C0201_DIFF-BUS,2733.51,14589.45,270.000,NO,,,
C812,"Q_CAP_DIFFBUS_C0201-DIFF BUS_0.22UF,6.3V,20%,X6S,SA",,,C0201_DIFF-BUS,2599.51,14589.45,270.000,NO,,,
C813,"Q_CAP_DIFFBUS_C0201-DIFF BUS_0.22UF,6.3V,20%,X6S,SA",,,C0201_DIFF-BUS,2563.51,14589.45,270.000,NO,,,
C814,"Q_CAP_DIFFBUS_C0201-DIFF BUS_0.22UF,6.3V,20%,X6S,SA",,,C0201_DIFF-BUS,2532.51,14686.45,270.000,NO,,,
C815,"Q_CAP_DIFFBUS_C0201-DIFF BUS_0.22UF,6.3V,20%,X6S,SA",,,C0201_DIFF-BUS,2496.51,14686.45,270.000,NO,,,
C816,"Q_CAP_DIFFBUS_C0201-DIFF BUS_0.22UF,6.3V,20%,X6S,SA",,,C0201_DIFF-BUS,2465.51,14783.45,270.000,NO,,,
C817,"Q_CAP_DIFFBUS_C0201-DIFF BUS_0.22UF,6.3V,20%,X6S,SA",,,C0201_DIFF-BUS,2429.51,14783.45,270.000,NO,,,
C818,"Q_CAP_DIFFBUS_C0201-DIFF BUS_0.22UF,6.3V,20%,X6S,SA",,,C0201_DIFF-BUS,2331.51,14589.45,270.000,NO,,,
C819,"Q_CAP_DIFFBUS_C0201-DIFF BUS_0.22UF,6.3V,20%,X6S,SA",,,C0201_DIFF-BUS,2295.51,14589.45,270.000,NO,,,
C820,"Q_CAP_DIFFBUS_C0201-DIFF BUS_0.22UF,6.3V,20%,X6S,SA",,,C0201_DIFF-BUS,2264.51,14686.45,270.000,NO,,,
C821,"Q_CAP_DIFFBUS_C0201-DIFF BUS_0.22UF,6.3V,20%,X6S,SA",,,C0201_DIFF-BUS,2228.51,14686.45,270.000,NO,,,
C822,"Q_CAP_DIFFBUS_C0201-DIFF BUS_0.22UF,6.3V,20%,X6S,SA",,,C0201_DIFF-BUS,2197.51,14783.45,270.000,NO,,,
C823,"Q_CAP_DIFFBUS_C0201-DIFF BUS_0.22UF,6.3V,20%,X6S,SA",,,C0201_DIFF-BUS,2161.51,14783.45,270.000,NO,,,
C824,"Q_CAP_DIFFBUS_C0201-DIFF BUS_0.22UF,6.3V,20%,X6S,SA",,,C0201_DIFF-BUS,2063.51,14589.45,270.000,NO,,,
C825,"Q_CAP_DIFFBUS_C0201-DIFF BUS_0.22UF,6.3V,20%,X6S,SA",,,C0201_DIFF-BUS,2027.51,14589.45,270.000,NO,,,
C826,"Q_CAP_DIFFBUS_C0201-DIFF BUS_0.22UF,6.3V,20%,X6S,SA",,,C0201_DIFF-BUS,1996.51,14686.45,270.000,NO,,,
C827,"Q_CAP_DIFFBUS_C0201-DIFF BUS_0.22UF,6.3V,20%,X6S,SA",,,C0201_DIFF-BUS,1960.51,14686.45,270.000,NO,,,
C828,"Q_CAP_DIFFBUS_C0201-DIFF BUS_0.22UF,6.3V,20%,X6S,SA",,,C0201_DIFF-BUS,1929.51,14783.45,270.000,NO,,,
C829,"Q_CAP_DIFFBUS_C0201-DIFF BUS_0.22UF,6.3V,20%,X6S,SA",,,C0201_DIFF-BUS,1893.51,14783.45,270.000,NO,,,
C830,"Q_CAP_DIFFBUS_C0201-DIFF BUS_0.22UF,6.3V,20%,X6S,SA",,,C0201_DIFF-BUS,1795.51,14589.45,270.000,NO,,,
C831,"Q_CAP_DIFFBUS_C0201-DIFF BUS_0.22UF,6.3V,20%,X6S,SA",,,C0201_DIFF-BUS,1759.51,14589.45,270.000,NO,,,
C832,"Q_CAP_DIFFBUS_C0201-DIFF BUS_0.22UF,6.3V,20%,X6S,SA",,,C0201_DIFF-BUS,1728.51,14686.45,270.000,NO,,,
C833,"Q_CAP_DIFFBUS_C0201-DIFF BUS_0.22UF,6.3V,20%,X6S,SA",,,C0201_DIFF-BUS,1692.51,14686.45,270.000,NO,,,
C834,"Q_CAP_DIFFBUS_C0201-DIFF BUS_0.22UF,6.3V,20%,X6S,SA",,,C0201_DIFF-BUS,1691.63,14836.90,180.000,NO,,,
C835,"Q_CAP_DIFFBUS_C0201-DIFF BUS_0.22UF,6.3V,20%,X6S,SA",,,C0201_DIFF-BUS,1691.63,14800.90,180.000,NO,,,
C836,"Q_CAP_DIFFBUS_C0201-DIFF BUS_0.22UF,6.3V,20%,X6S,SA",,,C0201_DIFF-BUS,1691.63,15018.90,180.000,NO,,,
C837,"Q_CAP_DIFFBUS_C0201-DIFF BUS_0.22UF,6.3V,20%,X6S,SA",,,C0201_DIFF-BUS,1691.63,15054.90,180.000,NO,,,
C838,"Q_CAP_DIFFBUS_C0201-DIFF BUS_0.22UF,6.3V,20%,X6S,SA",,,C0201_DIFF-BUS,16746.80,15305.82,0.000,NO,,,
C839,"Q_CAP_DIFFBUS_C0201-DIFF BUS_0.22UF,6.3V,20%,X6S,SA",,,C0201_DIFF-BUS,16746.80,15269.82,0.000,NO,,,
C840,"Q_CAP_DIFFBUS_C0201-DIFF BUS_0.22UF,6.3V,20%,X6S,SA",,,C0201_DIFF-BUS,16746.80,15171.82,0.000,NO,,,
C841,"Q_CAP_DIFFBUS_C0201-DIFF BUS_0.22UF,6.3V,20%,X6S,SA",,,C0201_DIFF-BUS,16746.80,15135.82,0.000,NO,,,
C842,"Q_CAP_DIFFBUS_C0201-DIFF BUS_0.22UF,6.3V,20%,X6S,SA",,,C0201_DIFF-BUS,16734.60,14919.45,270.000,NO,,,
C843,"Q_CAP_DIFFBUS_C0201-DIFF BUS_0.22UF,6.3V,20%,X6S,SA",,,C0201_DIFF-BUS,16698.60,14919.45,270.000,NO,,,
C844,"Q_CAP_DIFFBUS_C0201-DIFF BUS_0.22UF,6.3V,20%,X6S,SA",,,C0201_DIFF-BUS,16600.60,14919.45,270.000,NO,,,
C845,"Q_CAP_DIFFBUS_C0201-DIFF BUS_0.22UF,6.3V,20%,X6S,SA",,,C0201_DIFF-BUS,16564.60,14919.45,270.000,NO,,,
C846,"Q_CAP_DIFFBUS_C0201-DIFF BUS_0.22UF,6.3V,20%,X6S,SA",,,C0201_DIFF-BUS,16533.60,15016.45,270.000,NO,,,
C847,"Q_CAP_DIFFBUS_C0201-DIFF BUS_0.22UF,6.3V,20%,X6S,SA",,,C0201_DIFF-BUS,16497.60,15016.45,270.000,NO,,,
C848,"Q_CAP_DIFFBUS_C0201-DIFF BUS_0.22UF,6.3V,20%,X6S,SA",,,C0201_DIFF-BUS,16466.60,15113.45,270.000,NO,,,
C849,"Q_CAP_DIFFBUS_C0201-DIFF BUS_0.22UF,6.3V,20%,X6S,SA",,,C0201_DIFF-BUS,16430.60,15113.45,270.000,NO,,,
C850,"Q_CAP_DIFFBUS_C0201-DIFF BUS_0.22UF,6.3V,20%,X6S,SA",,,C0201_DIFF-BUS,16332.60,14919.45,270.000,NO,,,
C851,"Q_CAP_DIFFBUS_C0201-DIFF BUS_0.22UF,6.3V,20%,X6S,SA",,,C0201_DIFF-BUS,16296.60,14919.45,270.000,NO,,,
C852,"Q_CAP_DIFFBUS_C0201-DIFF BUS_0.22UF,6.3V,20%,X6S,SA",,,C0201_DIFF-BUS,16265.60,15016.45,270.000,NO,,,
C853,"Q_CAP_DIFFBUS_C0201-DIFF BUS_0.22UF,6.3V,20%,X6S,SA",,,C0201_DIFF-BUS,16229.60,15016.45,270.000,NO,,,
C854,"Q_CAP_DIFFBUS_C0201-DIFF BUS_0.22UF,6.3V,20%,X6S,SA",,,C0201_DIFF-BUS,16198.60,15113.45,270.000,NO,,,
C855,"Q_CAP_DIFFBUS_C0201-DIFF BUS_0.22UF,6.3V,20%,X6S,SA",,,C0201_DIFF-BUS,16162.60,15113.45,270.000,NO,,,
C856,"Q_CAP_DIFFBUS_C0201-DIFF BUS_0.22UF,6.3V,20%,X6S,SA",,,C0201_DIFF-BUS,16064.60,14919.45,270.000,NO,,,
C857,"Q_CAP_DIFFBUS_C0201-DIFF BUS_0.22UF,6.3V,20%,X6S,SA",,,C0201_DIFF-BUS,16028.60,14919.45,270.000,NO,,,
C858,"Q_CAP_DIFFBUS_C0201-DIFF BUS_0.22UF,6.3V,20%,X6S,SA",,,C0201_DIFF-BUS,15997.60,15016.45,270.000,NO,,,
C859,"Q_CAP_DIFFBUS_C0201-DIFF BUS_0.22UF,6.3V,20%,X6S,SA",,,C0201_DIFF-BUS,15961.60,15016.45,270.000,NO,,,
C860,"Q_CAP_DIFFBUS_C0201-DIFF BUS_0.22UF,6.3V,20%,X6S,SA",,,C0201_DIFF-BUS,15930.60,15113.45,270.000,NO,,,
C861,"Q_CAP_DIFFBUS_C0201-DIFF BUS_0.22UF,6.3V,20%,X6S,SA",,,C0201_DIFF-BUS,15894.60,15113.45,270.000,NO,,,
C862,"Q_CAP_DIFFBUS_C0201-DIFF BUS_0.22UF,6.3V,20%,X6S,SA",,,C0201_DIFF-BUS,15796.60,14919.45,270.000,NO,,,
C863,"Q_CAP_DIFFBUS_C0201-DIFF BUS_0.22UF,6.3V,20%,X6S,SA",,,C0201_DIFF-BUS,15760.60,14919.45,270.000,NO,,,
C864,"Q_CAP_DIFFBUS_C0201-DIFF BUS_0.22UF,6.3V,20%,X6S,SA",,,C0201_DIFF-BUS,15729.60,15016.45,270.000,NO,,,
C865,"Q_CAP_DIFFBUS_C0201-DIFF BUS_0.22UF,6.3V,20%,X6S,SA",,,C0201_DIFF-BUS,15693.60,15016.45,270.000,NO,,,
C866,"Q_CAP_DIFFBUS_C0201-DIFF BUS_0.22UF,6.3V,20%,X6S,SA",,,C0201_DIFF-BUS,15692.72,15166.90,180.000,NO,,,
C867,"Q_CAP_DIFFBUS_C0201-DIFF BUS_0.22UF,6.3V,20%,X6S,SA",,,C0201_DIFF-BUS,15692.72,15130.90,180.000,NO,,,
C868,"Q_CAP_DIFFBUS_C0201-DIFF BUS_0.22UF,6.3V,20%,X6S,SA",,,C0201_DIFF-BUS,15692.72,15348.90,180.000,NO,,,
C869,"Q_CAP_DIFFBUS_C0201-DIFF BUS_0.22UF,6.3V,20%,X6S,SA",,,C0201_DIFF-BUS,15692.72,15384.90,180.000,NO,,,
C870,"Q_CAP_DIFFBUS_C0201-DIFF BUS_0.22UF,6.3V,20%,X6S,SA",,,C0201_DIFF-BUS,15466.18,15305.82,0.000,NO,,,
C871,"Q_CAP_DIFFBUS_C0201-DIFF BUS_0.22UF,6.3V,20%,X6S,SA",,,C0201_DIFF-BUS,15466.18,15269.82,0.000,NO,,,
C872,"Q_CAP_DIFFBUS_C0201-DIFF BUS_0.22UF,6.3V,20%,X6S,SA",,,C0201_DIFF-BUS,15466.18,15135.82,0.000,NO,,,
C873,"Q_CAP_DIFFBUS_C0201-DIFF BUS_0.22UF,6.3V,20%,X6S,SA",,,C0201_DIFF-BUS,15466.18,15171.82,0.000,NO,,,
C874,"Q_CAP_DIFFBUS_C0201-DIFF BUS_0.22UF,6.3V,20%,X6S,SA",,,C0201_DIFF-BUS,15453.98,14919.45,270.000,NO,,,
C875,"Q_CAP_DIFFBUS_C0201-DIFF BUS_0.22UF,6.3V,20%,X6S,SA",,,C0201_DIFF-BUS,15417.98,14919.45,270.000,NO,,,
C876,"Q_CAP_DIFFBUS_C0201-DIFF BUS_0.22UF,6.3V,20%,X6S,SA",,,C0201_DIFF-BUS,15319.98,14919.45,270.000,NO,,,
C877,"Q_CAP_DIFFBUS_C0201-DIFF BUS_0.22UF,6.3V,20%,X6S,SA",,,C0201_DIFF-BUS,15283.98,14919.45,270.000,NO,,,
C878,"Q_CAP_DIFFBUS_C0201-DIFF BUS_0.22UF,6.3V,20%,X6S,SA",,,C0201_DIFF-BUS,15252.98,15016.45,270.000,NO,,,
C879,"Q_CAP_DIFFBUS_C0201-DIFF BUS_0.22UF,6.3V,20%,X6S,SA",,,C0201_DIFF-BUS,15216.98,15016.45,270.000,NO,,,
C880,"Q_CAP_DIFFBUS_C0201-DIFF BUS_0.22UF,6.3V,20%,X6S,SA",,,C0201_DIFF-BUS,15185.98,15113.45,270.000,NO,,,
C881,"Q_CAP_DIFFBUS_C0201-DIFF BUS_0.22UF,6.3V,20%,X6S,SA",,,C0201_DIFF-BUS,15149.98,15113.45,270.000,NO,,,
C882,"Q_CAP_DIFFBUS_C0201-DIFF BUS_0.22UF,6.3V,20%,X6S,SA",,,C0201_DIFF-BUS,15051.98,14919.45,270.000,NO,,,
C883,"Q_CAP_DIFFBUS_C0201-DIFF BUS_0.22UF,6.3V,20%,X6S,SA",,,C0201_DIFF-BUS,15015.98,14919.45,270.000,NO,,,
C884,"Q_CAP_DIFFBUS_C0201-DIFF BUS_0.22UF,6.3V,20%,X6S,SA",,,C0201_DIFF-BUS,14984.98,15016.45,270.000,NO,,,
C885,"Q_CAP_DIFFBUS_C0201-DIFF BUS_0.22UF,6.3V,20%,X6S,SA",,,C0201_DIFF-BUS,14948.98,15016.45,270.000,NO,,,
C886,"Q_CAP_DIFFBUS_C0201-DIFF BUS_0.22UF,6.3V,20%,X6S,SA",,,C0201_DIFF-BUS,14917.98,15113.45,270.000,NO,,,
C887,"Q_CAP_DIFFBUS_C0201-DIFF BUS_0.22UF,6.3V,20%,X6S,SA",,,C0201_DIFF-BUS,14881.98,15113.45,270.000,NO,,,
C888,"Q_CAP_DIFFBUS_C0201-DIFF BUS_0.22UF,6.3V,20%,X6S,SA",,,C0201_DIFF-BUS,14783.98,14919.45,270.000,NO,,,
C889,"Q_CAP_DIFFBUS_C0201-DIFF BUS_0.22UF,6.3V,20%,X6S,SA",,,C0201_DIFF-BUS,14747.98,14919.45,270.000,NO,,,
C890,"Q_CAP_DIFFBUS_C0201-DIFF BUS_0.22UF,6.3V,20%,X6S,SA",,,C0201_DIFF-BUS,14716.98,15016.45,270.000,NO,,,
C891,"Q_CAP_DIFFBUS_C0201-DIFF BUS_0.22UF,6.3V,20%,X6S,SA",,,C0201_DIFF-BUS,14680.98,15016.45,270.000,NO,,,
C892,"Q_CAP_DIFFBUS_C0201-DIFF BUS_0.22UF,6.3V,20%,X6S,SA",,,C0201_DIFF-BUS,14649.98,15113.45,270.000,NO,,,
C893,"Q_CAP_DIFFBUS_C0201-DIFF BUS_0.22UF,6.3V,20%,X6S,SA",,,C0201_DIFF-BUS,14613.98,15113.45,270.000,NO,,,
C894,"Q_CAP_DIFFBUS_C0201-DIFF BUS_0.22UF,6.3V,20%,X6S,SA",,,C0201_DIFF-BUS,14515.98,14919.45,270.000,NO,,,
C895,"Q_CAP_DIFFBUS_C0201-DIFF BUS_0.22UF,6.3V,20%,X6S,SA",,,C0201_DIFF-BUS,14479.98,14919.45,270.000,NO,,,
C896,"Q_CAP_DIFFBUS_C0201-DIFF BUS_0.22UF,6.3V,20%,X6S,SA",,,C0201_DIFF-BUS,14448.98,15016.45,270.000,NO,,,
C897,"Q_CAP_DIFFBUS_C0201-DIFF BUS_0.22UF,6.3V,20%,X6S,SA",,,C0201_DIFF-BUS,14412.98,15016.45,270.000,NO,,,
C898,"Q_CAP_DIFFBUS_C0201-DIFF BUS_0.22UF,6.3V,20%,X6S,SA",,,C0201_DIFF-BUS,14412.10,15166.90,180.000,NO,,,
C899,"Q_CAP_DIFFBUS_C0201-DIFF BUS_0.22UF,6.3V,20%,X6S,SA",,,C0201_DIFF-BUS,14412.10,15130.90,180.000,NO,,,
C900,"Q_CAP_DIFFBUS_C0201-DIFF BUS_0.22UF,6.3V,20%,X6S,SA",,,C0201_DIFF-BUS,14412.10,15348.90,180.000,NO,,,
C901,"Q_CAP_DIFFBUS_C0201-DIFF BUS_0.22UF,6.3V,20%,X6S,SA",,,C0201_DIFF-BUS,14412.10,15384.90,180.000,NO,,,
C902,"Q_CAP_DIFFBUS_C0201-DIFF BUS_0.22UF,6.3V,20%,X6S,SA",,,C0201_DIFF-BUS,12824.44,15305.82,0.000,NO,,,
C903,"Q_CAP_DIFFBUS_C0201-DIFF BUS_0.22UF,6.3V,20%,X6S,SA",,,C0201_DIFF-BUS,12824.44,15269.82,0.000,NO,,,
C904,"Q_CAP_DIFFBUS_C0201-DIFF BUS_0.22UF,6.3V,20%,X6S,SA",,,C0201_DIFF-BUS,12824.44,15171.82,0.000,NO,,,
C905,"Q_CAP_DIFFBUS_C0201-DIFF BUS_0.22UF,6.3V,20%,X6S,SA",,,C0201_DIFF-BUS,12824.44,15135.82,0.000,NO,,,
C906,"Q_CAP_DIFFBUS_C0201-DIFF BUS_0.22UF,6.3V,20%,X6S,SA",,,C0201_DIFF-BUS,12776.24,14919.45,270.000,NO,,,
C907,"Q_CAP_DIFFBUS_C0201-DIFF BUS_0.22UF,6.3V,20%,X6S,SA",,,C0201_DIFF-BUS,12812.24,14919.45,270.000,NO,,,
C908,"Q_CAP_DIFFBUS_C0201-DIFF BUS_0.22UF,6.3V,20%,X6S,SA",,,C0201_DIFF-BUS,12678.24,14919.45,270.000,NO,,,
C909,"Q_CAP_DIFFBUS_C0201-DIFF BUS_0.22UF,6.3V,20%,X6S,SA",,,C0201_DIFF-BUS,12642.24,14919.45,270.000,NO,,,
C910,"Q_CAP_DIFFBUS_C0201-DIFF BUS_0.22UF,6.3V,20%,X6S,SA",,,C0201_DIFF-BUS,12611.24,15016.45,270.000,NO,,,
C911,"Q_CAP_DIFFBUS_C0201-DIFF BUS_0.22UF,6.3V,20%,X6S,SA",,,C0201_DIFF-BUS,12575.24,15016.45,270.000,NO,,,
C912,"Q_CAP_DIFFBUS_C0201-DIFF BUS_0.22UF,6.3V,20%,X6S,SA",,,C0201_DIFF-BUS,12544.24,15113.45,270.000,NO,,,
C913,"Q_CAP_DIFFBUS_C0201-DIFF BUS_0.22UF,6.3V,20%,X6S,SA",,,C0201_DIFF-BUS,12508.24,15113.45,270.000,NO,,,
C914,"Q_CAP_DIFFBUS_C0201-DIFF BUS_0.22UF,6.3V,20%,X6S,SA",,,C0201_DIFF-BUS,12410.24,14919.45,270.000,NO,,,
C915,"Q_CAP_DIFFBUS_C0201-DIFF BUS_0.22UF,6.3V,20%,X6S,SA",,,C0201_DIFF-BUS,12374.24,14919.45,270.000,NO,,,
C916,"Q_CAP_DIFFBUS_C0201-DIFF BUS_0.22UF,6.3V,20%,X6S,SA",,,C0201_DIFF-BUS,12343.24,15016.45,270.000,NO,,,
C917,"Q_CAP_DIFFBUS_C0201-DIFF BUS_0.22UF,6.3V,20%,X6S,SA",,,C0201_DIFF-BUS,12307.24,15016.45,270.000,NO,,,
C918,"Q_CAP_DIFFBUS_C0201-DIFF BUS_0.22UF,6.3V,20%,X6S,SA",,,C0201_DIFF-BUS,12276.24,15113.45,270.000,NO,,,
C919,"Q_CAP_DIFFBUS_C0201-DIFF BUS_0.22UF,6.3V,20%,X6S,SA",,,C0201_DIFF-BUS,12240.24,15113.45,270.000,NO,,,
C920,"Q_CAP_DIFFBUS_C0201-DIFF BUS_0.22UF,6.3V,20%,X6S,SA",,,C0201_DIFF-BUS,12142.24,14919.45,270.000,NO,,,
C921,"Q_CAP_DIFFBUS_C0201-DIFF BUS_0.22UF,6.3V,20%,X6S,SA",,,C0201_DIFF-BUS,12106.24,14919.45,270.000,NO,,,
C922,"Q_CAP_DIFFBUS_C0201-DIFF BUS_0.22UF,6.3V,20%,X6S,SA",,,C0201_DIFF-BUS,12075.24,15016.45,270.000,NO,,,
C923,"Q_CAP_DIFFBUS_C0201-DIFF BUS_0.22UF,6.3V,20%,X6S,SA",,,C0201_DIFF-BUS,12039.24,15016.45,270.000,NO,,,
C924,"Q_CAP_DIFFBUS_C0201-DIFF BUS_0.22UF,6.3V,20%,X6S,SA",,,C0201_DIFF-BUS,12008.24,15113.45,270.000,NO,,,
C925,"Q_CAP_DIFFBUS_C0201-DIFF BUS_0.22UF,6.3V,20%,X6S,SA",,,C0201_DIFF-BUS,11972.24,15113.45,270.000,NO,,,
C926,"Q_CAP_DIFFBUS_C0201-DIFF BUS_0.22UF,6.3V,20%,X6S,SA",,,C0201_DIFF-BUS,11874.24,14919.45,270.000,NO,,,
C927,"Q_CAP_DIFFBUS_C0201-DIFF BUS_0.22UF,6.3V,20%,X6S,SA",,,C0201_DIFF-BUS,11838.24,14919.45,270.000,NO,,,
C928,"Q_CAP_DIFFBUS_C0201-DIFF BUS_0.22UF,6.3V,20%,X6S,SA",,,C0201_DIFF-BUS,11807.24,15016.45,270.000,NO,,,
C929,"Q_CAP_DIFFBUS_C0201-DIFF BUS_0.22UF,6.3V,20%,X6S,SA",,,C0201_DIFF-BUS,11771.24,15016.45,270.000,NO,,,
C930,"Q_CAP_DIFFBUS_C0201-DIFF BUS_0.22UF,6.3V,20%,X6S,SA",,,C0201_DIFF-BUS,11770.36,15166.90,180.000,NO,,,
C931,"Q_CAP_DIFFBUS_C0201-DIFF BUS_0.22UF,6.3V,20%,X6S,SA",,,C0201_DIFF-BUS,11770.36,15130.90,180.000,NO,,,
C932,"Q_CAP_DIFFBUS_C0201-DIFF BUS_0.22UF,6.3V,20%,X6S,SA",,,C0201_DIFF-BUS,11770.36,15348.90,180.000,NO,,,
C933,"Q_CAP_DIFFBUS_C0201-DIFF BUS_0.22UF,6.3V,20%,X6S,SA",,,C0201_DIFF-BUS,11770.36,15384.90,180.000,NO,,,
C934,"Q_CAP_DIFFBUS_C0201-DIFF BUS_0.22UF,6.3V,20%,X6S,SA",,,C0201_DIFF-BUS,14105.06,15305.82,0.000,NO,,,
C935,"Q_CAP_DIFFBUS_C0201-DIFF BUS_0.22UF,6.3V,20%,X6S,SA",,,C0201_DIFF-BUS,14105.06,15269.82,0.000,NO,,,
C936,"Q_CAP_DIFFBUS_C0201-DIFF BUS_0.22UF,6.3V,20%,X6S,SA",,,C0201_DIFF-BUS,14105.06,15135.82,0.000,NO,,,
C937,"Q_CAP_DIFFBUS_C0201-DIFF BUS_0.22UF,6.3V,20%,X6S,SA",,,C0201_DIFF-BUS,14105.06,15171.82,0.000,NO,,,
C938,"Q_CAP_DIFFBUS_C0201-DIFF BUS_0.22UF,6.3V,20%,X6S,SA",,,C0201_DIFF-BUS,14092.86,14919.45,270.000,NO,,,
C939,"Q_CAP_DIFFBUS_C0201-DIFF BUS_0.22UF,6.3V,20%,X6S,SA",,,C0201_DIFF-BUS,14056.86,14919.45,270.000,NO,,,
C940,"Q_CAP_DIFFBUS_C0201-DIFF BUS_0.22UF,6.3V,20%,X6S,SA",,,C0201_DIFF-BUS,13958.86,14919.45,270.000,NO,,,
C941,"Q_CAP_DIFFBUS_C0201-DIFF BUS_0.22UF,6.3V,20%,X6S,SA",,,C0201_DIFF-BUS,13922.86,14919.45,270.000,NO,,,
C942,"Q_CAP_DIFFBUS_C0201-DIFF BUS_0.22UF,6.3V,20%,X6S,SA",,,C0201_DIFF-BUS,13891.86,15016.45,270.000,NO,,,
C943,"Q_CAP_DIFFBUS_C0201-DIFF BUS_0.22UF,6.3V,20%,X6S,SA",,,C0201_DIFF-BUS,13855.86,15016.45,270.000,NO,,,
C944,"Q_CAP_DIFFBUS_C0201-DIFF BUS_0.22UF,6.3V,20%,X6S,SA",,,C0201_DIFF-BUS,13824.86,15113.45,270.000,NO,,,
C945,"Q_CAP_DIFFBUS_C0201-DIFF BUS_0.22UF,6.3V,20%,X6S,SA",,,C0201_DIFF-BUS,13788.86,15113.45,270.000,NO,,,
C946,"Q_CAP_DIFFBUS_C0201-DIFF BUS_0.22UF,6.3V,20%,X6S,SA",,,C0201_DIFF-BUS,13690.86,14919.45,270.000,NO,,,
C947,"Q_CAP_DIFFBUS_C0201-DIFF BUS_0.22UF,6.3V,20%,X6S,SA",,,C0201_DIFF-BUS,13654.86,14919.45,270.000,NO,,,
C948,"Q_CAP_DIFFBUS_C0201-DIFF BUS_0.22UF,6.3V,20%,X6S,SA",,,C0201_DIFF-BUS,13623.86,15016.45,270.000,NO,,,
C949,"Q_CAP_DIFFBUS_C0201-DIFF BUS_0.22UF,6.3V,20%,X6S,SA",,,C0201_DIFF-BUS,13587.86,15016.45,270.000,NO,,,
C950,"Q_CAP_DIFFBUS_C0201-DIFF BUS_0.22UF,6.3V,20%,X6S,SA",,,C0201_DIFF-BUS,13556.86,15113.45,270.000,NO,,,
C951,"Q_CAP_DIFFBUS_C0201-DIFF BUS_0.22UF,6.3V,20%,X6S,SA",,,C0201_DIFF-BUS,13520.86,15113.45,270.000,NO,,,
C952,"Q_CAP_DIFFBUS_C0201-DIFF BUS_0.22UF,6.3V,20%,X6S,SA",,,C0201_DIFF-BUS,13422.86,14919.45,270.000,NO,,,
C953,"Q_CAP_DIFFBUS_C0201-DIFF BUS_0.22UF,6.3V,20%,X6S,SA",,,C0201_DIFF-BUS,13386.86,14919.45,270.000,NO,,,
C954,"Q_CAP_DIFFBUS_C0201-DIFF BUS_0.22UF,6.3V,20%,X6S,SA",,,C0201_DIFF-BUS,13355.86,15016.45,270.000,NO,,,
C955,"Q_CAP_DIFFBUS_C0201-DIFF BUS_0.22UF,6.3V,20%,X6S,SA",,,C0201_DIFF-BUS,13319.86,15016.45,270.000,NO,,,
C956,"Q_CAP_DIFFBUS_C0201-DIFF BUS_0.22UF,6.3V,20%,X6S,SA",,,C0201_DIFF-BUS,13288.86,15113.45,270.000,NO,,,
C957,"Q_CAP_DIFFBUS_C0201-DIFF BUS_0.22UF,6.3V,20%,X6S,SA",,,C0201_DIFF-BUS,13252.86,15113.45,270.000,NO,,,
C958,"Q_CAP_DIFFBUS_C0201-DIFF BUS_0.22UF,6.3V,20%,X6S,SA",,,C0201_DIFF-BUS,13154.86,14919.45,270.000,NO,,,
C959,"Q_CAP_DIFFBUS_C0201-DIFF BUS_0.22UF,6.3V,20%,X6S,SA",,,C0201_DIFF-BUS,13118.86,14919.45,270.000,NO,,,
C960,"Q_CAP_DIFFBUS_C0201-DIFF BUS_0.22UF,6.3V,20%,X6S,SA",,,C0201_DIFF-BUS,13087.86,15016.45,270.000,NO,,,
C961,"Q_CAP_DIFFBUS_C0201-DIFF BUS_0.22UF,6.3V,20%,X6S,SA",,,C0201_DIFF-BUS,13051.86,15016.45,270.000,NO,,,
C962,"Q_CAP_DIFFBUS_C0201-DIFF BUS_0.22UF,6.3V,20%,X6S,SA",,,C0201_DIFF-BUS,13050.98,15166.90,180.000,NO,,,
C963,"Q_CAP_DIFFBUS_C0201-DIFF BUS_0.22UF,6.3V,20%,X6S,SA",,,C0201_DIFF-BUS,13050.98,15130.90,180.000,NO,,,
C964,"Q_CAP_DIFFBUS_C0201-DIFF BUS_0.22UF,6.3V,20%,X6S,SA",,,C0201_DIFF-BUS,13050.98,15348.90,180.000,NO,,,
C965,"Q_CAP_DIFFBUS_C0201-DIFF BUS_0.22UF,6.3V,20%,X6S,SA",,,C0201_DIFF-BUS,13050.98,15384.90,180.000,NO,,,
C966,"Q_CAP_C0805-100UF,4V,20%,X6S,CH710KMEA01",100UF,20%,C0805_H61,15671.15,15707.46,0.000,YES,,,
C967,"Q_CAP_0402-4.7UF,6.3V,20%,X6S,CH5471MEB01",4.7UF,20%,C0402,15961.38,15706.38,90.000,YES,,,
C968,"Q_CAP_C0201-0.1UF,10V,10%,X7S,CH4102K6E00",0.1UF,10%,C0201,15871.90,15606.03,270.000,YES,,,
C969,"Q_CAP_C0402-22UF,4V,20%,X6S,CH622KMEB02",22UF,20%,C0402_H32,16481.06,15706.38,90.000,YES,,,
C970,"Q_CAP_0402-4.7UF,6.3V,20%,X6S,CH5471MEB01",4.7UF,20%,C0402,15831.30,15737.12,270.000,YES,,,
C971,"Q_CAP_C0402-10UF,6.3V,20%,X6S,CH6101MEB01",10UF,20%,C0402,16150.35,15706.38,90.000,YES,,,
C972,"Q_CAP_C0201-0.1UF,10V,10%,X7S,CH4102K6E00",0.1UF,10%,C0201,15966.39,15606.03,270.000,YES,,,
C973,"Q_CAP_C0402-10UF,6.3V,20%,X6S,CH6101MEB01",10UF,20%,C0402,16433.82,15706.38,90.000,YES,,,
C974,"Q_CAP_C0402-22UF,4V,20%,X6S,CH622KMEB02",22UF,20%,C0402_H32,15914.13,15706.38,90.000,YES,,,
C975,"Q_CAP_0201-1UF,4V,20%,X6S,CH-10KMEE00",1UF,20%,C0201,16527.81,15557.03,90.000,YES,,,
C976,"Q_CAP_0402-4.7UF,6.3V,20%,X6S,CH5471MEB01",4.7UF,20%,C0402,16103.11,15706.38,90.000,YES,,,
C977,"Q_CAP_0402-4.7UF,6.3V,20%,X6S,CH5471MEB01",4.7UF,20%,C0402,16528.31,15706.38,90.000,YES,,,
C978,"Q_CAP_0201-1UF,4V,20%,X6S,CH-10KMEE00",1UF,20%,C0201,15960.88,15557.03,90.000,YES,,,
C979,"Q_CAP_0201-1UF,4V,20%,X6S,CH-10KMEE00",1UF,20%,C0201,16622.50,15557.03,90.000,YES,,,
C980,"Q_CAP_0201-1UF,4V,20%,X6S,CH-10KMEE00",1UF,20%,C0201,16339.33,15720.13,90.000,YES,,,
C981,"Q_CAP_0402-4.7UF,6.3V,20%,X6S,CH5471MEB01",4.7UF,20%,C0402,16386.57,15706.38,90.000,YES,,,
C982,"Q_CAP_C0201-0.1UF,10V,10%,X7S,CH4102K6E00",0.1UF,10%,C0201,16438.83,15606.03,270.000,YES,,,
C983,"Q_CAP_0201-1UF,4V,20%,X6S,CH-10KMEE00",1UF,20%,C0201,15866.39,15557.03,90.000,YES,,,
C984,"Q_CAP_C0201-0.1UF,10V,10%,X7S,CH4102K6E00",0.1UF,10%,C0201,16533.32,15606.03,270.000,YES,,,
C985,"Q_CAP_C0201-0.1UF,10V,10%,X7S,CH4102K6E00",0.1UF,10%,C0201,16013.63,15606.03,270.000,YES,,,
C986,"Q_CAP_C0402-10UF,6.3V,20%,X6S,CH6101MEB01",10UF,20%,C0402,16575.55,15706.38,90.000,YES,,,
C987,"Q_CAP_C0201-0.1UF,10V,10%,X7S,CH4102K6E00",0.1UF,10%,C0201,16578.36,15460.03,270.000,YES,,,
C988,"Q_CAP_C0402-22UF,4V,20%,X6S,CH622KMEB02",22UF,20%,C0402_H32,16628.86,15706.38,90.000,YES,,,
C989,"Q_CAP_C0201-0.1UF,10V,10%,X7S,CH4102K6E00",0.1UF,10%,C0201,16672.18,16701.49,0.000,NO,,,
C990,"Q_CAP_C0805-100UF,4V,20%,X6S,CH710KMEA01",100UF,20%,C0805_H61,15501.79,15569.53,270.000,YES,,,
C991,"Q_CAP_C0805-100UF,4V,20%,X6S,CH710KMEA01",100UF,20%,C0805_H61,15433.71,15569.53,270.000,YES,,,
C992,"Q_CAP_C0402-22UF,4V,20%,X6S,CH622KMEB02",22UF,20%,C0402_H32,15515.46,15544.20,90.000,NO,,,
C993,"Q_CAP_C0402-22UF,4V,20%,X6S,CH622KMEB02",22UF,20%,C0402_H32,15456.44,15544.20,90.000,NO,,,
C994,"Q_CAP_C0402-10UF,6.3V,20%,X6S,CH6101MEB01",10UF,20%,C0402,15597.18,15556.22,270.000,YES,,,
C995,"Q_CAP_C0402-10UF,6.3V,20%,X6S,CH6101MEB01",10UF,20%,C0402,14964.22,15706.38,90.000,YES,,,
C996,"Q_CAP_0402-4.7UF,6.3V,20%,X6S,CH5471MEB01",4.7UF,20%,C0402,14916.98,15706.38,90.000,YES,,,
C997,"Q_CAP_0402-4.7UF,6.3V,20%,X6S,CH5471MEB01",4.7UF,20%,C0402,15557.18,15556.22,270.000,YES,,,
C998,"Q_CAP_0201-1UF,4V,20%,X6S,CH-10KMEE00",1UF,20%,C0201,14921.99,15606.03,270.000,YES,,,
C999,"Q_CAP_0201-1UF,4V,20%,X6S,CH-10KMEE00",1UF,20%,C0201,15010.96,15557.03,90.000,YES,,,
C1000,"Q_CAP_0201-1UF,4V,20%,X6S,CH-10KMEE00",1UF,20%,C0201,14874.74,15606.03,270.000,YES,,,
C1001,"Q_CAP_C0201-0.1UF,10V,10%,X7S,CH4102K6E00",0.1UF,10%,C0201,14869.23,15557.03,90.000,YES,,,
C1002,"Q_CAP_C0201-0.1UF,10V,10%,X7S,CH4102K6E00",0.1UF,10%,C0201,15016.47,15606.03,270.000,YES,,,
C1003,"Q_CAP_C0201-0.1UF,10V,10%,X7S,CH4102K6E00",0.1UF,10%,C0201,14963.72,15557.03,90.000,YES,,,
C1004,"Q_CAP_C0201-0.1UF,10V,10%,X7S,CH4102K6E00",0.1UF,10%,C0201,14916.48,15557.03,90.000,YES,,,
C1005,"Q_CAP_C0201-0.1UF,10V,10%,X7S,CH4102K6E00",0.1UF,10%,C0201,14969.23,15606.03,270.000,YES,,,
C1006,"Q_CAP_0201-1UF,4V,20%,X6S,CH-10KMEE00",1UF,20%,C0201,14577.67,15507.20,270.000,YES,,,
C1007,"Q_CAP_C0201-0.1UF,10V,10%,X7S,CH4102K6E00",0.1UF,10%,C0201,14821.99,15557.03,90.000,YES,,,
C1008,"Q_CAP_C0201-0.1UF,10V,10%,X7S,CH4102K6E00",0.1UF,10%,C0201,14638.52,15606.03,270.000,YES,,,
C1009,"Q_CAP_C0201-0.1UF,10V,10%,X7S,CH4102K6E00",0.1UF,10%,C0201,14827.50,15606.03,270.000,YES,,,
C1010,"Q_CAP_C0201-0.1UF,10V,10%,X7S,CH4102K6E00",0.1UF,10%,C0201,15252.70,15606.03,270.000,YES,,,
C1011,"Q_CAP_C0201-0.1UF,10V,10%,X7S,CH4102K6E00",0.1UF,10%,C0201,14685.77,15606.03,270.000,YES,,,
C1012,"Q_CAP_C0201-0.1UF,10V,10%,X7S,CH4102K6E00",0.1UF,10%,C0201,15063.72,15606.03,270.000,YES,,,
C1013,"Q_CAP_0201-1UF,4V,20%,X6S,CH-10KMEE00",1UF,20%,C0201,14680.26,15557.03,90.000,YES,,,
C1014,"Q_CAP_C0201-0.1UF,10V,10%,X7S,CH4102K6E00",0.1UF,10%,C0201,15110.96,15606.03,270.000,YES,,,
C1015,"Q_CAP_0201-1UF,4V,20%,X6S,CH-10KMEE00",1UF,20%,C0201,15152.70,15557.03,90.000,YES,,,
C1016,"Q_CAP_0201-1UF,4V,20%,X6S,CH-10KMEE00",1UF,20%,C0201,15058.71,15720.13,90.000,YES,,,
C1017,"Q_CAP_0201-1UF,4V,20%,X6S,CH-10KMEE00",1UF,20%,C0201,14585.77,15557.03,90.000,YES,,,
C1018,"Q_CAP_0201-1UF,4V,20%,X6S,CH-10KMEE00",1UF,20%,C0201,15105.45,15557.03,90.000,YES,,,
C1019,"Q_CAP_0201-1UF,4V,20%,X6S,CH-10KMEE00",1UF,20%,C0201,15294.43,15557.03,90.000,YES,,,
C1020,"Q_CAP_0201-1UF,4V,20%,X6S,CH-10KMEE00",1UF,20%,C0201,14774.74,15557.03,90.000,YES,,,
C1021,"Q_CAP_C0201-0.1UF,10V,10%,X7S,CH4102K6E00",0.1UF,10%,C0201,14780.25,15606.03,270.000,YES,,,
C1022,"Q_CAP_C0805-100UF,4V,20%,X6S,CH710KMEA01",100UF,20%,C0805_H61,15470.93,15687.21,180.000,YES,,,
C1023,"Q_CAP_C0402-10UF,6.3V,20%,X6S,CH6101MEB01",10UF,20%,C0402,15153.20,15706.38,90.000,YES,,,
C1024,"Q_CAP_0201-1UF,4V,20%,X6S,CH-10KMEE00",1UF,20%,C0201,14727.50,15557.03,90.000,YES,,,
C1025,"Q_CAP_C0805-100UF,4V,20%,X6S,CH710KMEA01",100UF,20%,C0805_H61,15470.93,15755.75,180.000,YES,,,
C1026,"Q_CAP_C0402-22UF,4V,20%,X6S,CH622KMEB02",22UF,20%,C0402_H32,15200.44,15706.38,90.000,YES,,,
C1027,"Q_CAP_0201-1UF,4V,20%,X6S,CH-10KMEE00",1UF,20%,C0201,15247.19,15557.03,90.000,YES,,,
C1028,"Q_CAP_C0805-100UF,4V,20%,X6S,CH710KMEA01",100UF,20%,C0805_H61,14292.71,15671.46,90.000,YES,,,
C1029,"Q_CAP_C0805-100UF,4V,20%,X6S,CH710KMEA01",100UF,20%,C0805_H61,14390.53,15707.46,0.000,YES,,,
C1030,"Q_CAP_C0402-22UF,4V,20%,X6S,CH622KMEB02",22UF,20%,C0402_H32,14633.51,15706.38,90.000,YES,,,
C1031,"Q_CAP_0201-1UF,4V,20%,X6S,CH-10KMEE00",1UF,20%,C0201,14633.01,15557.03,90.000,YES,,,
C1032,"Q_CAP_C0402-22UF,4V,20%,X6S,CH622KMEB02",22UF,20%,C0402_H32,15011.47,15706.38,90.000,YES,,,
C1033,"Q_CAP_C0805-100UF,4V,20%,X6S,CH710KMEA01",100UF,20%,C0805_H61,14390.27,15638.92,0.000,YES,,,
C1034,"Q_CAP_0402-4.7UF,6.3V,20%,X6S,CH5471MEB01",4.7UF,20%,C0402,15105.95,15706.38,90.000,YES,,,
C1035,"Q_CAP_C0201-0.1UF,10V,10%,X7S,CH4102K6E00",0.1UF,10%,C0201,14733.01,15606.03,270.000,YES,,,
C1036,"Q_CAP_C0402-10UF,6.3V,20%,X6S,CH6101MEB01",10UF,20%,C0402,15294.93,15706.38,90.000,YES,,,
C1037,"Q_CAP_C0402-10UF,6.3V,20%,X6S,CH6101MEB01",10UF,20%,C0402,14586.26,15706.38,90.000,YES,,,
C1038,"Q_CAP_0402-4.7UF,6.3V,20%,X6S,CH5471MEB01",4.7UF,20%,C0402,14822.49,15706.38,90.000,YES,,,
C1039,"Q_CAP_0201-1UF,4V,20%,X6S,CH-10KMEE00",1UF,20%,C0201,15199.94,15557.03,90.000,YES,,,
C1040,"Q_CAP_C0402-22UF,4V,20%,X6S,CH622KMEB02",22UF,20%,C0402_H32,15348.24,15706.38,90.000,YES,,,
C1041,"Q_CAP_C0402-22UF,4V,20%,X6S,CH622KMEB02",22UF,20%,C0402_H32,14775.25,15706.38,90.000,YES,,,
C1042,"Q_CAP_C0402-100NF,50V,10%,X7R,CH4106K1B01",100NF,10%,C0402,15840.79,5631.08,270.000,NO,,,
C1043,"Q_CAP_C0201-0.1UF,10V,10%,X7S,CH4102K6E00",0.1UF,10%,C0201,15299.94,15606.03,270.000,YES,,,
C1044,"Q_CAP_C0402-10UF,6.3V,20%,X6S,CH6101MEB01",10UF,20%,C0402,14869.73,15706.38,90.000,YES,,,
C1045,"Q_CAP_0402-4.7UF,6.3V,20%,X6S,CH5471MEB01",4.7UF,20%,C0402,15247.69,15706.38,90.000,YES,,,
C1046,"Q_CAP_0201-1UF,4V,20%,X6S,CH-10KMEE00",1UF,20%,C0201,15341.88,15557.03,90.000,YES,,,
C1047,"Q_CAP_C0201-0.1UF,10V,10%,X7S,CH4102K6E00",0.1UF,10%,C0201,15374.70,15596.48,180.000,YES,,,
C1048,"Q_CAP_C0201-0.1UF,10V,10%,X7S,CH4102K6E00",0.1UF,10%,C0201,15058.21,15557.03,90.000,YES,,,
C1049,"Q_CAP_C0402-10UF,6.3V,20%,X6S,CH6101MEB01",10UF,20%,C0402,14728.00,15706.38,90.000,YES,,,
C1050,"Q_CAP_0201-1UF,4V,20%,X6S,CH-10KMEE00",1UF,20%,C0201,14508.60,15568.20,0.000,YES,,,
C1051,"Q_CAP_C0201-0.1UF,10V,10%,X7S,CH4102K6E00",0.1UF,10%,C0201,15205.45,15606.03,270.000,YES,,,
C1052,"Q_CAP_C0201-0.1UF,10V,10%,X7S,CH4102K6E00",0.1UF,10%,C0201,14591.28,15606.03,270.000,YES,,,
C1053,"Q_CAP_C0201-0.1UF,10V,10%,X7S,CH4102K6E00",0.1UF,10%,C0201,14496.06,15629.57,90.000,YES,,,
C1054,"Q_CAP_0402-4.7UF,6.3V,20%,X6S,CH5471MEB01",4.7UF,20%,C0402,14550.68,15737.12,270.000,YES,,,
C1055,"Q_CAP_C0201-0.1UF,10V,10%,X7S,CH4102K6E00",0.1UF,10%,C0201,15158.21,15606.03,270.000,YES,,,
C1056,"Q_CAP_0402-4.7UF,6.3V,20%,X6S,CH5471MEB01",4.7UF,20%,C0402,14680.76,15706.38,90.000,YES,,,
C1057,"Q_CAP_C0201-0.1UF,10V,10%,X7S,CH4102K6E00",0.1UF,10%,C0201,14550.00,16790.00,0.000,YES,,,
C1058,"Q_CAP_0402-0.1UF,25V,10%,X7R,CH4104K1B00",0.1UF,10%,C0402,6495.00,3780.00,90.000,NO,,,
C1059,"Q_CAP_0402-0.1UF,25V,10%,X7R,CH4104K1B00",0.1UF,10%,C0402,8070.59,3867.91,0.000,NO,,,
C1060,"Q_CAP_0402-0.1UF,25V,10%,X7R,CH4104K1B00",0.1UF,10%,C0402,8370.00,4750.00,180.000,NO,,,
C1061,"Q_CAP_0402-0.1UF,25V,10%,X7R,CH4104K1B00",0.1UF,10%,C0402,3930.00,3115.00,0.000,NO,,,
C1062,"Q_CAP_0402-0.1UF,25V,10%,X7R,CH4104K1B00",0.1UF,10%,C0402,2755.00,2325.00,90.000,NO,,,
C1063,"Q_CAP_0402-0.1UF,25V,10%,X7R,CH4104K1B00",0.1UF,10%,C0402,3405.00,2850.00,0.000,NO,,,
C1064,"Q_CAP_0402-0.1UF,25V,10%,X7R,CH4104K1B00",0.1UF,10%,C0402,2930.00,2210.00,270.000,NO,,,
C1065,"Q_CAP_0402-0.1UF,25V,10%,X7R,CH4104K1B00",0.1UF,10%,C0402,2195.00,1565.00,0.000,NO,,,
C1066,"Q_CAP_C0201-0.1UF,10V,10%,X7S,CH4102K6E00",0.1UF,10%,C0201,6709.62,16685.00,90.000,YES,,,
C1067,"Q_CAP_C0201-0.1UF,10V,10%,X7S,CH4102K6E00",0.1UF,10%,C0201,4507.49,15721.54,270.000,NO,,,
C1068,"Q_CAP_C0201-0.1UF,10V,10%,X7S,CH4102K6E00",0.1UF,10%,C0201,6296.52,16359.49,0.000,YES,,,
C1069,"Q_CAP_C0201-0.1UF,10V,10%,X7S,CH4102K6E00",0.1UF,10%,C0201,3844.57,15928.86,90.000,NO,,,
C1070,"Q_CAP_C0201-0.1UF,10V,10%,X7S,CH4102K6E00",0.1UF,10%,C0201,14810.00,16830.00,90.000,NO,,,
C1071,"Q_CAP_C0201-0.1UF,10V,10%,X7S,CH4102K6E00",0.1UF,10%,C0201,16621.75,16880.21,180.000,YES,,,
C1072,"Q_CAP_C0201-0.1UF,10V,10%,X7S,CH4102K6E00",0.1UF,10%,C0201,11373.20,15550.62,270.000,NO,,,
C1073,"Q_CAP_C0201-0.1UF,10V,10%,X7S,CH4102K6E00",0.1UF,10%,C0201,11767.76,16821.32,180.000,YES,,,
C1074,"Q_CAP_0402-0.1UF,25V,10%,X7R,CH4104K1B00",0.1UF,10%,C0402,10127.27,12900.96,180.000,YES,,,
C1075,"Q_CAP_0402-0.1UF,25V,10%,X7R,CH4104K1B00",0.1UF,10%,C0402,9675.00,12960.00,270.000,YES,,,
C1076,"Q_CAP_C0805-10UF,16V,10%,X6S,CH6103KEA00",10UF,10%,C0805_H57,10146.44,12847.87,180.000,YES,,,
C1077,"Q_CAP_C0805-10UF,16V,10%,X6S,CH6103KEA00",10UF,10%,C0805_H57,9620.00,12955.00,270.000,YES,,,
C1078,"Q_CAP_0402-100PF,50V,5%,EMPTY,CH11006JB18",NA,5%,C0402,10068.69,12717.43,180.000,YES,,,
C1079,"Q_CAP_0402-100PF,50V,5%,EMPTY,CH11006JB18",NA,5%,C0402,9958.69,12671.26,180.000,YES,,,
C1080,"Q_CAP_0402-100PF,50V,5%,EMPTY,CH11006JB18",NA,5%,C0402,9595.00,12750.00,0.000,YES,,,
C1081,"Q_CAP_0402-100PF,50V,5%,EMPTY,CH11006JB18",NA,5%,C0402,9595.00,12790.00,0.000,YES,,,
C1082,"Q_CAP_0402-100PF,50V,5%,EMPTY,CH11006JB18",NA,5%,C0402,9595.00,12710.00,0.000,YES,,,
C1083,"Q_CAP_0402-100PF,50V,5%,EMPTY,CH11006JB18",NA,5%,C0402,9595.00,12670.00,0.000,YES,,,
C1084,"Q_CAP_0402-100PF,50V,5%,EMPTY,CH11006JB18",NA,5%,C0402,10068.40,12757.68,180.000,YES,,,
C1085,"Q_CAP_0402-100PF,50V,5%,EMPTY,CH11006JB18",NA,5%,C0402,10069.19,12797.51,180.000,YES,,,
C1086,"Q_CAP_0402-0.1UF,25V,10%,X7R,CH4104K1B00",0.1UF,10%,C0402,8995.50,12769.68,180.000,YES,,,
C1087,"Q_CAP_0402-0.1UF,25V,10%,X7R,CH4104K1B00",0.1UF,10%,C0402,8995.02,12812.03,180.000,YES,,,
C1088,"Q_CAP_0402-0.1UF,25V,10%,X7R,CH4104K1B00",0.1UF,10%,C0402,8992.54,12938.53,180.000,YES,,,
C1089,"Q_CAP_0402-0.1UF,25V,10%,X7R,CH4104K1B00",0.1UF,10%,C0402,8995.26,12896.30,180.000,YES,,,
C1090,"Q_CAP_0402-0.1UF,25V,10%,X7R,CH4104K1B00",0.1UF,10%,C0402,8992.93,12980.27,180.000,YES,,,
C1091,"Q_CAP_0402-0.1UF,25V,10%,X7R,CH4104K1B00",0.1UF,10%,C0402,8995.48,12854.20,180.000,YES,,,
C1092,"Q_CAP_0402-0.1UF,25V,10%,X7R,CH4104K1B00",0.1UF,10%,C0402,8996.27,12726.92,180.000,YES,,,
C1093,"Q_CAP_0402-0.1UF,25V,10%,X7R,CH4104K1B00",0.1UF,10%,C0402,8995.83,12684.20,180.000,YES,,,
C1094,"Q_CAP_0402-0.1UF,25V,10%,X7R,CH4104K1B00",0.1UF,10%,C0402,8395.79,12813.24,0.000,YES,,,
C1095,"Q_CAP_0402-0.1UF,25V,10%,X7R,CH4104K1B00",0.1UF,10%,C0402,8397.07,12854.72,0.000,YES,,,
C1096,"Q_CAP_0402-0.1UF,25V,10%,X7R,CH4104K1B00",0.1UF,10%,C0402,12917.02,4036.25,0.000,NO,,,
C1097,"Q_CAP_0402-0.1UF,25V,10%,X7R,CH4104K1B00",0.1UF,10%,C0402,15680.17,2973.16,0.000,NO,,,
C1098,"Q_CAP_DIFFBUS_C0201-DIFF BUS_0.22UF,6.3V,20%,X6S,SA",,,C0201_DIFF-BUS,7107.42,2089.21,0.000,NO,,,
C1099,"Q_CAP_DIFFBUS_C0201-DIFF BUS_0.22UF,6.3V,20%,X6S,SA",,,C0201_DIFF-BUS,7107.42,2125.21,0.000,NO,,,
C1100,"Q_CAP_DIFFBUS_C0201-DIFF BUS_0.22UF,6.3V,20%,X6S,SA",,,C0201_DIFF-BUS,7107.42,1970.87,0.000,NO,,,
C1101,"Q_CAP_DIFFBUS_C0201-DIFF BUS_0.22UF,6.3V,20%,X6S,SA",,,C0201_DIFF-BUS,7107.42,2006.87,0.000,NO,,,
C1102,"Q_CAP_0402-0.1UF,25V,10%,X7R,CH4104K1B00",0.1UF,10%,C0402,10102.06,5103.04,0.000,NO,,,
C1103,"Q_CAP_0402-0.1UF,25V,10%,X7R,CH4104K1B00",0.1UF,10%,C0402,10348.38,5397.76,270.000,NO,,,
C1104,"Q_CAP_0402-0.1UF,25V,10%,X7R,CH4104K1B00",0.1UF,10%,C0402,10133.06,5221.46,270.000,YES,,,
C1105,"Q_CAP_0402-0.1UF,25V,10%,X7R,CH4104K1B00",0.1UF,10%,C0402,10202.02,5397.76,270.000,NO,,,
C1106,"Q_CAP_0402-0.1UF,25V,10%,X7R,CH4104K1B00",0.1UF,10%,C0402,1032.54,1536.91,0.000,NO,,,
C1107,"Q_CAP_0402-0.1UF,25V,10%,X7R,CH4104K1B00",0.1UF,10%,C0402,12917.02,4081.25,0.000,NO,,,
C1108,"Q_CAP_0402-0.1UF,25V,10%,X7R,CH4104K1B00",0.1UF,10%,C0402,15680.17,3018.16,0.000,NO,,,
C1109,"Q_CAP_0402-0.1UF,25V,10%,X7R,CH4104K1B00",0.1UF,10%,C0402,1032.54,1581.91,0.000,NO,,,
C1110,"Q_CAP_0402-0.1UF,25V,10%,X7R,CH4104K1B00",0.1UF,10%,C0402,9631.25,2020.96,180.000,NO,,,
C1111,"Q_CAP_0402-0.1UF,25V,10%,X7R,CH4104K1B00",0.1UF,10%,C0402,17418.09,892.64,180.000,NO,,,
C1112,"Q_CAP_0402-0.1UF,25V,10%,X7R,CH4104K1B00",0.1UF,10%,C0402,2769.56,784.61,180.000,NO,,,
C1113,"Q_CAP_C0805-22UF,16V,20%,EMPTY,CH6223MEA00",NA,20%,C0805_H57,1618.60,4142.50,0.000,NO,,,
C1114,"Q_CAP_C0805-22UF,16V,20%,EMPTY,CH6223MEA00",NA,20%,C0805_H57,1886.40,4137.10,0.000,NO,,,
C1115,"Q_CAP_C0805-22UF,16V,20%,EMPTY,CH6223MEA00",NA,20%,C0805_H57,10408.94,16581.46,180.000,NO,,,
C1126,"Q_CAP_C0402-0.1UF,16V,10%,X7R,CH4103K1B08",0.1UF,10%,C0402,7226.42,4404.06,270.000,YES,,,
C1127,"Q_CAP_C0402-0.1UF,16V,10%,X7R,CH4103K1B08",0.1UF,10%,C0402,7194.18,4404.06,270.000,YES,,,
C1128,"Q_CAP_C0402-0.1UF,16V,10%,X7R,CH4103K1B08",0.1UF,10%,C0402,7382.36,4623.74,90.000,YES,,,
C1129,"Q_CAP_C0402-0.1UF,16V,10%,X7R,CH4103K1B08",0.1UF,10%,C0402,7209.94,4639.48,0.000,YES,,,
C1131,"Q_CAP_C0402-0.1UF,16V,10%,X7R,CH4103K1B08",0.1UF,10%,C0402,7257.18,4404.06,270.000,YES,,,
C1132,"Q_CAP_C0402-0.1UF,16V,10%,X7R,CH4103K1B08",0.1UF,10%,C0402,7257.18,4655.23,90.000,YES,,,
C1133,"Q_CAP_C0402-0.1UF,16V,10%,X7R,CH4103K1B08",0.1UF,10%,C0402,7350.86,4623.74,90.000,YES,,,
C1134,"Q_CAP_C0402-0.1UF,16V,10%,X7R,CH4103K1B08",0.1UF,10%,C0402,7301.52,4655.23,90.000,YES,,,
C1170,"Q_CAP_C0805-10UF,16V,10%,X6S,CH6103KEA00",10UF,10%,C0805_H57,15974.99,5624.88,270.000,NO,,,
C1171,"Q_CAP_C0402-0.1UF,16V,10%,X7R,CH4103K1B08",0.1UF,10%,C0402,7366.61,4528.44,180.000,YES,,,
C1172,"Q_CAP_C0402-0.1UF,16V,10%,X7R,CH4103K1B08",0.1UF,10%,C0402,7178.44,4576.49,180.000,YES,,,
C1173,"Q_CAP_C0402-0.1UF,16V,10%,X7R,CH4103K1B08",0.1UF,10%,C0402,7301.52,4592.24,270.000,YES,,,
C1174,"Q_CAP_C0402-0.1UF,16V,10%,X7R,CH4103K1B08",0.1UF,10%,C0402,7257.18,4592.24,270.000,YES,,,
C1175,"Q_CAP_C0402-0.1UF,16V,10%,X7R,CH4103K1B08",0.1UF,10%,C0402,7366.61,4419.81,180.000,YES,,,
C1176,"Q_CAP_C0402-0.1UF,16V,10%,X7R,CH4103K1B08",0.1UF,10%,C0402,7241.43,4528.44,0.000,YES,,,
C1209,"Q_CAP_0402-100PF,50V,5%,NPO,CH11006JB00",100PF,5%,C0402,6459.17,4791.41,180.000,YES,,,
C1213,"Q_CAP_C0805-22UF,16V,20%,X6S,CH6223MEA00",22UF,20%,C0805_H57,17335.96,630.51,180.000,NO,,,
C1227,"Q_CAP_C0402-100NF,50V,10%,X7R,CH4106K1B01",100NF,10%,C0402,15613.45,5761.98,270.000,NO,,,
C1235,"Q_CAP_0402-0.1UF,25V,10%,X7R,CH4104K1B00",0.1UF,10%,C0402,17338.65,536.51,0.000,YES,,,
C1236,"Q_CAP_0402-0.1UF,25V,10%,X7R,CH4104K1B00",0.1UF,10%,C0402,17338.65,576.51,180.000,NO,,,
C1237,"Q_CAP_0402-0.1UF,25V,10%,X7R,CH4104K1B00",0.1UF,10%,C0402,17147.63,516.54,180.000,YES,,,
C1238,"Q_CAP_0402-0.1UF,25V,10%,X7R,CH4104K1B00",0.1UF,10%,C0402,17147.63,476.54,180.000,YES,,,
C1239,"Q_CAP_0402-0.1UF,25V,10%,X7R,CH4104K1B00",0.1UF,10%,C0402,17147.63,436.54,180.000,YES,,,
C1240,"Q_CAP_0402-0.1UF,25V,10%,X7R,CH4104K1B00",0.1UF,10%,C0402,17147.63,396.54,180.000,YES,,,
C1274,"Q_CAP_0402-0.1UF,25V,10%,X7R,CH4104K1B00",0.1UF,10%,C0402,8346.16,1057.81,270.000,NO,,,
C1275,"Q_CAP_0402-0.1UF,25V,10%,X7R,CH4104K1B00",0.1UF,10%,C0402,8329.62,586.32,0.000,NO,,,
C1276,"Q_CAP_C0805-22UF,16V,20%,X6S,CH6223MEA01",22UF,20%,C0805_H57,9584.52,1656.03,270.000,NO,,,
C1277,"Q_CAP_C0805-22UF,16V,20%,X6S,CH6223MEA01",22UF,20%,C0805_H57,9569.42,1759.17,0.000,NO,,,
C1278,"Q_CAP_0402-0.1UF,25V,10%,X7R,CH4104K1B00",0.1UF,10%,C0402,9654.42,1733.85,90.000,NO,,,
C1279,"Q_CAP_0402-0.1UF,25V,10%,X7R,CH4104K1B00",0.1UF,10%,C0402,9654.42,1663.85,270.000,NO,,,
C1282,"Q_CAP_0402-0.1UF,25V,10%,X7R,CH4104K1B00",0.1UF,10%,C0402,9317.95,1933.86,0.000,YES,,,
C1283,"Q_CAP_0402-0.1UF,25V,10%,X7R,CH4104K1B00",0.1UF,10%,C0402,9315.95,1893.86,0.000,YES,,,
C1305,"Q_CAP_0402-0.1UF,25V,10%,X7R,CH4104K1B00",0.1UF,10%,C0402,6147.82,1797.20,180.000,NO,,,
C1323,"Q_CAP_0402-0.1UF,25V,10%,X7R,CH4104K1B00",0.1UF,10%,C0402,5881.94,1765.50,90.000,NO,,,
C1331,"Q_CAP_C0805-10UF,16V,10%,X6S,CH6103KEA00",10UF,10%,C0805_H57,15671.75,5753.88,270.000,NO,,,
C1332,"Q_CAP_C0402-100NF,50V,10%,X7R,CH4106K1B01",100NF,10%,C0402,17519.83,2596.37,270.000,NO,,,
C1333,"Q_CAP_C0805-10UF,16V,10%,X6S,CH6103KEA00",10UF,10%,C0805_H57,17650.70,2590.27,270.000,NO,,,
C1336,"Q_CAP_0402-0.1UF,25V,10%,X7R,CH4104K1B00",0.1UF,10%,C0402,11866.92,5743.22,180.000,NO,,,
C1337,"Q_CAP_0402-0.1UF,25V,10%,X7R,CH4104K1B00",0.1UF,10%,C0402,17248.34,6562.38,180.000,NO,,,
C1338,"Q_CAP_0402-0.1UF,25V,10%,X7R,CH4104K1B00",0.1UF,10%,C0402,1512.47,6683.61,180.000,NO,,,
C1339,"Q_CAP_0402-0.1UF,25V,10%,X7R,CH4104K1B00",0.1UF,10%,C0402,7117.02,6507.56,90.000,NO,,,
C1340,"Q_CAP_C0805-10UF,16V,10%,X6S,CH6103KEA00",10UF,10%,C0805_H57,17485.67,2996.37,0.000,NO,,,
C1344,"Q_CAP_0402-100PF,50V,5%,EMPTY,CH11006JB18",NA,5%,C0402,12431.93,1372.39,180.000,NO,,,
C1347,"Q_CAP_0402-0.1UF,25V,10%,X7R,CH4104K1B00",0.1UF,10%,C0402,12326.93,1452.39,180.000,NO,,,
C1352,"Q_CAP_0402-0.1UF,25V,10%,X7R,CH4104K1B00",0.1UF,10%,C0402,14605.08,1379.43,270.000,NO,,,
C1354,"Q_CAP_0402-0.1UF,25V,10%,X7R,CH4104K1B00",0.1UF,10%,C0402,14572.42,1282.42,0.000,NO,,,
C1503,"Q_CAP_C0402-0.1UF,16V,10%,X7R,CH4103K1B08",0.1UF,10%,C0402,5778.59,2161.96,270.000,NO,,,
C1504,"Q_CAP_C0402-0.1UF,16V,10%,X7R,CH4103K1B08",0.1UF,10%,C0402,4847.54,2249.52,90.000,NO,,,
C1505,"Q_CAP_C0402-0.1UF,16V,10%,X7R,CH4103K1B08",0.1UF,10%,C0402,5739.11,2161.96,270.000,NO,,,
C1506,"Q_CAP_C0402-0.1UF,16V,10%,X7R,CH4103K1B08",0.1UF,10%,C0402,10565.17,4065.60,0.000,NO,,,
C1507,"Q_CAP_C0402-0.1UF,16V,10%,X7R,CH4103K1B08",0.1UF,10%,C0402,10692.36,3954.57,270.000,NO,,,
C1508,"Q_CAP_C0402-0.1UF,16V,10%,X7R,CH4103K1B08",0.1UF,10%,C0402,10452.45,4065.86,180.000,NO,,,
C1509,"Q_CAP_C0402-0.1UF,16V,10%,X7R,CH4103K1B08",0.1UF,10%,C0402,10693.22,4025.48,90.000,NO,,,
C1510,"Q_CAP_0402-33PF,50V,5%,NPO,TMP_QCH03306JB04",33PF,15%,C0402,11349.05,3805.33,0.000,NO,,,
C1511,"Q_CAP_0402-33PF,50V,5%,NPO,TMP_QCH03306JB04",33PF,15%,C0402,11349.05,3856.98,0.000,NO,,,
C1512,"Q_CAP_0402-33PF,50V,5%,NPO,TMP_QCH03306JB04",33PF,15%,C0402,10229.59,3977.26,0.000,NO,,,
C1513,"Q_CAP_C0402-0.1UF,16V,10%,X7R,CH4103K1B08",0.1UF,10%,C0402,5220.88,2058.60,90.000,NO,,,
C1514,"Q_CAP_C0402-0.1UF,16V,10%,X7R,CH4103K1B08",0.1UF,10%,C0402,10096.18,4005.65,270.000,NO,,,
C1515,"Q_CAP_C0402-0.1UF,16V,10%,X7R,CH4103K1B08",0.1UF,10%,C0402,11259.09,3980.20,0.000,NO,,,
C1516,"Q_CAP_C0402-0.1UF,16V,10%,X7R,CH4103K1B08",0.1UF,10%,C0402,10044.60,3650.36,270.000,NO,,,
C1517,"Q_CAP_C0402-0.1UF,16V,10%,X7R,CH4103K1B08",0.1UF,10%,C0402,10885.11,3731.87,180.000,NO,,,
C1518,"Q_CAP_C0402-0.1UF,16V,10%,X7R,CH4103K1B08",0.1UF,10%,C0402,5027.76,2132.85,180.000,NO,,,
C1519,"Q_CAP_C0402-0.1UF,16V,10%,X7R,CH4103K1B08",0.1UF,10%,C0402,9081.72,5824.12,180.000,NO,,,
C1520,"Q_CAP_C0402-0.01UF,50V,10%,EMPTY,CH31006KB18",NA,10%,C0402,9465.81,5904.17,180.000,NO,,,
C1521,"Q_CAP_C0402-0.1UF,16V,10%,X7R,CH4103K1B08",0.1UF,10%,C0402,9039.51,5974.49,180.000,NO,,,
C1522,"Q_CAP_C0402-0.1UF,16V,10%,X7R,CH4103K1B08",0.1UF,10%,C0402,9051.31,6113.58,180.000,NO,,,
C1523,"Q_CAP_C0402-0.1UF,16V,10%,X7R,CH4103K1B08",0.1UF,10%,C0402,9081.72,6259.12,180.000,NO,,,
C1524,"Q_CAP_DIFFBUS_C0201-DIFF BUS_0.22UF,6.3V,20%,X6S,SA",,,C0201_DIFF-BUS,5174.24,14686.45,270.000,NO,,,
C1525,"Q_CAP_DIFFBUS_C0201-DIFF BUS_0.22UF,6.3V,20%,X6S,SA",,,C0201_DIFF-BUS,5138.24,14686.45,270.000,NO,,,
C1526,"Q_CAP_DIFFBUS_C0201-DIFF BUS_0.22UF,6.3V,20%,X6S,SA",,,C0201_DIFF-BUS,5107.24,14783.45,270.000,NO,,,
C1527,"Q_CAP_DIFFBUS_C0201-DIFF BUS_0.22UF,6.3V,20%,X6S,SA",,,C0201_DIFF-BUS,5071.24,14783.45,270.000,NO,,,
C1528,"Q_CAP_DIFFBUS_C0201-DIFF BUS_0.22UF,6.3V,20%,X6S,SA",,,C0201_DIFF-BUS,4973.24,14589.45,270.000,NO,,,
C1529,"Q_CAP_DIFFBUS_C0201-DIFF BUS_0.22UF,6.3V,20%,X6S,SA",,,C0201_DIFF-BUS,4937.24,14589.45,270.000,NO,,,
C1530,"Q_CAP_DIFFBUS_C0201-DIFF BUS_0.22UF,6.3V,20%,X6S,SA",,,C0201_DIFF-BUS,4906.24,14686.45,270.000,NO,,,
C1531,"Q_CAP_DIFFBUS_C0201-DIFF BUS_0.22UF,6.3V,20%,X6S,SA",,,C0201_DIFF-BUS,4870.24,14686.45,270.000,NO,,,
C1532,"Q_CAP_DIFFBUS_C0201-DIFF BUS_0.22UF,6.3V,20%,X6S,SA",,,C0201_DIFF-BUS,4839.24,14783.45,270.000,NO,,,
C1533,"Q_CAP_DIFFBUS_C0201-DIFF BUS_0.22UF,6.3V,20%,X6S,SA",,,C0201_DIFF-BUS,4803.24,14783.45,270.000,NO,,,
C1534,"Q_CAP_DIFFBUS_C0201-DIFF BUS_0.22UF,6.3V,20%,X6S,SA",,,C0201_DIFF-BUS,4705.24,14589.45,270.000,NO,,,
C1535,"Q_CAP_DIFFBUS_C0201-DIFF BUS_0.22UF,6.3V,20%,X6S,SA",,,C0201_DIFF-BUS,4669.24,14589.45,270.000,NO,,,
C1536,"Q_CAP_DIFFBUS_C0201-DIFF BUS_0.22UF,6.3V,20%,X6S,SA",,,C0201_DIFF-BUS,4638.24,14686.45,270.000,NO,,,
C1537,"Q_CAP_DIFFBUS_C0201-DIFF BUS_0.22UF,6.3V,20%,X6S,SA",,,C0201_DIFF-BUS,4602.24,14686.45,270.000,NO,,,
C1538,"Q_CAP_DIFFBUS_C0201-DIFF BUS_0.22UF,6.3V,20%,X6S,SA",,,C0201_DIFF-BUS,4571.24,14783.45,270.000,NO,,,
C1539,"Q_CAP_DIFFBUS_C0201-DIFF BUS_0.22UF,6.3V,20%,X6S,SA",,,C0201_DIFF-BUS,4535.24,14783.45,270.000,NO,,,
C1540,"Q_CAP_DIFFBUS_C0201-DIFF BUS_0.22UF,6.3V,20%,X6S,SA",,,C0201_DIFF-BUS,4437.24,14589.45,270.000,NO,,,
C1541,"Q_CAP_DIFFBUS_C0201-DIFF BUS_0.22UF,6.3V,20%,X6S,SA",,,C0201_DIFF-BUS,4401.24,14589.45,270.000,NO,,,
C1542,"Q_CAP_DIFFBUS_C0201-DIFF BUS_0.22UF,6.3V,20%,X6S,SA",,,C0201_DIFF-BUS,4370.24,14686.45,270.000,NO,,,
C1543,"Q_CAP_DIFFBUS_C0201-DIFF BUS_0.22UF,6.3V,20%,X6S,SA",,,C0201_DIFF-BUS,4334.24,14686.45,270.000,NO,,,
C1544,"Q_CAP_DIFFBUS_C0201-DIFF BUS_0.22UF,6.3V,20%,X6S,SA",,,C0201_DIFF-BUS,4333.36,14836.90,180.000,NO,,,
C1545,"Q_CAP_DIFFBUS_C0201-DIFF BUS_0.22UF,6.3V,20%,X6S,SA",,,C0201_DIFF-BUS,4333.36,14800.90,180.000,NO,,,
C1546,"Q_CAP_DIFFBUS_C0201-DIFF BUS_0.22UF,6.3V,20%,X6S,SA",,,C0201_DIFF-BUS,4333.36,15018.90,180.000,NO,,,
C1547,"Q_CAP_DIFFBUS_C0201-DIFF BUS_0.22UF,6.3V,20%,X6S,SA",,,C0201_DIFF-BUS,4333.36,15054.90,180.000,NO,,,
C1548,"Q_CAP_DIFFBUS_C0201-DIFF BUS_0.22UF,6.3V,20%,X6S,SA",,,C0201_DIFF-BUS,15354.62,633.87,90.000,NO,,,
C1549,"Q_CAP_DIFFBUS_C0201-DIFF BUS_0.22UF,6.3V,20%,X6S,SA",,,C0201_DIFF-BUS,15390.62,633.87,90.000,NO,,,
C1550,"Q_CAP_DIFFBUS_C0201-DIFF BUS_0.22UF,6.3V,20%,X6S,SA",,,C0201_DIFF-BUS,15464.62,693.87,90.000,NO,,,
C1552,"Q_CAP_DIFFBUS_C0201-DIFF BUS_0.22UF,6.3V,20%,X6S,SA",,,C0201_DIFF-BUS,15574.62,633.87,90.000,NO,,,
C1553,"Q_CAP_DIFFBUS_C0201-DIFF BUS_0.22UF,6.3V,20%,X6S,SA",,,C0201_DIFF-BUS,15610.62,633.87,90.000,NO,,,
C1554,"Q_CAP_C0402-0.1UF,16V,10%,X7R,CH4103K1B08",0.1UF,10%,C0402,4581.15,2425.28,90.000,NO,,,
C1555,"Q_CAP_DIFFBUS_C0201-DIFF BUS_0.22UF,6.3V,20%,X6S,SA",,,C0201_DIFF-BUS,15720.62,693.87,90.000,NO,,,
C1556,"Q_CAP_DIFFBUS_C0201-DIFF BUS_0.22UF,6.3V,20%,X6S,SA",,,C0201_DIFF-BUS,15794.62,633.87,90.000,NO,,,
C1557,"Q_CAP_DIFFBUS_C0201-DIFF BUS_0.22UF,6.3V,20%,X6S,SA",,,C0201_DIFF-BUS,15830.62,633.87,90.000,NO,,,
C1558,"Q_CAP_DIFFBUS_C0201-DIFF BUS_0.22UF,6.3V,20%,X6S,SA",,,C0201_DIFF-BUS,15904.62,693.87,90.000,NO,,,
C1559,"Q_CAP_DIFFBUS_C0201-DIFF BUS_0.22UF,6.3V,20%,X6S,SA",,,C0201_DIFF-BUS,15940.62,693.87,90.000,NO,,,
C1560,"Q_CAP_DIFFBUS_C0201-DIFF BUS_0.22UF,6.3V,20%,X6S,SA",,,C0201_DIFF-BUS,16014.62,633.87,90.000,NO,,,
C1561,"Q_CAP_0402-0.1UF,25V,10%,EMPTY,CH4104K1B00",NA,10%,C0402,5984.98,4643.49,180.000,NO,,,
C1563,"Q_CAP_C0402-0.1UF,16V,10%,X7R,CH4103K1B08",0.1UF,10%,C0402,11874.88,871.25,0.000,NO,,,
C1564,"Q_CAP_C0402-1UF,25V,10%,X6S,CH5104KEB02",1UF,10%,C0402,11662.03,757.77,270.000,NO,,,
C1565,"Q_CAP_DIFFBUS_C0201-DIFF BUS_0.22UF,6.3V,20%,X6S,SA",,,C0201_DIFF-BUS,16270.62,633.87,90.000,NO,,,
C1566,"Q_CAP_DIFFBUS_C0201-DIFF BUS_0.22UF,6.3V,20%,X6S,SA",,,C0201_DIFF-BUS,16356.66,693.87,90.000,NO,,,
C1567,"Q_CAP_C0402-1UF,25V,10%,X6S,CH5104KEB02",1UF,10%,C0402,13078.57,1073.53,90.000,NO,,,
C1568,"Q_CAP_DIFFBUS_C0201-DIFF BUS_0.22UF,6.3V,20%,X6S,SA",,,C0201_DIFF-BUS,16466.66,633.87,90.000,NO,,,
C1569,"Q_CAP_DIFFBUS_C0201-DIFF BUS_0.22UF,6.3V,20%,X6S,SA",,,C0201_DIFF-BUS,16502.66,633.87,90.000,NO,,,
C1570,"Q_CAP_DIFFBUS_C0201-DIFF BUS_0.22UF,6.3V,20%,X6S,SA",,,C0201_DIFF-BUS,16576.66,693.87,90.000,NO,,,
C1571,"Q_CAP_DIFFBUS_C0201-DIFF BUS_0.22UF,6.3V,20%,X6S,SA",,,C0201_DIFF-BUS,16612.66,693.87,90.000,NO,,,
C1572,"Q_CAP_DIFFBUS_C0201-DIFF BUS_0.22UF,6.3V,20%,X6S,SA",,,C0201_DIFF-BUS,16686.66,633.87,90.000,NO,,,
C1573,"Q_CAP_DIFFBUS_C0201-DIFF BUS_0.22UF,6.3V,20%,X6S,SA",,,C0201_DIFF-BUS,16722.66,633.87,90.000,NO,,,
C1574,"Q_CAP_DIFFBUS_C0201-DIFF BUS_0.22UF,6.3V,20%,X6S,SA",,,C0201_DIFF-BUS,16798.00,693.87,90.000,NO,,,
C1575,"Q_CAP_DIFFBUS_C0201-DIFF BUS_0.22UF,6.3V,20%,X6S,SA",,,C0201_DIFF-BUS,16834.00,693.87,90.000,NO,,,
C1576,"Q_CAP_DIFFBUS_C0201-DIFF BUS_0.22UF,6.3V,20%,X6S,SA",,,C0201_DIFF-BUS,16908.00,633.87,90.000,NO,,,
C1577,"Q_CAP_DIFFBUS_C0201-DIFF BUS_0.22UF,6.3V,20%,X6S,SA",,,C0201_DIFF-BUS,16944.00,633.87,90.000,NO,,,
C1578,"Q_CAP_DIFFBUS_C0201-DIFF BUS_0.22UF,6.3V,20%,X6S,SA",,,C0201_DIFF-BUS,17018.00,693.87,90.000,NO,,,
C1579,"Q_CAP_DIFFBUS_C0201-DIFF BUS_0.22UF,6.3V,20%,X6S,SA",,,C0201_DIFF-BUS,17054.00,693.87,90.000,NO,,,
C1592,"Q_CAP_0402-0.1UF,25V,10%,X7R,CH4104K1B00",0.1UF,10%,C0402,10153.34,2928.11,90.000,NO,,,
C1663,"Q_CAP_0402-0.1UF,25V,10%,X7R,CH4104K1B00",0.1UF,10%,C0402,6350.60,1446.43,90.000,NO,,,
C1707,"Q_CAP_0402-0.1UF,25V,10%,X7R,CH4104K1B00",0.1UF,10%,C0402,6377.94,17199.70,90.000,NO,,,
C1708,"Q_CAP_0402-0.1UF,25V,10%,X7R,CH4104K1B00",0.1UF,10%,C0402,11379.64,16825.18,0.000,YES,,,
C1713,"Q_CAP_0402-0.1UF,25V,10%,X7R,CH4104K1B00",0.1UF,10%,C0402,7066.23,16645.76,270.000,NO,,,
C1751,"Q_CAP_0402-0.1UF,25V,10%,X7R,CH4104K1B00",0.1UF,10%,C0402,6845.00,16545.00,0.000,YES,,,
C1754,"Q_CAP_0402-0.1UF,25V,10%,X7R,CH4104K1B00",0.1UF,10%,C0402,16895.13,17101.84,270.000,NO,,,
C1756,"Q_CAP_0402-0.1UF,25V,10%,X7R,CH4104K1B00",0.1UF,10%,C0402,2036.60,16701.78,90.000,YES,,,
C1757,"Q_CAP_0402-0.1UF,25V,10%,X7R,CH4104K1B00",0.1UF,10%,C0402,12966.93,1457.39,0.000,NO,,,
C1766,"Q_CAP_0402-0.1UF,25V,10%,X7R,CH4104K1B00",0.1UF,10%,C0402,1310.68,17093.46,0.000,NO,,,
C1767,"Q_CAP_C0805-10UF,16V,10%,X6S,CH6103KEA00",10UF,10%,C0805_H57,12206.93,1457.39,180.000,NO,,,
C1768,"Q_CAP_C0805-10UF,16V,10%,X6S,CH6103KEA00",10UF,10%,C0805_H57,12985.77,1512.17,0.000,NO,,,
C1769,"Q_CAP_0402-0.1UF,25V,10%,X7R,CH4104K1B00",0.1UF,10%,C0402,7042.58,16310.36,180.000,YES,,,
C1770,"Q_CAP_0402-0.1UF,25V,10%,X7R,CH4104K1B00",0.1UF,10%,C0402,1940.00,17165.00,270.000,NO,,,
C1772,"Q_CAP_0402-0.1UF,25V,10%,X7R,CH4104K1B00",0.1UF,10%,C0402,16545.13,17253.34,270.000,NO,,,
C1773,"Q_CAP_0402-0.1UF,25V,10%,X7R,CH4104K1B00",0.1UF,10%,C0402,6504.00,17280.00,0.000,NO,,,
C1774,"Q_CAP_0402-0.1UF,25V,10%,X7R,CH4104K1B00",0.1UF,10%,C0402,14166.69,16414.31,180.000,YES,,,
C1775,"Q_CAP_0402-0.1UF,25V,10%,X7R,CH4104K1B00",0.1UF,10%,C0402,7540.30,16575.83,90.000,NO,,,
C1786,"Q_CAP_0603-1000PF,50V,10%,X7R,TMP_QCH21006K917",1000PF,10%,C0603,11230.10,15802.98,180.000,NO,,,
C1787,"Q_CAP_C0402-0.1UF,16V,10%,X7R,CH4103K1B08",0.1UF,10%,C0402,11312.56,15705.27,90.000,NO,,,
C1792,"Q_CAP_DIFFBUS_C0201-DIFF BUS_0.22UF,6.3V,20%,X6S,SA",,,C0201_DIFF-BUS,15500.62,693.87,90.000,NO,,,
C1793,"Q_CAP_DIFFBUS_C0201-DIFF BUS_0.22UF,6.3V,20%,X6S,SA",,,C0201_DIFF-BUS,16050.62,633.87,90.000,NO,,,
C1794,"Q_CAP_DIFFBUS_C0201-DIFF BUS_0.22UF,6.3V,20%,X6S,SA",,,C0201_DIFF-BUS,16124.62,693.87,90.000,NO,,,
C1796,"Q_CAP_0402-0.1UF,25V,10%,X7R,CH4104K1B00",0.1UF,10%,C0402,937.67,17162.41,180.000,NO,,,
C1797,"Q_CAP_0402-0.1UF,25V,10%,X7R,CH4104K1B00",0.1UF,10%,C0402,10642.21,16584.20,90.000,NO,,,
C1802,"Q_CAP_0402-0.1UF,25V,10%,X7R,CH4104K1B00",0.1UF,10%,C0402,4610.00,16455.00,90.000,NO,,,
C1803,"Q_CAP_0402-0.1UF,25V,10%,X7R,CH4104K1B00",0.1UF,10%,C0402,14136.22,16393.42,90.000,NO,,,
C1804,"Q_CAP_0402-0.1UF,25V,10%,X7R,CH4104K1B00",0.1UF,10%,C0402,4280.00,16450.00,90.000,YES,,,
C1809,"Q_CAP_0402-0.1UF,25V,10%,X7R,CH4104K1B00",0.1UF,10%,C0402,613.55,3103.57,0.000,NO,,,
C1810,"Q_CAP_0402-0.1UF,25V,10%,X7R,CH4104K1B00",0.1UF,10%,C0402,613.55,2803.57,0.000,NO,,,
C1821,"Q_CAP_0402-0.1UF,25V,10%,X7R,CH4104K1B00",0.1UF,10%,C0402,3359.14,1651.70,0.000,NO,,,
C1822,"Q_CAP_0402-0.1UF,25V,10%,X7R,CH4104K1B00",0.1UF,10%,C0402,3774.95,1490.77,180.000,NO,,,
C1823,"Q_CAP_0402-0.1UF,25V,10%,X7R,CH4104K1B00",0.1UF,10%,C0402,10087.02,4334.26,0.000,NO,,,
C1824,"Q_CAP_0402-0.1UF,25V,10%,X7R,CH4104K1B00",0.1UF,10%,C0402,3879.93,1429.37,0.000,NO,,,
C1825,"Q_CAP_0402-0.1UF,25V,10%,X7R,CH4104K1B00",0.1UF,10%,C0402,1908.61,1270.77,90.000,NO,,,
C1826,"Q_CAP_0402-0.1UF,25V,10%,X7R,CH4104K1B00",0.1UF,10%,C0402,8026.70,3127.73,0.000,YES,,,
C1827,"Q_CAP_0402-0.1UF,25V,10%,X7R,CH4104K1B00",0.1UF,10%,C0402,7590.39,2866.32,0.000,YES,,,
C1829,"Q_CAP_C0805-22UF,16V,20%,X6S,CH6223MEA00",22UF,20%,C0805_H57,2566.66,678.26,180.000,NO,,,
C1830,"Q_CAP_C0805-22UF,16V,20%,X6S,CH6223MEA00",22UF,20%,C0805_H57,2566.66,678.26,0.000,YES,,,
C1831,"Q_CAP_0402-0.1UF,25V,10%,X7R,CH4104K1B00",0.1UF,10%,C0402,2574.00,624.00,180.000,NO,,,
C1832,"Q_CAP_0402-0.1UF,25V,10%,X7R,CH4104K1B00",0.1UF,10%,C0402,2574.00,544.00,180.000,NO,,,
C1833,"Q_CAP_0402-0.1UF,25V,10%,X7R,CH4104K1B00",0.1UF,10%,C0402,2574.00,584.00,180.000,NO,,,
C1834,"Q_CAP_0402-0.1UF,25V,10%,X7R,CH4104K1B00",0.1UF,10%,C0402,2574.00,624.00,0.000,YES,,,
C1835,"Q_CAP_0402-0.1UF,25V,10%,X7R,CH4104K1B00",0.1UF,10%,C0402,2541.22,353.70,90.000,YES,,,
C1836,"Q_CAP_0402-0.1UF,25V,10%,X7R,CH4104K1B00",0.1UF,10%,C0402,2422.20,353.62,90.000,YES,,,
C1837,"Q_CAP_0402-0.1UF,25V,10%,X7R,CH4104K1B00",0.1UF,10%,C0402,2462.20,353.62,90.000,YES,,,
C1838,"Q_CAP_0402-0.1UF,25V,10%,X7R,CH4104K1B00",0.1UF,10%,C0402,2502.20,353.62,90.000,YES,,,
C1839,"Q_CAP_0402-0.1UF,25V,10%,X7R,CH4104K1B00",0.1UF,10%,C0402,2574.00,584.00,0.000,YES,,,
C1840,"Q_CAP_0402-0.1UF,25V,10%,X7R,CH4104K1B00",0.1UF,10%,C0402,18187.32,3713.29,0.000,NO,,,
C1841,"Q_CAP_0402-0.1UF,25V,10%,X7R,CH4104K1B00",0.1UF,10%,C0402,2030.61,1270.77,90.000,NO,,,
C1859,"Q_CAP_0402-0.1UF,25V,10%,X7R,CH4104K1B00",0.1UF,10%,C0402,5664.60,1590.69,90.000,NO,,,
C1860,"Q_CAP_0402-0.1UF,25V,10%,X7R,CH4104K1B00",0.1UF,10%,C0402,15888.00,3051.71,90.000,NO,,,
C1861,"Q_CAP_0402-0.1UF,25V,10%,X7R,CH4104K1B00",0.1UF,10%,C0402,5952.60,1590.69,90.000,NO,,,
C1862,"Q_CAP_0402-0.1UF,25V,10%,X7R,CH4104K1B00",0.1UF,10%,C0402,16174.00,3051.71,90.000,NO,,,
C1863,"Q_CAP_0402-0.1UF,25V,10%,X7R,CH4104K1B00",0.1UF,10%,C0402,1248.53,16610.87,180.000,NO,,,
C1864,"Q_CAP_0402-0.1UF,25V,10%,X7R,CH4104K1B00",0.1UF,10%,C0402,1453.53,16825.87,0.000,NO,,,
C1865,"Q_CAP_0402-0.1UF,25V,10%,X7R,CH4104K1B00",0.1UF,10%,C0402,644.38,16598.19,270.000,YES,,,
C1866,"Q_CAP_0402-0.1UF,25V,10%,X7R,CH4104K1B00",0.1UF,10%,C0402,1316.75,16805.13,180.000,YES,,,
C1867,"Q_CAP_C0805-10UF,25V,10%,X6S,CH6104KEA00",10UF,10%,C0805_H61,1381.85,16723.33,0.000,YES,,,
C1868,"Q_CAP_0402-0.1UF,25V,10%,X7R,CH4104K1B00",0.1UF,10%,C0402,1541.35,16793.84,0.000,NO,,,
C1869,"Q_CAP_0402-0.1UF,25V,10%,X7R,CH4104K1B00",0.1UF,10%,C0402,1541.35,16742.39,0.000,NO,,,
C1870,"Q_CAP_0402-0.1UF,25V,10%,X7R,CH4104K1B00",0.1UF,10%,C0402,1123.50,16577.52,180.000,NO,,,
C1871,"Q_CAP_0402-0.1UF,25V,10%,X7R,CH4104K1B00",0.1UF,10%,C0402,1123.45,16627.19,180.000,NO,,,
C1873,"Q_CAP_0402-0.1UF,25V,10%,X7R,CH4104K1B00",0.1UF,10%,C0402,6153.85,4084.21,90.000,NO,,,
C1874,"Q_CAP_0402-0.1UF,25V,10%,X7R,CH4104K1B00",0.1UF,10%,C0402,16519.10,2314.87,90.000,NO,,,
C1875,"Q_CAP_0402-0.1UF,25V,10%,X7R,CH4104K1B00",0.1UF,10%,C0402,331.80,2997.82,90.000,NO,,,
C1876,"Q_CAP_0402-0.1UF,25V,10%,X7R,CH4104K1B00",0.1UF,10%,C0402,637.80,2997.82,90.000,NO,,,
C1877,"Q_CAP_0402-0.1UF,25V,10%,X7R,CH4104K1B00",0.1UF,10%,C0402,6153.85,3888.02,90.000,NO,,,
C1878,"Q_CAP_0402-0.1UF,25V,10%,X7R,CH4104K1B00",0.1UF,10%,C0402,6153.85,3780.02,90.000,NO,,,
C1879,"Q_CAP_0402-0.1UF,25V,10%,X7R,CH4104K1B00",0.1UF,10%,C0402,5793.85,3780.02,90.000,NO,,,
C1880,"Q_CAP_0402-0.1UF,25V,10%,X7R,CH4104K1B00",0.1UF,10%,C0402,5793.85,3888.02,90.000,NO,,,
C1881,"Q_CAP_0402-0.1UF,25V,10%,X7R,CH4104K1B00",0.1UF,10%,C0402,2024.23,16581.70,0.000,YES,,,
C1882,"Q_CAP_0402-0.1UF,25V,10%,X7R,CH4104K1B00",0.1UF,10%,C0402,1184.07,5227.91,270.000,NO,,,
C1883,"Q_CAP_C0805-10UF,25V,10%,X6S,CH6104KEA00",10UF,10%,C0805_H61,428.61,5392.85,0.000,YES,,,
C1884,"Q_CAP_C0402-1UF,25V,10%,X6S,CH5104KEB02",1UF,10%,C0402,608.22,5227.95,90.000,YES,,,
C1886,"Q_CAP_0402-0.1UF,25V,10%,X7R,CH4104K1B00",0.1UF,10%,C0402,461.02,5218.75,270.000,YES,,,
C1889,"Q_CAP_0402-0.1UF,25V,10%,X7R,CH4104K1B00",0.1UF,10%,C0402,473.44,5283.04,180.000,YES,,,
C1920,"Q_CAP_C0603-22UF,6.3V,20%,X6S,CH6221ME900",22UF,20%,C0603,6516.12,2039.90,270.000,NO,,,
C1921,"Q_CAP_C0603-22UF,6.3V,20%,X6S,CH6221ME900",22UF,20%,C0603,6461.76,2039.95,270.000,NO,,,
C1922,"Q_CAP_C0402-22UF,4V,20%,X6S,CH622KMEB02",22UF,20%,C0402_H32,13811.77,9817.65,180.000,YES,,,
C1923,"Q_CAP_0402-0.1UF,25V,10%,X7R,CH4104K1B00",0.1UF,10%,C0402,6679.80,2103.62,180.000,YES,,,
C1924,"Q_CAP_0402-0.1UF,25V,10%,X7R,CH4104K1B00",0.1UF,10%,C0402,6679.80,2063.62,180.000,YES,,,
C1925,"Q_CAP_0402-0.1UF,25V,10%,X7R,CH4104K1B00",0.1UF,10%,C0402,6679.80,2023.62,180.000,YES,,,
C1957,"Q_CAP_0402-0.1UF,25V,10%,X7R,CH4104K1B00",0.1UF,10%,C0402,2110.00,17135.00,270.000,NO,,,
C1958,"Q_CAP_0402-0.1UF,25V,10%,X7R,CH4104K1B00",0.1UF,10%,C0402,4715.00,16800.00,0.000,NO,,,
C1963,"Q_CAP_0402-0.1UF,25V,10%,X7R,CH4104K1B00",0.1UF,10%,C0402,4170.00,16665.00,90.000,NO,,,
C1973,"Q_CAP_0402-0.1UF,25V,10%,X7R,CH4104K1B00",0.1UF,10%,C0402,6504.00,17171.38,0.000,NO,,,
C1974,"Q_CAP_0402-0.1UF,25V,10%,X7R,CH4104K1B00",0.1UF,10%,C0402,2038.07,17004.13,90.000,YES,,,
C1975,"Q_CAP_0402-0.1UF,25V,10%,X7R,CH4104K1B00",0.1UF,10%,C0402,4665.00,16555.00,180.000,NO,,,
C1976,"Q_CAP_0402-0.1UF,25V,10%,X7R,CH4104K1B00",0.1UF,10%,C0402,12102.54,17154.36,90.000,NO,,,
C1977,"Q_CAP_0402-0.1UF,25V,10%,X7R,CH4104K1B00",0.1UF,10%,C0402,1675.00,17170.00,270.000,NO,,,
C1978,"Q_CAP_0402-0.1UF,25V,10%,X7R,CH4104K1B00",0.1UF,10%,C0402,2038.07,16852.95,90.000,YES,,,
C1979,"Q_CAP_0402-0.1UF,25V,10%,X7R,CH4104K1B00",0.1UF,10%,C0402,4685.00,17130.00,270.000,NO,,,
C1988,"Q_CAP_0402-0.1UF,25V,10%,X7R,CH4104K1B00",0.1UF,10%,C0402,4571.51,16374.42,90.000,YES,,,
C1989,"Q_CAP_DIFFBUS_C0201-DIFF BUS_0.22UF,6.3V,20%,X6S,SA",,,C0201_DIFF-BUS,9415.46,2296.35,0.000,NO,,,
C1990,"Q_CAP_DIFFBUS_C0201-DIFF BUS_0.22UF,6.3V,20%,X6S,SA",,,C0201_DIFF-BUS,9415.46,2260.35,0.000,NO,,,
C1991,"Q_CAP_DIFFBUS_C0201-DIFF BUS_0.22UF,6.3V,20%,X6S,SA",,,C0201_DIFF-BUS,9482.46,2189.48,0.000,NO,,,
C1992,"Q_CAP_DIFFBUS_C0201-DIFF BUS_0.22UF,6.3V,20%,X6S,SA",,,C0201_DIFF-BUS,9482.46,2225.48,0.000,NO,,,
C1993,"Q_CAP_DIFFBUS_C0201-DIFF BUS_0.22UF,6.3V,20%,X6S,SA",,,C0201_DIFF-BUS,9415.46,2118.97,0.000,NO,,,
C1994,"Q_CAP_DIFFBUS_C0201-DIFF BUS_0.22UF,6.3V,20%,X6S,SA",,,C0201_DIFF-BUS,9415.46,2154.97,0.000,NO,,,
C1995,"Q_CAP_DIFFBUS_C0201-DIFF BUS_0.22UF,6.3V,20%,X6S,SA",,,C0201_DIFF-BUS,9415.46,2047.75,0.000,NO,,,
C1996,"Q_CAP_DIFFBUS_C0201-DIFF BUS_0.22UF,6.3V,20%,X6S,SA",,,C0201_DIFF-BUS,9415.46,2083.75,0.000,NO,,,
C1997,"Q_CAP_0402-0.1UF,25V,10%,X7R,CH4104K1B00",0.1UF,10%,C0402,8503.20,1627.62,0.000,NO,,,
C1998,"Q_CAP_0402-0.1UF,25V,10%,X7R,CH4104K1B00",0.1UF,10%,C0402,8727.20,1663.62,0.000,NO,,,
C2007,"Q_CAP_C0402-1UF,25V,10%,X6S,CH5104KEB02",1UF,10%,C0402,5793.85,4027.33,90.000,NO,,,
C2010,"Q_CAP_0402-0.1UF,25V,10%,X7R,CH4104K1B00",0.1UF,10%,C0402,14425.79,16693.03,90.000,NO,,,
C2012,"Q_CAP_0402-0.1UF,25V,10%,X7R,CH4104K1B00",0.1UF,10%,C0402,2980.53,1517.03,0.000,NO,,,
C2013,"Q_CAP_0402-0.1UF,25V,10%,X7R,CH4104K1B00",0.1UF,10%,C0402,6220.29,2217.77,0.000,NO,,,
C2014,"Q_CAP_0402-0.1UF,25V,10%,X7R,CH4104K1B00",0.1UF,10%,C0402,8266.14,1486.98,90.000,NO,,,
C2015,"Q_CAP_0402-0.1UF,25V,10%,X7R,CH4104K1B00",0.1UF,10%,C0402,17255.00,3793.62,90.000,NO,,,
C2017,"Q_CAP_0402-0.1UF,25V,10%,X7R,CH4104K1B00",0.1UF,10%,C0402,2980.53,1562.03,0.000,NO,,,
C2018,"Q_CAP_0402-0.1UF,25V,10%,X7R,CH4104K1B00",0.1UF,10%,C0402,6220.29,2262.77,0.000,NO,,,
C2019,"Q_CAP_0402-0.1UF,25V,10%,X7R,CH4104K1B00",0.1UF,10%,C0402,8211.20,1409.62,90.000,YES,,,
C2020,"Q_CAP_0402-0.1UF,25V,10%,X7R,CH4104K1B00",0.1UF,10%,C0402,3103.39,2298.51,270.000,NO,,,
C2021,"Q_CAP_0402-0.1UF,25V,10%,X7R,CH4104K1B00",0.1UF,10%,C0402,6306.09,2289.75,270.000,NO,,,
C2022,"Q_CAP_0402-0.1UF,25V,10%,X7R,CH4104K1B00",0.1UF,10%,C0402,8082.20,1415.62,90.000,YES,,,
C2024,"Q_CAP_0402-0.1UF,25V,10%,X7R,CH4104K1B00",0.1UF,10%,C0402,17225.00,3703.62,90.000,NO,,,
C2027,"Q_CAP_0402-0.1UF,25V,10%,X7R,CH4104K1B00",0.1UF,10%,C0402,17161.90,3649.62,0.000,NO,,,
C2029,"Q_CAP_0402-15PF,50V,5%,C0G,CH01506JB06",15PF,5%,C0402,365.24,3937.71,90.000,NO,,,
C2030,"Q_CAP_0402-15PF,50V,5%,C0G,CH01506JB06",15PF,5%,C0402,365.95,3865.52,270.000,NO,,,
C2031,"Q_CAP_C0402-1UF,25V,10%,X6S,CH5104KEB02",1UF,10%,C0402,537.38,3984.70,90.000,YES,,,
C2032,"Q_CAP_0402-0.1UF,25V,10%,X7R,CH4104K1B00",0.1UF,10%,C0402,638.13,3884.62,0.000,YES,,,
C2033,"Q_CAP_0402-0.1UF,25V,10%,X7R,CH4104K1B00",0.1UF,10%,C0402,472.58,3934.08,180.000,YES,,,
C2034,"Q_CAP_0402-0.1UF,25V,10%,X7R,CH4104K1B00",0.1UF,10%,C0402,470.91,3869.93,180.000,YES,,,
C2035,"Q_CAP_C0402-1UF,25V,10%,X6S,CH5104KEB02",1UF,10%,C0402,575.44,3984.96,90.000,YES,,,
C2038,"Q_CAP_C0402-10UF,6.3V,20%,X6S,CH6101MEB01",10UF,20%,C0402,638.11,3930.79,0.000,YES,,,
C2039,"Q_CAP_0402-0.1UF,25V,10%,X7R,CH4104K1B00",0.1UF,10%,C0402,653.97,3831.28,90.000,YES,,,
C2040,"Q_CAP_0402-0.1UF,25V,10%,X7R,CH4104K1B00",0.1UF,10%,C0402,699.98,3832.37,90.000,YES,,,
C2041,"Q_CAP_C0402-1UF,25V,10%,X6S,CH5104KEB02",1UF,10%,C0402,468.34,3649.12,270.000,NO,,,
C2042,"Q_CAP_0402-100PF,50V,5%,EMPTY,CH11006JB18",NA,5%,C0402,12966.93,1297.39,0.000,NO,,,
C2043,"Q_CAP_0402-100PF,50V,5%,EMPTY,CH11006JB18",NA,5%,C0402,12966.93,1257.39,0.000,NO,,,
C2044,"Q_CAP_0402-100PF,50V,5%,EMPTY,CH11006JB18",NA,5%,C0402,12431.93,1237.39,180.000,NO,,,
C2045,"Q_CAP_0402-100PF,50V,5%,EMPTY,CH11006JB18",NA,5%,C0402,12966.93,1337.39,0.000,NO,,,
C2046,"Q_CAP_0402-0.1UF,25V,10%,X7R,CH4104K1B00",0.1UF,10%,C0402,12596.07,1850.51,0.000,NO,,,
C2047,"Q_CAP_0402-0.1UF,25V,10%,X7R,CH4104K1B00",0.1UF,10%,C0402,12596.07,1640.51,0.000,NO,,,
C2048,"Q_CAP_0402-0.1UF,25V,10%,X7R,CH4104K1B00",0.1UF,10%,C0402,12596.07,1680.51,0.000,NO,,,
C2049,"Q_CAP_0402-0.1UF,25V,10%,X7R,CH4104K1B00",0.1UF,10%,C0402,12596.07,1720.51,0.000,NO,,,
C2050,"Q_CAP_0402-0.1UF,25V,10%,X7R,CH4104K1B00",0.1UF,10%,C0402,12596.07,1600.51,0.000,NO,,,
C2051,"Q_CAP_0402-0.1UF,25V,10%,X7R,CH4104K1B00",0.1UF,10%,C0402,11937.02,1771.87,180.000,NO,,,
C2052,"Q_CAP_0402-0.1UF,25V,10%,X7R,CH4104K1B00",0.1UF,10%,C0402,11937.02,1731.87,180.000,NO,,,
C2056,"Q_CAP_0402-0.1UF,25V,10%,X7R,CH4104K1B00",0.1UF,10%,C0402,10574.80,4900.37,0.000,NO,,,
C2067,"Q_CAP_0402-0.1UF,25V,10%,X7R,CH4104K1B00",0.1UF,10%,C0402,8512.20,2093.62,0.000,YES,,,
C2069,"Q_CAP_0402-0.1UF,25V,10%,X7R,CH4104K1B00",0.1UF,10%,C0402,8511.20,2163.62,0.000,YES,,,
C2071,"Q_CAP_0402-0.1UF,25V,10%,X7R,CH4104K1B00",0.1UF,10%,C0402,8587.83,2259.83,270.000,NO,,,
C2073,"Q_CAP_DIFFBUS_C0201-DIFF BUS_0.22UF,6.3V,20%,X6S,SA",,,C0201_DIFF-BUS,1738.15,16287.07,0.000,YES,,,
C2074,"Q_CAP_DIFFBUS_C0201-DIFF BUS_0.22UF,6.3V,20%,X6S,SA",,,C0201_DIFF-BUS,1738.15,16254.07,0.000,YES,,,
C2075,"Q_CAP_DIFFBUS_C0201-DIFF BUS_0.22UF,6.3V,20%,X6S,SA",,,C0201_DIFF-BUS,2036.81,16381.54,0.000,YES,,,
C2076,"Q_CAP_DIFFBUS_C0201-DIFF BUS_0.22UF,6.3V,20%,X6S,SA",,,C0201_DIFF-BUS,2036.81,16414.54,0.000,YES,,,
C2077,"Q_CAP_DIFFBUS_C0201-DIFF BUS_0.22UF,6.3V,20%,X6S,SA",,,C0201_DIFF-BUS,6301.47,790.11,270.000,NO,,,
C2078,"Q_CAP_DIFFBUS_C0201-DIFF BUS_0.22UF,6.3V,20%,X6S,SA",,,C0201_DIFF-BUS,6332.93,790.11,270.000,NO,,,
C2102,"Q_CAP_C0402-22UF,4V,20%,X6S,CH622KMEB02",22UF,20%,C0402_H32,4030.66,10225.60,180.000,YES,,,
C2103,"Q_CAP_C0402-22UF,4V,20%,X6S,CH622KMEB02",22UF,20%,C0402_H32,3955.86,10225.60,180.000,YES,,,
C2104,"Q_CAP_C0402-22UF,4V,20%,X6S,CH622KMEB02",22UF,20%,C0402_H32,3881.59,10107.66,180.000,YES,,,
C2105,"Q_CAP_C0402-22UF,4V,20%,X6S,CH622KMEB02",22UF,20%,C0402_H32,3947.71,10374.88,0.000,YES,,,
C2106,"Q_CAP_C0402-22UF,4V,20%,X6S,CH622KMEB02",22UF,20%,C0402_H32,3947.71,10312.88,0.000,YES,,,
C2107,"Q_CAP_C0402-22UF,4V,20%,X6S,CH622KMEB02",22UF,20%,C0402_H32,3881.06,10225.60,180.000,YES,,,
C2108,"Q_CAP_C0402-22UF,4V,20%,X6S,CH622KMEB02",22UF,20%,C0402_H32,3877.71,10434.88,0.000,YES,,,
C2109,"Q_CAP_C0402-22UF,4V,20%,X6S,CH622KMEB02",22UF,20%,C0402_H32,3881.06,10190.17,180.000,YES,,,
C2110,"Q_CAP_C0402-22UF,4V,20%,X6S,CH622KMEB02",22UF,20%,C0402_H32,4030.66,10154.74,180.000,YES,,,
C2111,"Q_CAP_C0402-22UF,4V,20%,X6S,CH622KMEB02",22UF,20%,C0402_H32,4171.66,10136.04,180.000,YES,,,
C2112,"Q_CAP_C0402-22UF,4V,20%,X6S,CH622KMEB02",22UF,20%,C0402_H32,3955.86,10154.74,180.000,YES,,,
C2113,"Q_CAP_C0402-22UF,4V,20%,X6S,CH622KMEB02",22UF,20%,C0402_H32,4388.86,10305.04,270.000,NO,,,
C2114,"Q_CAP_C0402-22UF,4V,20%,X6S,CH622KMEB02",22UF,20%,C0402_H32,4781.59,10407.66,0.000,YES,,,
C2115,"Q_CAP_C0402-22UF,4V,20%,X6S,CH622KMEB02",22UF,20%,C0402_H32,4046.59,10472.66,0.000,YES,,,
C2116,"Q_CAP_C0402-22UF,4V,20%,X6S,CH622KMEB02",22UF,20%,C0402_H32,3877.71,10312.88,0.000,YES,,,
C2117,"Q_CAP_C0402-22UF,4V,20%,X6S,CH622KMEB02",22UF,20%,C0402_H32,3947.71,10434.88,0.000,YES,,,
C2118,"Q_CAP_C0402-22UF,4V,20%,X6S,CH622KMEB02",22UF,20%,C0402_H32,4561.59,10472.66,0.000,YES,,,
C2119,"Q_CAP_C0402-22UF,4V,20%,X6S,CH622KMEB02",22UF,20%,C0402_H32,4711.59,10407.66,0.000,YES,,,
C2120,"Q_CAP_C0402-22UF,4V,20%,X6S,CH622KMEB02",22UF,20%,C0402_H32,4926.59,10407.66,0.000,YES,,,
C2121,"Q_CAP_C0402-22UF,4V,20%,X6S,CH622KMEB02",22UF,20%,C0402_H32,4314.06,10305.04,270.000,NO,,,
C2122,"Q_CAP_C0402-22UF,4V,20%,X6S,CH622KMEB02",22UF,20%,C0402_H32,4265.98,10188.79,180.000,YES,,,
C2123,"Q_CAP_C0402-22UF,4V,20%,X6S,CH622KMEB02",22UF,20%,C0402_H32,3881.06,10154.74,180.000,YES,,,
C2124,"Q_CAP_C0402-22UF,4V,20%,X6S,CH622KMEB02",22UF,20%,C0402_H32,4351.46,10305.04,90.000,YES,,,
C2125,"Q_CAP_C0402-22UF,4V,20%,X6S,CH622KMEB02",22UF,20%,C0402_H32,4314.06,10305.04,90.000,YES,,,
C2126,"Q_CAP_C0402-22UF,4V,20%,X6S,CH622KMEB02",22UF,20%,C0402_H32,4931.59,10472.66,0.000,YES,,,
C2127,"Q_CAP_C0402-22UF,4V,20%,X6S,CH622KMEB02",22UF,20%,C0402_H32,4265.98,10230.13,0.000,NO,,,
C2128,"Q_CAP_C0402-22UF,4V,20%,X6S,CH622KMEB02",22UF,20%,C0402_H32,4636.59,10407.66,0.000,YES,,,
C2129,"Q_CAP_C0402-22UF,4V,20%,X6S,CH622KMEB02",22UF,20%,C0402_H32,14628.01,10190.16,0.000,YES,,,
C2130,"Q_CAP_C0402-22UF,4V,20%,X6S,CH622KMEB02",22UF,20%,C0402_H32,14553.01,10072.65,0.000,YES,,,
C2131,"Q_CAP_C0402-22UF,4V,20%,X6S,CH622KMEB02",22UF,20%,C0402_H32,14027.40,10230.12,180.000,YES,,,
C2132,"Q_CAP_C0402-22UF,4V,20%,X6S,CH622KMEB02",22UF,20%,C0402_H32,14125.83,10230.12,0.000,NO,,,
C2133,"Q_CAP_C0402-22UF,4V,20%,X6S,CH622KMEB02",22UF,20%,C0402_H32,14402.98,10323.03,180.000,NO,,,
C2134,"Q_CAP_C0402-22UF,4V,20%,X6S,CH622KMEB02",22UF,20%,C0402_H32,14553.01,9942.65,0.000,YES,,,
C2135,"Q_CAP_C0402-22UF,4V,20%,X6S,CH622KMEB02",22UF,20%,C0402_H32,14187.64,10079.22,270.000,YES,,,
C2136,"Q_CAP_C0402-22UF,4V,20%,X6S,CH622KMEB02",22UF,20%,C0402_H32,13933.08,10210.83,0.000,NO,,,
C2137,"Q_CAP_C0402-22UF,4V,20%,X6S,CH622KMEB02",22UF,20%,C0402_H32,14299.89,10305.03,90.000,YES,,,
C2138,"Q_CAP_C0402-22UF,4V,20%,X6S,CH622KMEB02",22UF,20%,C0402_H32,14323.01,10407.65,0.000,YES,,,
C2139,"Q_CAP_C0402-22UF,4V,20%,X6S,CH622KMEB02",22UF,20%,C0402_H32,14402.98,10248.23,180.000,NO,,,
C2140,"Q_CAP_C0402-22UF,4V,20%,X6S,CH622KMEB02",22UF,20%,C0402_H32,14162.26,10017.65,180.000,YES,,,
C2141,"Q_CAP_C0402-22UF,4V,20%,X6S,CH622KMEB02",22UF,20%,C0402_H32,13933.08,10248.23,0.000,NO,,,
C2142,"Q_CAP_C0402-22UF,4V,20%,X6S,CH622KMEB02",22UF,20%,C0402_H32,14473.01,10472.65,0.000,YES,,,
C2143,"Q_CAP_C0402-22UF,4V,20%,X6S,CH622KMEB02",22UF,20%,C0402_H32,14458.01,9977.65,0.000,YES,,,
C2144,"Q_CAP_C0402-22UF,4V,20%,X6S,CH622KMEB02",22UF,20%,C0402_H32,14162.26,9977.65,180.000,YES,,,
C2145,"Q_CAP_C0402-22UF,4V,20%,X6S,CH622KMEB02",22UF,20%,C0402_H32,13933.08,10285.63,180.000,YES,,,
C2146,"Q_CAP_C0402-22UF,4V,20%,X6S,CH622KMEB02",22UF,20%,C0402_H32,14187.68,10305.03,270.000,NO,,,
C2147,"Q_CAP_C0402-22UF,4V,20%,X6S,CH622KMEB02",22UF,20%,C0402_H32,14402.98,10098.63,0.000,YES,,,
C2148,"Q_CAP_C0402-22UF,4V,20%,X6S,CH622KMEB02",22UF,20%,C0402_H32,14225.04,10079.22,90.000,NO,,,
C2149,"Q_CAP_C0402-22UF,4V,20%,X6S,CH622KMEB02",22UF,20%,C0402_H32,13933.08,10285.63,0.000,NO,,,
C2150,"Q_CAP_C0402-22UF,4V,20%,X6S,CH622KMEB02",22UF,20%,C0402_H32,14000.68,10305.03,270.000,NO,,,
C2151,"Q_CAP_C0402-22UF,4V,20%,X6S,CH622KMEB02",22UF,20%,C0402_H32,14628.01,9942.65,0.000,YES,,,
C2152,"Q_CAP_C0402-22UF,4V,20%,X6S,CH622KMEB02",22UF,20%,C0402_H32,14402.98,10061.22,0.000,YES,,,
C2153,"Q_CAP_C0402-22UF,4V,20%,X6S,CH622KMEB02",22UF,20%,C0402_H32,14075.48,10305.03,90.000,YES,,,
C2154,"Q_CAP_C0402-22UF,4V,20%,X6S,CH622KMEB02",22UF,20%,C0402_H32,14628.01,10072.65,0.000,YES,,,
C2155,"Q_CAP_C0402-22UF,4V,20%,X6S,CH622KMEB02",22UF,20%,C0402_H32,14337.24,10079.22,270.000,YES,,,
C2156,"Q_CAP_C0402-22UF,4V,20%,X6S,CH622KMEB02",22UF,20%,C0402_H32,14112.88,10305.03,270.000,NO,,,
C2157,"Q_CAP_C0402-22UF,4V,20%,X6S,CH622KMEB02",22UF,20%,C0402_H32,14402.98,10210.83,180.000,NO,,,
C2158,"Q_CAP_C0402-22UF,4V,20%,X6S,CH622KMEB02",22UF,20%,C0402_H32,14150.28,10305.03,270.000,NO,,,
C2159,"Q_CAP_C0402-22UF,4V,20%,X6S,CH622KMEB02",22UF,20%,C0402_H32,14262.44,10079.22,90.000,NO,,,
C2160,"Q_CAP_C0402-22UF,4V,20%,X6S,CH622KMEB02",22UF,20%,C0402_H32,14214.41,10230.12,180.000,YES,,,
C2161,"Q_CAP_C0402-22UF,4V,20%,X6S,CH622KMEB02",22UF,20%,C0402_H32,14299.84,10079.22,90.000,NO,,,
C2162,"Q_CAP_C0402-22UF,4V,20%,X6S,CH622KMEB02",22UF,20%,C0402_H32,13803.01,10407.65,0.000,YES,,,
C2163,"Q_CAP_C0402-22UF,4V,20%,X6S,CH622KMEB02",22UF,20%,C0402_H32,13933.08,10098.63,180.000,YES,,,
C2164,"Q_CAP_C0402-22UF,4V,20%,X6S,CH622KMEB02",22UF,20%,C0402_H32,13933.08,10061.22,0.000,NO,,,
C2165,"Q_CAP_C0402-22UF,4V,20%,X6S,CH622KMEB02",22UF,20%,C0402_H32,13881.77,9877.65,180.000,YES,,,
C2166,"Q_CAP_C0402-22UF,4V,20%,X6S,CH622KMEB02",22UF,20%,C0402_H32,14628.01,9877.65,0.000,YES,,,
C2167,"Q_CAP_C0402-22UF,4V,20%,X6S,CH622KMEB02",22UF,20%,C0402_H32,13736.77,9817.65,180.000,YES,,,
C2169,"Q_CAP_C0402-22UF,4V,20%,X6S,CH622KMEB02",22UF,20%,C0402_H32,14418.01,9782.65,180.000,YES,,,
C2170,"Q_CAP_C0402-22UF,4V,20%,X6S,CH622KMEB02",22UF,20%,C0402_H32,13953.77,9877.65,180.000,YES,,,
C2171,"Q_CAP_C0402-22UF,4V,20%,X6S,CH622KMEB02",22UF,20%,C0402_H32,14228.01,9702.65,300.000,YES,,,
C2173,"Q_CAP_C0402-22UF,4V,20%,X6S,CH622KMEB02",22UF,20%,C0402_H32,14478.01,9817.65,0.000,YES,,,
C2174,"Q_CAP_C0402-22UF,4V,20%,X6S,CH622KMEB02",22UF,20%,C0402_H32,14348.01,9782.65,0.000,YES,,,
C2175,"Q_CAP_C0402-22UF,4V,20%,X6S,CH622KMEB02",22UF,20%,C0402_H32,14253.99,9817.65,0.000,YES,,,
C2176,"Q_CAP_0402-100PF,50V,5%,EMPTY,CH11006JB18",NA,5%,C0402,12431.93,1327.39,180.000,NO,,,
C2177,"Q_CAP_C0402-22UF,4V,20%,X6S,CH622KMEB02",22UF,20%,C0402_H32,14550.01,9817.65,0.000,YES,,,
C2178,"Q_CAP_C0402-22UF,4V,20%,X6S,CH622KMEB02",22UF,20%,C0402_H32,13903.01,9782.65,0.000,YES,,,
C2179,"Q_CAP_C0402-100NF,50V,10%,X7R,CH4106K1B01",100NF,10%,C0402,10637.51,16494.94,90.000,NO,,,
C2181,"Q_CAP_C0402-22UF,4V,20%,X6S,CH622KMEB02",22UF,20%,C0402_H32,14681.77,9782.65,0.000,YES,,,
C2182,"Q_CAP_C0402-22UF,4V,20%,X6S,CH622KMEB02",22UF,20%,C0402_H32,14096.77,9799.88,120.000,YES,,,
C2183,"Q_CAP_C0402-22UF,4V,20%,X6S,CH622KMEB02",22UF,20%,C0402_H32,13696.77,9679.88,270.000,YES,,,
C2185,"Q_CAP_C0402-22UF,4V,20%,X6S,CH622KMEB02",22UF,20%,C0402_H32,14291.77,9699.88,180.000,YES,,,
C2186,"Q_CAP_C0402-22UF,4V,20%,X6S,CH622KMEB02",22UF,20%,C0402_H32,14163.01,9837.65,90.000,YES,,,
C2189,"Q_CAP_C0402-22UF,4V,20%,X6S,CH622KMEB02",22UF,20%,C0402_H32,13756.77,9664.88,180.000,YES,,,
C2190,"Q_CAP_C0402-22UF,4V,20%,X6S,CH622KMEB02",22UF,20%,C0402_H32,14098.01,9702.65,240.000,YES,,,
C2192,"Q_CAP_C0402-22UF,4V,20%,X6S,CH622KMEB02",22UF,20%,C0402_H32,14571.77,9664.88,0.000,YES,,,
C2193,"Q_CAP_C0402-22UF,4V,20%,X6S,CH622KMEB02",22UF,20%,C0402_H32,14163.01,9762.65,90.000,YES,,,
C2194,"Q_CAP_0402-0.1UF,25V,10%,X7R,CH4104K1B00",0.1UF,10%,C0402,12596.07,1557.30,0.000,NO,,,
C2195,"Q_CAP_C0402-22UF,4V,20%,X6S,CH622KMEB02",22UF,20%,C0402_H32,14568.77,9782.65,0.000,YES,,,
C2196,"Q_CAP_C0402-22UF,4V,20%,X6S,CH622KMEB02",22UF,20%,C0402_H32,14238.01,9852.65,0.000,YES,,,
C2198,"Q_CAP_C0402-22UF,4V,20%,X6S,CH622KMEB02",22UF,20%,C0402_H32,14631.77,9679.88,270.000,YES,,,
C2199,"Q_CAP_C0402-22UF,4V,20%,X6S,CH622KMEB02",22UF,20%,C0402_H32,14031.77,9699.88,0.000,YES,,,
C2201,"Q_CAP_C0402-22UF,4V,20%,X6S,CH622KMEB02",22UF,20%,C0402_H32,13988.01,10602.65,180.000,YES,,,
C2202,"Q_CAP_C0402-22UF,4V,20%,X6S,CH622KMEB02",22UF,20%,C0402_H32,14250.91,10532.65,0.000,YES,,,
C2203,"Q_CAP_C0402-22UF,4V,20%,X6S,CH622KMEB02",22UF,20%,C0402_H32,14083.01,10567.65,0.000,YES,,,
C2204,"Q_CAP_C0402-22UF,4V,20%,X6S,CH622KMEB02",22UF,20%,C0402_H32,14325.72,10532.65,0.000,YES,,,
C2205,"Q_CAP_C0402-22UF,4V,20%,X6S,CH622KMEB02",22UF,20%,C0402_H32,13803.01,10532.65,0.000,YES,,,
C2207,"Q_CAP_C0402-22UF,4V,20%,X6S,CH622KMEB02",22UF,20%,C0402_H32,14618.01,10531.44,0.000,YES,,,
C2208,"Q_CAP_C0402-22UF,4V,20%,X6S,CH622KMEB02",22UF,20%,C0402_H32,14433.01,10602.65,180.000,YES,,,
C2209,"Q_CAP_C0402-22UF,4V,20%,X6S,CH622KMEB02",22UF,20%,C0402_H32,14043.77,10684.88,0.000,YES,,,
C2210,"Q_CAP_C0402-22UF,4V,20%,X6S,CH622KMEB02",22UF,20%,C0402_H32,13808.01,10602.65,0.000,YES,,,
C2211,"Q_CAP_C0402-22UF,4V,20%,X6S,CH622KMEB02",22UF,20%,C0402_H32,14473.01,10531.44,0.000,YES,,,
C2213,"Q_CAP_C0402-22UF,4V,20%,X6S,CH622KMEB02",22UF,20%,C0402_H32,14431.77,10719.88,180.000,YES,,,
C2214,"Q_CAP_C0402-22UF,4V,20%,X6S,CH622KMEB02",22UF,20%,C0402_H32,14563.01,10567.65,0.000,YES,,,
C2215,"Q_CAP_C0402-22UF,4V,20%,X6S,CH622KMEB02",22UF,20%,C0402_H32,14581.77,10719.88,0.000,YES,,,
C2216,"Q_CAP_C0402-22UF,4V,20%,X6S,CH622KMEB02",22UF,20%,C0402_H32,13918.01,10602.65,0.000,YES,,,
C2217,"Q_CAP_C0402-22UF,4V,20%,X6S,CH622KMEB02",22UF,20%,C0402_H32,13676.77,10567.65,180.000,YES,,,
C2219,"Q_CAP_C0402-22UF,4V,20%,X6S,CH622KMEB02",22UF,20%,C0402_H32,14343.01,10567.65,0.000,YES,,,
C2220,"Q_CAP_C0402-22UF,4V,20%,X6S,CH622KMEB02",22UF,20%,C0402_H32,13863.01,10567.65,0.000,YES,,,
C2221,"Q_CAP_C0402-22UF,4V,20%,X6S,CH622KMEB02",22UF,20%,C0402_H32,14361.77,10719.88,0.000,YES,,,
C2222,"Q_CAP_C0402-22UF,4V,20%,X6S,CH622KMEB02",22UF,20%,C0402_H32,14418.01,10567.65,0.000,YES,,,
C2223,"Q_CAP_C0402-22UF,4V,20%,X6S,CH622KMEB02",22UF,20%,C0402_H32,14693.01,10531.44,0.000,YES,,,
C2225,"Q_CAP_C0402-22UF,4V,20%,X6S,CH622KMEB02",22UF,20%,C0402_H32,14304.77,10684.88,180.000,YES,,,
C2226,"Q_CAP_C0402-22UF,4V,20%,X6S,CH622KMEB02",22UF,20%,C0402_H32,14008.01,10567.65,0.000,YES,,,
C2227,"Q_CAP_C0402-22UF,4V,20%,X6S,CH622KMEB02",22UF,20%,C0402_H32,14028.01,10532.65,0.000,YES,,,
C2228,"Q_CAP_C0402-22UF,4V,20%,X6S,CH622KMEB02",22UF,20%,C0402_H32,14583.77,10602.65,0.000,YES,,,
C2229,"Q_CAP_C0402-22UF,4V,20%,X6S,CH622KMEB02",22UF,20%,C0402_H32,13938.01,10567.65,0.000,YES,,,
C2231,"Q_CAP_C0402-22UF,4V,20%,X6S,CH622KMEB02",22UF,20%,C0402_H32,13733.01,10532.65,0.000,YES,,,
C2232,"Q_CAP_C0402-22UF,4V,20%,X6S,CH622KMEB02",22UF,20%,C0402_H32,14488.01,10567.65,0.000,YES,,,
C2233,"Q_CAP_C0402-22UF,4V,20%,X6S,CH622KMEB02",22UF,20%,C0402_H32,13704.77,10703.88,90.000,YES,,,
C2234,"Q_CAP_C0402-22UF,4V,20%,X6S,CH622KMEB02",22UF,20%,C0402_H32,13766.77,10719.88,180.000,YES,,,
C2237,"Q_CAP_C0402-22UF,4V,20%,X6S,CH622KMEB02",22UF,20%,C0402_H32,13878.01,10532.65,0.000,YES,,,
C2238,"Q_CAP_C0402-22UF,4V,20%,X6S,CH622KMEB02",22UF,20%,C0402_H32,13788.01,10567.65,0.000,YES,,,
C2239,"Q_CAP_C0402-22UF,4V,20%,X6S,CH622KMEB02",22UF,20%,C0402_H32,13986.77,10719.88,180.000,YES,,,
C2240,"Q_CAP_C0402-22UF,4V,20%,X6S,CH622KMEB02",22UF,20%,C0402_H32,14103.01,10532.65,0.000,YES,,,
C2243,"Q_CAP_C0402-22UF,4V,20%,X6S,CH622KMEB02",22UF,20%,C0402_H32,14543.01,10531.44,0.000,YES,,,
C2244,"Q_CAP_C0402-22UF,4V,20%,X6S,CH622KMEB02",22UF,20%,C0402_H32,14173.01,10532.65,270.000,YES,,,
C2245,"Q_CAP_C0402-22UF,4V,20%,X6S,CH622KMEB02",22UF,20%,C0402_H32,14638.01,10567.65,0.000,YES,,,
C2246,"Q_CAP_C0402-22UF,4V,20%,X6S,CH622KMEB02",22UF,20%,C0402_H32,14701.77,10584.88,60.000,YES,,,
C2248,"Q_CAP_C0402-22UF,4V,20%,X6S,CH622KMEB02",22UF,20%,C0402_H32,14268.01,10567.65,0.000,YES,,,
C2249,"Q_CAP_C0402-22UF,4V,20%,X6S,CH622KMEB02",22UF,20%,C0402_H32,14641.77,10702.88,90.000,YES,,,
C2250,"Q_CAP_C0402-22UF,4V,20%,X6S,CH622KMEB02",22UF,20%,C0402_H32,13916.77,10719.88,0.000,YES,,,
C2251,"Q_CAP_C0402-22UF,4V,20%,X6S,CH622KMEB02",22UF,20%,C0402_H32,14651.01,10602.65,180.000,YES,,,
C2253,"Q_CAP_C0402-22UF,4V,20%,X6S,CH622KMEB02",22UF,20%,C0402_H32,13953.01,10532.65,0.000,YES,,,
C2254,"Q_CAP_C0402-22UF,4V,20%,X6S,CH622KMEB02",22UF,20%,C0402_H32,14363.01,10602.65,0.000,YES,,,
C2255,"Q_CAP_C0402-22UF,4V,20%,X6S,CH622KMEB02",22UF,20%,C0402_H32,14400.52,10532.65,0.000,YES,,,
C2256,"Q_CAP_C0402-22UF,4V,20%,X6S,CH622KMEB02",22UF,20%,C0402_H32,13651.77,10602.65,180.000,YES,,,
C2257,"Q_CAP_0402-0.1UF,25V,10%,X7R,CH4104K1B00",0.1UF,10%,C0402,474.82,5339.85,180.000,YES,,,
C2258,"Q_CAP_C0402-22UF,4V,20%,X6S,CH622KMEB02",22UF,20%,C0402_H32,4256.59,9977.66,0.000,YES,,,
C2259,"Q_CAP_C0402-22UF,4V,20%,X6S,CH622KMEB02",22UF,20%,C0402_H32,4696.59,9912.66,0.000,YES,,,
C2260,"Q_CAP_C0402-22UF,4V,20%,X6S,CH622KMEB02",22UF,20%,C0402_H32,4171.66,10173.44,0.000,NO,,,
C2261,"Q_CAP_C0402-22UF,4V,20%,X6S,CH622KMEB02",22UF,20%,C0402_H32,4116.59,10472.66,0.000,YES,,,
C2262,"Q_CAP_C0402-22UF,4V,20%,X6S,CH622KMEB02",22UF,20%,C0402_H32,4239.26,10305.04,270.000,NO,,,
C2263,"Q_CAP_C0402-22UF,4V,20%,X6S,CH622KMEB02",22UF,20%,C0402_H32,4314.01,10079.23,270.000,YES,,,
C2264,"Q_CAP_C0402-22UF,4V,20%,X6S,CH622KMEB02",22UF,20%,C0402_H32,4452.99,10147.45,180.000,YES,,,
C2265,"Q_CAP_C0402-22UF,4V,20%,X6S,CH622KMEB02",22UF,20%,C0402_H32,4171.66,10248.24,180.000,YES,,,
C2266,"Q_CAP_C0402-22UF,4V,20%,X6S,CH622KMEB02",22UF,20%,C0402_H32,4364.41,10230.13,0.000,NO,,,
C2267,"Q_CAP_C0402-22UF,4V,20%,X6S,CH622KMEB02",22UF,20%,C0402_H32,4555.35,10230.13,0.000,NO,,,
C2268,"Q_CAP_C0402-22UF,4V,20%,X6S,CH622KMEB02",22UF,20%,C0402_H32,4400.84,9937.66,180.000,YES,,,
C2269,"Q_CAP_C0402-22UF,4V,20%,X6S,CH622KMEB02",22UF,20%,C0402_H32,4641.56,10210.84,180.000,NO,,,
C2270,"Q_CAP_C0402-22UF,4V,20%,X6S,CH622KMEB02",22UF,20%,C0402_H32,4171.66,10136.04,0.000,NO,,,
C2271,"Q_CAP_C0402-22UF,4V,20%,X6S,CH622KMEB02",22UF,20%,C0402_H32,4575.87,10305.04,90.000,YES,,,
C2272,"Q_CAP_C0402-22UF,4V,20%,X6S,CH622KMEB02",22UF,20%,C0402_H32,4400.84,9977.66,180.000,YES,,,
C2273,"Q_CAP_C0402-22UF,4V,20%,X6S,CH622KMEB02",22UF,20%,C0402_H32,4641.56,10285.64,180.000,NO,,,
C2274,"Q_CAP_C0402-22UF,4V,20%,X6S,CH622KMEB02",22UF,20%,C0402_H32,4171.66,10248.24,0.000,NO,,,
C2275,"Q_CAP_C0402-22UF,4V,20%,X6S,CH622KMEB02",22UF,20%,C0402_H32,4486.59,10472.66,0.000,YES,,,
C2276,"Q_CAP_C0402-22UF,4V,20%,X6S,CH622KMEB02",22UF,20%,C0402_H32,4452.99,10188.79,180.000,YES,,,
C2277,"Q_CAP_C0402-22UF,4V,20%,X6S,CH622KMEB02",22UF,20%,C0402_H32,4401.59,9897.66,180.000,YES,,,
C2278,"Q_CAP_C0402-22UF,4V,20%,X6S,CH622KMEB02",22UF,20%,C0402_H32,4171.66,10210.84,0.000,NO,,,
C2279,"Q_CAP_C0402-22UF,4V,20%,X6S,CH622KMEB02",22UF,20%,C0402_H32,4452.99,10230.13,0.000,NO,,,
C2280,"Q_CAP_C0402-22UF,4V,20%,X6S,CH622KMEB02",22UF,20%,C0402_H32,4696.59,9977.66,0.000,YES,,,
C2281,"Q_CAP_C0402-22UF,4V,20%,X6S,CH622KMEB02",22UF,20%,C0402_H32,4476.59,9912.66,0.000,YES,,,
C2282,"Q_CAP_C0402-22UF,4V,20%,X6S,CH622KMEB02",22UF,20%,C0402_H32,4463.66,10305.04,270.000,NO,,,
C2283,"Q_CAP_C0402-22UF,4V,20%,X6S,CH622KMEB02",22UF,20%,C0402_H32,4641.56,10061.23,180.000,NO,,,
C2284,"Q_CAP_C0402-22UF,4V,20%,X6S,CH622KMEB02",22UF,20%,C0402_H32,4476.59,9977.66,0.000,YES,,,
C2285,"Q_CAP_C0402-22UF,4V,20%,X6S,CH622KMEB02",22UF,20%,C0402_H32,4336.59,10472.66,0.000,YES,,,
C2286,"Q_CAP_C0402-22UF,4V,20%,X6S,CH622KMEB02",22UF,20%,C0402_H32,4641.56,10248.24,180.000,NO,,,
C2287,"Q_CAP_C0402-22UF,4V,20%,X6S,CH622KMEB02",22UF,20%,C0402_H32,4191.59,10472.66,0.000,YES,,,
C2288,"Q_CAP_C0402-22UF,4V,20%,X6S,CH622KMEB02",22UF,20%,C0402_H32,4641.56,10173.44,180.000,NO,,,
C2289,"Q_CAP_C0402-22UF,4V,20%,X6S,CH622KMEB02",22UF,20%,C0402_H32,4266.59,10472.66,0.000,YES,,,
C2290,"Q_CAP_C0402-22UF,4V,20%,X6S,CH622KMEB02",22UF,20%,C0402_H32,4641.56,10098.64,180.000,NO,,,
C2291,"Q_CAP_C0402-22UF,4V,20%,X6S,CH622KMEB02",22UF,20%,C0402_H32,4388.86,10305.04,90.000,YES,,,
C2292,"Q_CAP_C0402-22UF,4V,20%,X6S,CH622KMEB02",22UF,20%,C0402_H32,3971.71,10002.66,180.000,YES,,,
C2293,"Q_CAP_C0402-22UF,4V,20%,X6S,CH622KMEB02",22UF,20%,C0402_H32,3901.59,10072.66,180.000,YES,,,
C2294,"Q_CAP_C0402-22UF,4V,20%,X6S,CH622KMEB02",22UF,20%,C0402_H32,4197.71,9817.66,180.000,YES,,,
C2295,"Q_CAP_C0402-22UF,4V,20%,X6S,CH622KMEB02",22UF,20%,C0402_H32,3933.71,9679.88,270.000,YES,,,
C2296,"Q_CAP_C0402-22UF,4V,20%,X6S,CH622KMEB02",22UF,20%,C0402_H32,4716.59,9877.66,0.000,YES,,,
C2297,"Q_CAP_C0402-22UF,4V,20%,X6S,CH622KMEB02",22UF,20%,C0402_H32,4641.59,9817.66,0.000,YES,,,
C2298,"Q_CAP_C0402-22UF,4V,20%,X6S,CH622KMEB02",22UF,20%,C0402_H32,4272.71,9817.66,180.000,YES,,,
C2300,"Q_CAP_C0402-22UF,4V,20%,X6S,CH622KMEB02",22UF,20%,C0402_H32,4122.71,9817.66,180.000,YES,,,
C2301,"Q_CAP_C0402-22UF,4V,20%,X6S,CH622KMEB02",22UF,20%,C0402_H32,4257.71,9852.66,0.000,YES,,,
C2302,"Q_CAP_C0402-22UF,4V,20%,X6S,CH622KMEB02",22UF,20%,C0402_H32,4566.59,9877.66,0.000,YES,,,
C2303,"Q_CAP_C0402-22UF,4V,20%,X6S,CH622KMEB02",22UF,20%,C0402_H32,3972.71,9817.66,180.000,YES,,,
C2304,"Q_CAP_C0402-22UF,4V,20%,X6S,CH622KMEB02",22UF,20%,C0402_H32,4271.71,9700.88,0.000,YES,,,
C2306,"Q_CAP_C0402-22UF,4V,20%,X6S,CH622KMEB02",22UF,20%,C0402_H32,4587.71,9664.88,0.000,YES,,,
C2307,"Q_CAP_C0402-22UF,4V,20%,X6S,CH622KMEB02",22UF,20%,C0402_H32,4566.59,9817.66,0.000,YES,,,
C2308,"Q_CAP_C0402-22UF,4V,20%,X6S,CH622KMEB02",22UF,20%,C0402_H32,4217.71,9664.88,180.000,YES,,,
C2309,"Q_CAP_C0402-22UF,4V,20%,X6S,CH622KMEB02",22UF,20%,C0402_H32,4142.71,9664.88,0.000,YES,,,
C2310,"Q_CAP_C0402-22UF,4V,20%,X6S,CH622KMEB02",22UF,20%,C0402_H32,3878.35,9782.66,180.000,YES,,,
C2312,"Q_CAP_C0402-22UF,4V,20%,X6S,CH622KMEB02",22UF,20%,C0402_H32,4866.59,9877.66,0.000,YES,,,
C2313,"Q_CAP_C0402-22UF,4V,20%,X6S,CH622KMEB02",22UF,20%,C0402_H32,4936.59,9817.66,0.000,YES,,,
C2314,"Q_CAP_C0402-22UF,4V,20%,X6S,CH622KMEB02",22UF,20%,C0402_H32,4216.59,9782.66,180.000,YES,,,
C2315,"Q_CAP_C0402-22UF,4V,20%,X6S,CH622KMEB02",22UF,20%,C0402_H32,4807.35,9782.66,0.000,YES,,,
C2316,"Q_CAP_C0402-22UF,4V,20%,X6S,CH622KMEB02",22UF,20%,C0402_H32,4476.59,9852.66,0.000,YES,,,
C2317,"Q_CAP_C0402-1UF,25V,10%,X6S,CH5104KEB02",1UF,10%,C0402,4906.82,2015.16,180.000,NO,,,
C2318,"Q_CAP_C0402-22UF,4V,20%,X6S,CH622KMEB02",22UF,20%,C0402_H32,4810.35,9664.89,0.000,YES,,,
C2319,"Q_CAP_C0402-22UF,4V,20%,X6S,CH622KMEB02",22UF,20%,C0402_H32,4141.59,9782.66,0.000,YES,,,
C2320,"Q_CAP_C0402-22UF,4V,20%,X6S,CH622KMEB02",22UF,20%,C0402_H32,4866.59,9817.66,0.000,YES,,,
C2321,"Q_CAP_C0402-22UF,4V,20%,X6S,CH622KMEB02",22UF,20%,C0402_H32,4401.59,9687.66,90.000,YES,,,
C2322,"Q_CAP_C0402-22UF,4V,20%,X6S,CH622KMEB02",22UF,20%,C0402_H32,4326.59,9852.66,0.000,YES,,,
C2324,"Q_CAP_C0402-22UF,4V,20%,X6S,CH622KMEB02",22UF,20%,C0402_H32,4532.71,9699.88,180.000,YES,,,
C2325,"Q_CAP_C0402-22UF,4V,20%,X6S,CH622KMEB02",22UF,20%,C0402_H32,4791.59,9817.66,0.000,YES,,,
C2326,"Q_CAP_C0402-22UF,4V,20%,X6S,CH622KMEB02",22UF,20%,C0402_H32,3991.35,9782.66,180.000,YES,,,
C2327,"Q_CAP_C0402-22UF,4V,20%,X6S,CH622KMEB02",22UF,20%,C0402_H32,4192.45,9877.61,180.000,YES,,,
C2328,"Q_CAP_C0402-10UF,6.3V,20%,X6S,CH6101MEB01",10UF,20%,C0402,11153.94,16243.27,270.000,NO,,,
C2329,"Q_CAP_0402-0.1UF,25V,10%,X7R,CH4104K1B00",0.1UF,10%,C0402,11346.49,16550.45,90.000,YES,,,
C2330,"Q_CAP_C0402-22UF,4V,20%,X6S,CH622KMEB02",22UF,20%,C0402_H32,4662.71,9664.88,180.000,YES,,,
C2331,"Q_CAP_C0402-22UF,4V,20%,X6S,CH622KMEB02",22UF,20%,C0402_H32,4586.59,9782.66,0.000,YES,,,
C2332,"Q_CAP_C0402-22UF,4V,20%,X6S,CH622KMEB02",22UF,20%,C0402_H32,4401.59,9837.66,90.000,YES,,,
C2333,"Q_CAP_C0402-22UF,4V,20%,X6S,CH622KMEB02",22UF,20%,C0402_H32,4920.35,9782.66,0.000,YES,,,
C2334,"Q_CAP_0402-0.1UF,25V,10%,X7R,CH4104K1B00",0.1UF,10%,C0402,11184.02,16554.78,90.000,YES,,,
C2335,"Q_CAP_C0402-22UF,4V,20%,X6S,CH622KMEB02",22UF,20%,C0402_H32,4122.71,9877.66,180.000,YES,,,
C2336,"Q_CAP_C0402-22UF,4V,20%,X6S,CH622KMEB02",22UF,20%,C0402_H32,4872.71,9679.88,270.000,YES,,,
C2337,"Q_CAP_C0402-22UF,4V,20%,X6S,CH622KMEB02",22UF,20%,C0402_H32,4656.59,9782.66,180.000,YES,,,
C2338,"Q_CAP_C0402-22UF,4V,20%,X6S,CH622KMEB02",22UF,20%,C0402_H32,4491.59,9817.66,0.000,YES,,,
C2339,"Q_CAP_0402-0.1UF,25V,10%,X7R,CH4104K1B00",0.1UF,10%,C0402,11232.28,16549.23,90.000,YES,,,
C2340,"Q_CAP_C0402-22UF,4V,20%,X6S,CH622KMEB02",22UF,20%,C0402_H32,4336.59,9702.66,240.000,YES,,,
C2341,"Q_CAP_C0402-22UF,4V,20%,X6S,CH622KMEB02",22UF,20%,C0402_H32,4401.59,9762.66,90.000,YES,,,
C2342,"Q_CAP_C0402-22UF,4V,20%,X6S,CH622KMEB02",22UF,20%,C0402_H32,4466.59,9702.66,300.000,YES,,,
C2343,"Q_CAP_C0402-22UF,4V,20%,X6S,CH622KMEB02",22UF,20%,C0402_H32,4047.71,9817.66,180.000,YES,,,
C2344,"Q_CAP_0402-0.1UF,25V,10%,X7R,CH4104K1B00",0.1UF,10%,C0402,14838.20,1272.58,270.000,NO,,,
C2345,"Q_CAP_C0402-22UF,4V,20%,X6S,CH622KMEB02",22UF,20%,C0402_H32,4716.59,9817.66,0.000,YES,,,
C2346,"Q_CAP_C0402-22UF,4V,20%,X6S,CH622KMEB02",22UF,20%,C0402_H32,3992.71,9664.88,180.000,YES,,,
C2347,"Q_CAP_C0402-22UF,4V,20%,X6S,CH622KMEB02",22UF,20%,C0402_H32,4337.71,9799.88,120.000,YES,,,
C2348,"Q_CAP_C0402-22UF,4V,20%,X6S,CH622KMEB02",22UF,20%,C0402_H32,4052.71,9877.66,180.000,YES,,,
C2350,"Q_CAP_C0402-22UF,4V,20%,X6S,CH622KMEB02",22UF,20%,C0402_H32,4101.59,10567.66,0.000,YES,,,
C2351,"Q_CAP_C0402-22UF,4V,20%,X6S,CH622KMEB02",22UF,20%,C0402_H32,4156.59,10602.66,0.000,YES,,,
C2352,"Q_CAP_C0402-22UF,4V,20%,X6S,CH622KMEB02",22UF,20%,C0402_H32,4564.30,10532.66,0.000,YES,,,
C2353,"Q_CAP_C0402-22UF,4V,20%,X6S,CH622KMEB02",22UF,20%,C0402_H32,4786.59,10602.66,180.000,YES,,,
C2354,"Q_CAP_C0402-22UF,4V,20%,X6S,CH622KMEB02",22UF,20%,C0402_H32,4227.71,10719.88,180.000,YES,,,
C2356,"Q_CAP_C0402-22UF,4V,20%,X6S,CH622KMEB02",22UF,20%,C0402_H32,4672.71,10719.88,180.000,YES,,,
C2357,"Q_CAP_C0402-22UF,4V,20%,X6S,CH622KMEB02",22UF,20%,C0402_H32,4287.71,10684.88,0.000,YES,,,
C2358,"Q_CAP_C0402-22UF,4V,20%,X6S,CH622KMEB02",22UF,20%,C0402_H32,3931.59,10602.66,0.000,YES,,,
C2359,"Q_CAP_C0402-22UF,4V,20%,X6S,CH622KMEB02",22UF,20%,C0402_H32,4341.59,10532.66,0.000,YES,,,
C2360,"Q_CAP_C0402-22UF,4V,20%,X6S,CH622KMEB02",22UF,20%,C0402_H32,3971.59,10532.66,0.000,YES,,,
C2362,"Q_CAP_C0402-22UF,4V,20%,X6S,CH622KMEB02",22UF,20%,C0402_H32,4671.59,10602.66,180.000,YES,,,
C2363,"Q_CAP_C0402-22UF,4V,20%,X6S,CH622KMEB02",22UF,20%,C0402_H32,4888.71,10602.88,180.000,YES,,,
C2364,"Q_CAP_C0402-22UF,4V,20%,X6S,CH622KMEB02",22UF,20%,C0402_H32,4876.59,10567.66,0.000,YES,,,
C2365,"Q_CAP_C0402-22UF,4V,20%,X6S,CH622KMEB02",22UF,20%,C0402_H32,4601.59,10602.66,0.000,YES,,,
C2366,"Q_CAP_C0402-22UF,4V,20%,X6S,CH622KMEB02",22UF,20%,C0402_H32,4026.59,10567.66,0.000,YES,,,
C2368,"Q_CAP_C0402-22UF,4V,20%,X6S,CH622KMEB02",22UF,20%,C0402_H32,4711.59,10531.45,0.000,YES,,,
C2369,"Q_CAP_C0402-22UF,4V,20%,X6S,CH622KMEB02",22UF,20%,C0402_H32,4597.71,10719.88,0.000,YES,,,
C2370,"Q_CAP_C0402-22UF,4V,20%,X6S,CH622KMEB02",22UF,20%,C0402_H32,4801.59,10567.66,0.000,YES,,,
C2371,"Q_CAP_C0402-22UF,4V,20%,X6S,CH622KMEB02",22UF,20%,C0402_H32,4542.71,10684.88,180.000,YES,,,
C2372,"Q_CAP_C0402-22UF,4V,20%,X6S,CH622KMEB02",22UF,20%,C0402_H32,4822.71,10719.88,0.000,YES,,,
C2374,"Q_CAP_C0402-22UF,4V,20%,X6S,CH622KMEB02",22UF,20%,C0402_H32,4246.59,10567.66,0.000,YES,,,
C2375,"Q_CAP_C0402-22UF,4V,20%,X6S,CH622KMEB02",22UF,20%,C0402_H32,4656.59,10567.66,0.000,YES,,,
C2376,"Q_CAP_C0402-22UF,4V,20%,X6S,CH622KMEB02",22UF,20%,C0402_H32,4939.71,10584.88,60.000,YES,,,
C2377,"Q_CAP_C0402-22UF,4V,20%,X6S,CH622KMEB02",22UF,20%,C0402_H32,4411.59,10532.66,270.000,YES,,,
C2378,"Q_CAP_C0402-22UF,4V,20%,X6S,CH622KMEB02",22UF,20%,C0402_H32,3951.59,10567.66,0.000,YES,,,
C2380,"Q_CAP_C0402-22UF,4V,20%,X6S,CH622KMEB02",22UF,20%,C0402_H32,4266.59,10532.66,0.000,YES,,,
C2381,"Q_CAP_C0402-22UF,4V,20%,X6S,CH622KMEB02",22UF,20%,C0402_H32,4781.59,10531.45,0.000,YES,,,
C2382,"Q_CAP_C0402-22UF,4V,20%,X6S,CH622KMEB02",22UF,20%,C0402_H32,3942.71,10704.88,90.000,YES,,,
C2383,"Q_CAP_C0402-22UF,4V,20%,X6S,CH622KMEB02",22UF,20%,C0402_H32,4176.59,10567.66,0.000,YES,,,
C2386,"Q_CAP_C0402-22UF,4V,20%,X6S,CH622KMEB02",22UF,20%,C0402_H32,4880.71,10702.88,90.000,YES,,,
C2387,"Q_CAP_C0402-22UF,4V,20%,X6S,CH622KMEB02",22UF,20%,C0402_H32,4506.59,10567.66,0.000,YES,,,
C2388,"Q_CAP_C0402-22UF,4V,20%,X6S,CH622KMEB02",22UF,20%,C0402_H32,4489.49,10532.66,0.000,YES,,,
C2389,"Q_CAP_C0402-22UF,4V,20%,X6S,CH622KMEB02",22UF,20%,C0402_H32,4002.71,10719.88,180.000,YES,,,
C2392,"Q_CAP_C0402-22UF,4V,20%,X6S,CH622KMEB02",22UF,20%,C0402_H32,4639.10,10532.66,0.000,YES,,,
C2393,"Q_CAP_C0402-22UF,4V,20%,X6S,CH622KMEB02",22UF,20%,C0402_H32,4046.59,10602.66,0.000,YES,,,
C2394,"Q_CAP_C0402-22UF,4V,20%,X6S,CH622KMEB02",22UF,20%,C0402_H32,4116.59,10532.66,0.000,YES,,,
C2395,"Q_CAP_C0402-22UF,4V,20%,X6S,CH622KMEB02",22UF,20%,C0402_H32,4157.71,10719.88,0.000,YES,,,
C2397,"Q_CAP_C0402-22UF,4V,20%,X6S,CH622KMEB02",22UF,20%,C0402_H32,4041.59,10532.66,0.000,YES,,,
C2398,"Q_CAP_C0402-22UF,4V,20%,X6S,CH622KMEB02",22UF,20%,C0402_H32,4726.59,10567.66,0.000,YES,,,
C2399,"Q_CAP_C0402-22UF,4V,20%,X6S,CH622KMEB02",22UF,20%,C0402_H32,4931.59,10531.45,0.000,YES,,,
C2400,"Q_CAP_C0402-22UF,4V,20%,X6S,CH622KMEB02",22UF,20%,C0402_H32,4581.59,10567.66,0.000,YES,,,
C2402,"Q_CAP_C0402-22UF,4V,20%,X6S,CH622KMEB02",22UF,20%,C0402_H32,4226.59,10602.66,180.000,YES,,,
C2403,"Q_CAP_C0402-22UF,4V,20%,X6S,CH622KMEB02",22UF,20%,C0402_H32,4191.59,10532.66,0.000,YES,,,
C2404,"Q_CAP_C0402-22UF,4V,20%,X6S,CH622KMEB02",22UF,20%,C0402_H32,4321.59,10567.66,0.000,YES,,,
C2405,"Q_CAP_C0402-22UF,4V,20%,X6S,CH622KMEB02",22UF,20%,C0402_H32,4856.59,10531.45,0.000,YES,,,
C2407,"Q_CAP_C0402-22UF,4V,20%,X6S,CH622KMEB02",22UF,20%,C0402_H32,4555.35,10147.45,180.000,YES,,,
C2408,"Q_CAP_C0402-22UF,4V,20%,X6S,CH622KMEB02",22UF,20%,C0402_H32,4239.21,10079.23,270.000,YES,,,
C2409,"Q_CAP_C0402-22UF,4V,20%,X6S,CH622KMEB02",22UF,20%,C0402_H32,4024.21,9930.48,60.000,YES,,,
C2410,"Q_CAP_C0402-22UF,4V,20%,X6S,CH622KMEB02",22UF,20%,C0402_H32,4314.01,10079.23,90.000,NO,,,
C2411,"Q_CAP_C0402-22UF,4V,20%,X6S,CH622KMEB02",22UF,20%,C0402_H32,4106.59,9912.66,0.000,YES,,,
C2412,"Q_CAP_C0402-22UF,4V,20%,X6S,CH622KMEB02",22UF,20%,C0402_H32,4239.21,10079.23,90.000,NO,,,
C2413,"Q_CAP_C0402-22UF,4V,20%,X6S,CH622KMEB02",22UF,20%,C0402_H32,4551.59,9912.66,0.000,YES,,,
C2414,"Q_CAP_C0402-22UF,4V,20%,X6S,CH622KMEB02",22UF,20%,C0402_H32,4641.59,9877.66,0.000,YES,,,
C2415,"Q_CAP_C0402-22UF,4V,20%,X6S,CH622KMEB02",22UF,20%,C0402_H32,4621.59,9977.66,0.000,YES,,,
C2416,"Q_CAP_C0402-22UF,4V,20%,X6S,CH622KMEB02",22UF,20%,C0402_H32,4081.59,10342.66,180.000,YES,,,
C2417,"Q_CAP_C0402-22UF,4V,20%,X6S,CH622KMEB02",22UF,20%,C0402_H32,4276.61,10079.23,270.000,YES,,,
C2418,"Q_CAP_C0402-22UF,4V,20%,X6S,CH622KMEB02",22UF,20%,C0402_H32,4538.42,10079.23,270.000,YES,,,
C2419,"Q_CAP_C0402-22UF,4V,20%,X6S,CH622KMEB02",22UF,20%,C0402_H32,4400.84,10017.66,180.000,YES,,,
C2420,"Q_CAP_C0402-22UF,4V,20%,X6S,CH622KMEB02",22UF,20%,C0402_H32,4641.56,10210.84,0.000,YES,,,
C2421,"Q_CAP_C0402-22UF,4V,20%,X6S,CH622KMEB02",22UF,20%,C0402_H32,4025.71,10019.88,300.000,YES,,,
C2422,"Q_CAP_C0402-22UF,4V,20%,X6S,CH622KMEB02",22UF,20%,C0402_H32,4641.56,10136.04,180.000,NO,,,
C2423,"Q_CAP_C0402-22UF,4V,20%,X6S,CH622KMEB02",22UF,20%,C0402_H32,4555.35,10147.45,0.000,NO,,,
C2424,"Q_CAP_C0402-22UF,4V,20%,X6S,CH622KMEB02",22UF,20%,C0402_H32,4641.56,10061.23,0.000,YES,,,
C2425,"Q_CAP_C0402-22UF,4V,20%,X6S,CH622KMEB02",22UF,20%,C0402_H32,4936.59,10190.17,0.000,YES,,,
C2426,"Q_CAP_C0402-22UF,4V,20%,X6S,CH622KMEB02",22UF,20%,C0402_H32,4551.59,9977.66,0.000,YES,,,
C2427,"Q_CAP_C0402-22UF,4V,20%,X6S,CH622KMEB02",22UF,20%,C0402_H32,4364.45,10147.45,0.000,NO,,,
C2428,"Q_CAP_C0402-22UF,4V,20%,X6S,CH622KMEB02",22UF,20%,C0402_H32,4555.35,10188.79,0.000,NO,,,
C2429,"Q_CAP_C0402-22UF,4V,20%,X6S,CH622KMEB02",22UF,20%,C0402_H32,4866.59,9942.66,0.000,YES,,,
C2430,"Q_CAP_C0402-22UF,4V,20%,X6S,CH622KMEB02",22UF,20%,C0402_H32,4641.56,10098.64,0.000,YES,,,
C2431,"Q_CAP_C0402-22UF,4V,20%,X6S,CH622KMEB02",22UF,20%,C0402_H32,4351.41,10079.23,270.000,YES,,,
C2432,"Q_CAP_C0402-22UF,4V,20%,X6S,CH622KMEB02",22UF,20%,C0402_H32,4866.59,10225.60,0.000,YES,,,
C2433,"Q_CAP_C0402-22UF,4V,20%,X6S,CH622KMEB02",22UF,20%,C0402_H32,4364.41,10147.45,180.000,YES,,,
C2434,"Q_CAP_C0402-22UF,4V,20%,X6S,CH622KMEB02",22UF,20%,C0402_H32,4538.42,10079.23,90.000,NO,,,
C2435,"Q_CAP_C0402-22UF,4V,20%,X6S,CH622KMEB02",22UF,20%,C0402_H32,4911.08,10312.45,0.000,YES,,,
C2436,"Q_CAP_C0402-22UF,4V,20%,X6S,CH622KMEB02",22UF,20%,C0402_H32,4181.59,9977.66,0.000,YES,,,
C2437,"Q_CAP_C0402-22UF,4V,20%,X6S,CH622KMEB02",22UF,20%,C0402_H32,4641.56,10285.64,0.000,YES,,,
C2438,"Q_CAP_C0402-22UF,4V,20%,X6S,CH622KMEB02",22UF,20%,C0402_H32,4256.59,9912.66,0.000,YES,,,
C2439,"Q_CAP_C0402-22UF,4V,20%,X6S,CH622KMEB02",22UF,20%,C0402_H32,4463.62,10079.23,90.000,NO,,,
C2440,"Q_CAP_C0402-22UF,4V,20%,X6S,CH622KMEB02",22UF,20%,C0402_H32,4011.59,10282.66,0.000,YES,,,
C2441,"Q_CAP_C0402-22UF,4V,20%,X6S,CH622KMEB02",22UF,20%,C0402_H32,4555.35,10188.79,180.000,YES,,,
C2442,"Q_CAP_C0402-22UF,4V,20%,X6S,CH622KMEB02",22UF,20%,C0402_H32,4452.99,10188.79,0.000,NO,,,
C2443,"Q_CAP_C0402-22UF,4V,20%,X6S,CH622KMEB02",22UF,20%,C0402_H32,4936.59,9877.66,0.000,YES,,,
C2444,"Q_CAP_C0402-22UF,4V,20%,X6S,CH622KMEB02",22UF,20%,C0402_H32,4896.59,10347.45,0.000,YES,,,
C2445,"Q_CAP_C0402-22UF,4V,20%,X6S,CH622KMEB02",22UF,20%,C0402_H32,4276.61,10079.23,90.000,NO,,,
C2446,"Q_CAP_C0402-22UF,4V,20%,X6S,CH622KMEB02",22UF,20%,C0402_H32,4426.22,10079.23,90.000,NO,,,
C2447,"Q_CAP_C0402-22UF,4V,20%,X6S,CH622KMEB02",22UF,20%,C0402_H32,4936.59,10072.66,0.000,YES,,,
C2448,"Q_CAP_C0402-22UF,4V,20%,X6S,CH622KMEB02",22UF,20%,C0402_H32,4181.59,9912.66,0.000,YES,,,
C2449,"Q_CAP_C0402-22UF,4V,20%,X6S,CH622KMEB02",22UF,20%,C0402_H32,4791.59,9877.66,0.000,YES,,,
C2450,"Q_CAP_C0402-22UF,4V,20%,X6S,CH622KMEB02",22UF,20%,C0402_H32,4452.99,10147.45,0.000,NO,,,
C2451,"Q_CAP_C0402-22UF,4V,20%,X6S,CH622KMEB02",22UF,20%,C0402_H32,4621.59,9912.66,0.000,YES,,,
C2452,"Q_CAP_C0402-22UF,4V,20%,X6S,CH622KMEB02",22UF,20%,C0402_H32,4936.59,10007.66,0.000,YES,,,
C2453,"Q_CAP_C0402-22UF,4V,20%,X6S,CH622KMEB02",22UF,20%,C0402_H32,4086.59,10072.66,180.000,YES,,,
C2454,"Q_CAP_C0402-22UF,4V,20%,X6S,CH622KMEB02",22UF,20%,C0402_H32,4866.59,10007.66,0.000,YES,,,
C2455,"Q_CAP_C0402-22UF,4V,20%,X6S,CH622KMEB02",22UF,20%,C0402_H32,4106.59,9977.66,0.000,YES,,,
C2456,"Q_CAP_C0402-22UF,4V,20%,X6S,CH622KMEB02",22UF,20%,C0402_H32,4837.07,10312.45,0.000,YES,,,
C2457,"Q_CAP_C0402-22UF,4V,20%,X6S,CH622KMEB02",22UF,20%,C0402_H32,4791.59,10072.66,0.000,YES,,,
C2458,"Q_CAP_C0402-22UF,4V,20%,X6S,CH622KMEB02",22UF,20%,C0402_H32,4575.82,10079.23,270.000,YES,,,
C2459,"Q_CAP_C0402-22UF,4V,20%,X6S,CH622KMEB02",22UF,20%,C0402_H32,4326.59,9912.66,0.000,YES,,,
C2460,"Q_CAP_C0402-22UF,4V,20%,X6S,CH622KMEB02",22UF,20%,C0402_H32,4388.82,10079.23,90.000,NO,,,
C2461,"Q_CAP_C0402-22UF,4V,20%,X6S,CH622KMEB02",22UF,20%,C0402_H32,4866.59,10190.17,0.000,YES,,,
C2462,"Q_CAP_C0402-22UF,4V,20%,X6S,CH622KMEB02",22UF,20%,C0402_H32,4936.59,10225.60,0.000,YES,,,
C2463,"Q_CAP_C0402-22UF,4V,20%,X6S,CH622KMEB02",22UF,20%,C0402_H32,4641.56,10248.24,0.000,YES,,,
C2464,"Q_CAP_C0402-22UF,4V,20%,X6S,CH622KMEB02",22UF,20%,C0402_H32,4641.56,10136.04,0.000,YES,,,
C2465,"Q_CAP_C0402-22UF,4V,20%,X6S,CH622KMEB02",22UF,20%,C0402_H32,4011.59,10342.66,0.000,YES,,,
C2466,"Q_CAP_C0402-22UF,4V,20%,X6S,CH622KMEB02",22UF,20%,C0402_H32,4326.59,9977.66,0.000,YES,,,
C2467,"Q_CAP_C0402-22UF,4V,20%,X6S,CH622KMEB02",22UF,20%,C0402_H32,4081.59,10282.66,180.000,YES,,,
C2468,"Q_CAP_C0402-22UF,4V,20%,X6S,CH622KMEB02",22UF,20%,C0402_H32,4791.59,9942.66,0.000,YES,,,
C2469,"Q_CAP_C0402-22UF,4V,20%,X6S,CH622KMEB02",22UF,20%,C0402_H32,4936.59,10154.74,0.000,YES,,,
C2470,"Q_CAP_C0402-22UF,4V,20%,X6S,CH622KMEB02",22UF,20%,C0402_H32,4011.59,10072.66,0.000,YES,,,
C2471,"Q_CAP_C0402-22UF,4V,20%,X6S,CH622KMEB02",22UF,20%,C0402_H32,4936.59,9942.66,0.000,YES,,,
C2472,"Q_CAP_C0402-22UF,4V,20%,X6S,CH622KMEB02",22UF,20%,C0402_H32,4791.59,10007.66,0.000,YES,,,
C2473,"Q_CAP_C0402-22UF,4V,20%,X6S,CH622KMEB02",22UF,20%,C0402_H32,4388.82,10079.23,270.000,YES,,,
C2474,"Q_CAP_C0402-22UF,4V,20%,X6S,CH622KMEB02",22UF,20%,C0402_H32,4031.59,10107.66,180.000,YES,,,
C2475,"Q_CAP_C0402-22UF,4V,20%,X6S,CH622KMEB02",22UF,20%,C0402_H32,4351.41,10079.23,90.000,NO,,,
C2476,"Q_CAP_C0402-22UF,4V,20%,X6S,CH622KMEB02",22UF,20%,C0402_H32,4641.56,10173.44,0.000,YES,,,
C2477,"Q_CAP_C0402-22UF,4V,20%,X6S,CH622KMEB02",22UF,20%,C0402_H32,4265.98,10230.13,180.000,YES,,,
C2478,"Q_CAP_C0402-22UF,4V,20%,X6S,CH622KMEB02",22UF,20%,C0402_H32,4265.98,10188.79,0.000,NO,,,
C2479,"Q_CAP_C0402-22UF,4V,20%,X6S,CH622KMEB02",22UF,20%,C0402_H32,4171.66,10173.44,180.000,YES,,,
C2480,"Q_CAP_C0402-22UF,4V,20%,X6S,CH622KMEB02",22UF,20%,C0402_H32,4786.59,10472.66,0.000,YES,,,
C2481,"Q_CAP_C0402-22UF,4V,20%,X6S,CH622KMEB02",22UF,20%,C0402_H32,4711.59,10472.66,0.000,YES,,,
C2482,"Q_CAP_C0402-22UF,4V,20%,X6S,CH622KMEB02",22UF,20%,C0402_H32,4800.97,10372.66,0.000,YES,,,
C2483,"Q_CAP_C0402-22UF,4V,20%,X6S,CH622KMEB02",22UF,20%,C0402_H32,4856.59,10407.66,0.000,YES,,,
C2484,"Q_CAP_C0402-22UF,4V,20%,X6S,CH622KMEB02",22UF,20%,C0402_H32,4030.66,10190.17,180.000,YES,,,
C2485,"Q_CAP_C0402-22UF,4V,20%,X6S,CH622KMEB02",22UF,20%,C0402_H32,4538.47,10305.04,270.000,NO,,,
C2486,"Q_CAP_C0402-22UF,4V,20%,X6S,CH622KMEB02",22UF,20%,C0402_H32,4364.41,10188.79,180.000,YES,,,
C2487,"Q_CAP_C0402-22UF,4V,20%,X6S,CH622KMEB02",22UF,20%,C0402_H32,4641.56,10323.04,180.000,NO,,,
C2488,"Q_CAP_C0402-22UF,4V,20%,X6S,CH622KMEB02",22UF,20%,C0402_H32,4555.35,10230.13,180.000,YES,,,
C2489,"Q_CAP_C0402-22UF,4V,20%,X6S,CH622KMEB02",22UF,20%,C0402_H32,4171.66,10323.04,0.000,YES,,,
C2490,"Q_CAP_C0402-22UF,4V,20%,X6S,CH622KMEB02",22UF,20%,C0402_H32,4116.59,10407.66,0.000,YES,,,
C2491,"Q_CAP_C0402-22UF,4V,20%,X6S,CH622KMEB02",22UF,20%,C0402_H32,4463.66,10305.04,90.000,YES,,,
C2492,"Q_CAP_C0402-22UF,4V,20%,X6S,CH622KMEB02",22UF,20%,C0402_H32,4641.56,10323.04,0.000,YES,,,
C2493,"Q_CAP_C0402-22UF,4V,20%,X6S,CH622KMEB02",22UF,20%,C0402_H32,3877.71,10374.88,0.000,YES,,,
C2494,"Q_CAP_C0402-22UF,4V,20%,X6S,CH622KMEB02",22UF,20%,C0402_H32,4276.66,10305.04,90.000,YES,,,
C2495,"Q_CAP_C0402-22UF,4V,20%,X6S,CH622KMEB02",22UF,20%,C0402_H32,4041.59,10407.66,0.000,YES,,,
C2496,"Q_CAP_C0402-22UF,4V,20%,X6S,CH622KMEB02",22UF,20%,C0402_H32,4561.59,10407.66,0.000,YES,,,
C2497,"Q_CAP_C0402-22UF,4V,20%,X6S,CH622KMEB02",22UF,20%,C0402_H32,4538.47,10305.04,90.000,YES,,,
C2498,"Q_CAP_C0402-22UF,4V,20%,X6S,CH622KMEB02",22UF,20%,C0402_H32,3956.59,10107.66,180.000,YES,,,
C2499,"Q_CAP_C0402-22UF,4V,20%,X6S,CH622KMEB02",22UF,20%,C0402_H32,4426.26,10305.04,270.000,NO,,,
C2500,"Q_CAP_C0402-22UF,4V,20%,X6S,CH622KMEB02",22UF,20%,C0402_H32,4276.66,10305.04,270.000,NO,,,
C2501,"Q_CAP_C0402-22UF,4V,20%,X6S,CH622KMEB02",22UF,20%,C0402_H32,4501.07,10305.04,270.000,NO,,,
C2502,"Q_CAP_C0402-22UF,4V,20%,X6S,CH622KMEB02",22UF,20%,C0402_H32,4364.41,10230.13,180.000,YES,,,
C2503,"Q_CAP_C0402-22UF,4V,20%,X6S,CH622KMEB02",22UF,20%,C0402_H32,4364.41,10188.79,0.000,NO,,,
C2504,"Q_CAP_C0402-22UF,4V,20%,X6S,CH622KMEB02",22UF,20%,C0402_H32,4351.46,10305.04,270.000,NO,,,
C2505,"Q_CAP_C0402-22UF,4V,20%,X6S,CH622KMEB02",22UF,20%,C0402_H32,4452.99,10230.13,180.000,YES,,,
C2506,"Q_CAP_C0402-22UF,4V,20%,X6S,CH622KMEB02",22UF,20%,C0402_H32,4501.07,10305.04,90.000,YES,,,
C2507,"Q_CAP_C0402-22UF,4V,20%,X6S,CH622KMEB02",22UF,20%,C0402_H32,3955.86,10190.17,180.000,YES,,,
C2508,"Q_CAP_C0402-22UF,4V,20%,X6S,CH622KMEB02",22UF,20%,C0402_H32,4575.87,10305.04,270.000,NO,,,
C2509,"Q_CAP_C0402-22UF,4V,20%,X6S,CH622KMEB02",22UF,20%,C0402_H32,4171.66,10285.64,180.000,YES,,,
C2510,"Q_CAP_C0402-22UF,4V,20%,X6S,CH622KMEB02",22UF,20%,C0402_H32,4426.26,10305.04,90.000,YES,,,
C2511,"Q_CAP_C0402-22UF,4V,20%,X6S,CH622KMEB02",22UF,20%,C0402_H32,4636.59,10472.66,0.000,YES,,,
C2512,"Q_CAP_C0402-10UF,6.3V,20%,X6S,CH6101MEB01",10UF,20%,C0402,13658.01,10532.65,0.000,YES,,,
C2513,"Q_CAP_C0402-22UF,4V,20%,X6S,CH622KMEB02",22UF,20%,C0402_H32,13661.77,9817.65,180.000,YES,,,
C2514,"Q_CAP_C0402-22UF,4V,20%,X6S,CH622KMEB02",22UF,20%,C0402_H32,13736.77,9877.65,180.000,YES,,,
C2515,"Q_CAP_C0402-10UF,6.3V,20%,X6S,CH6101MEB01",10UF,20%,C0402,13643.01,10497.65,0.000,YES,,,
C2516,"Q_CAP_C0402-22UF,4V,20%,X6S,CH622KMEB02",22UF,20%,C0402_H32,13661.77,9942.65,180.000,YES,,,
C2517,"Q_CAP_C0402-22UF,4V,20%,X6S,CH622KMEB02",22UF,20%,C0402_H32,14027.40,10147.44,180.000,YES,,,
C2518,"Q_CAP_C0402-22UF,4V,20%,X6S,CH622KMEB02",22UF,20%,C0402_H32,13731.77,9942.65,180.000,YES,,,
C2520,"Q_CAP_C0402-22UF,4V,20%,X6S,CH622KMEB02",22UF,20%,C0402_H32,13643.52,10037.65,0.000,YES,,,
C2521,"Q_CAP_C0402-22UF,4V,20%,X6S,CH622KMEB02",22UF,20%,C0402_H32,13661.77,9877.65,180.000,YES,,,
C2522,"Q_CAP_C0402-22UF,4V,20%,X6S,CH622KMEB02",22UF,20%,C0402_H32,13735.77,10002.65,180.000,YES,,,
C2523,"Q_CAP_C0402-22UF,4V,20%,X6S,CH622KMEB02",22UF,20%,C0402_H32,13661.77,10002.65,180.000,YES,,,
C2524,"Q_CAP_C0402-22UF,4V,20%,X6S,CH622KMEB02",22UF,20%,C0402_H32,13663.01,10072.65,180.000,YES,,,
C2525,"Q_CAP_C0402-22UF,4V,20%,X6S,CH622KMEB02",22UF,20%,C0402_H32,14027.40,10147.44,0.000,NO,,,
C2526,"Q_CAP_C0402-22UF,4V,20%,X6S,CH622KMEB02",22UF,20%,C0402_H32,13933.08,10061.22,180.000,YES,,,
C2527,"Q_CAP_C0402-22UF,4V,20%,X6S,CH622KMEB02",22UF,20%,C0402_H32,14214.41,10188.78,0.000,NO,,,
C2528,"Q_CAP_C0402-22UF,4V,20%,X6S,CH622KMEB02",22UF,20%,C0402_H32,14337.24,10079.22,90.000,NO,,,
C2529,"Q_CAP_C0402-22UF,4V,20%,X6S,CH622KMEB02",22UF,20%,C0402_H32,14583.01,10277.44,0.000,YES,,,
C2530,"Q_CAP_C0402-22UF,4V,20%,X6S,CH622KMEB02",22UF,20%,C0402_H32,14628.01,10154.73,0.000,YES,,,
C2531,"Q_CAP_C0402-22UF,4V,20%,X6S,CH622KMEB02",22UF,20%,C0402_H32,14402.98,10248.23,0.000,YES,,,
C2532,"Q_CAP_C0402-22UF,4V,20%,X6S,CH622KMEB02",22UF,20%,C0402_H32,14313.01,9977.65,0.000,YES,,,
C2533,"Q_CAP_C0402-22UF,4V,20%,X6S,CH622KMEB02",22UF,20%,C0402_H32,13843.01,10342.65,180.000,YES,,,
C2534,"Q_CAP_C0402-22UF,4V,20%,X6S,CH622KMEB02",22UF,20%,C0402_H32,14698.01,10007.65,0.000,YES,,,
C2535,"Q_CAP_C0402-22UF,4V,20%,X6S,CH622KMEB02",22UF,20%,C0402_H32,14402.98,10061.22,180.000,NO,,,
C2536,"Q_CAP_C0402-22UF,4V,20%,X6S,CH622KMEB02",22UF,20%,C0402_H32,14238.01,9912.65,0.000,YES,,,
C2537,"Q_CAP_C0402-22UF,4V,20%,X6S,CH622KMEB02",22UF,20%,C0402_H32,14552.20,10190.16,0.000,YES,,,
C2538,"Q_CAP_C0402-22UF,4V,20%,X6S,CH622KMEB02",22UF,20%,C0402_H32,14658.01,10347.44,0.000,YES,,,
C2539,"Q_CAP_C0402-22UF,4V,20%,X6S,CH622KMEB02",22UF,20%,C0402_H32,14299.84,10079.22,270.000,YES,,,
C2540,"Q_CAP_C0402-22UF,4V,20%,X6S,CH622KMEB02",22UF,20%,C0402_H32,14088.01,9977.65,0.000,YES,,,
C2541,"Q_CAP_C0402-22UF,4V,20%,X6S,CH622KMEB02",22UF,20%,C0402_H32,14383.01,9912.65,0.000,YES,,,
C2542,"Q_CAP_C0402-22UF,4V,20%,X6S,CH622KMEB02",22UF,20%,C0402_H32,14628.01,10225.59,0.000,YES,,,
C2543,"Q_CAP_C0402-22UF,4V,20%,X6S,CH622KMEB02",22UF,20%,C0402_H32,14262.44,10079.22,270.000,YES,,,
C2544,"Q_CAP_C0402-22UF,4V,20%,X6S,CH622KMEB02",22UF,20%,C0402_H32,14552.20,10154.73,0.000,YES,,,
C2545,"Q_CAP_C0402-22UF,4V,20%,X6S,CH622KMEB02",22UF,20%,C0402_H32,14698.01,9942.65,0.000,YES,,,
C2546,"Q_CAP_C0402-22UF,4V,20%,X6S,CH622KMEB02",22UF,20%,C0402_H32,14075.43,10079.22,270.000,YES,,,
C2547,"Q_CAP_C0402-22UF,4V,20%,X6S,CH622KMEB02",22UF,20%,C0402_H32,14038.03,10079.22,270.000,YES,,,
C2548,"Q_CAP_C0402-22UF,4V,20%,X6S,CH622KMEB02",22UF,20%,C0402_H32,14658.01,10277.44,0.000,YES,,,
C2549,"Q_CAP_C0402-22UF,4V,20%,X6S,CH622KMEB02",22UF,20%,C0402_H32,14018.01,9977.65,0.000,YES,,,
C2550,"Q_CAP_C0402-22UF,4V,20%,X6S,CH622KMEB02",22UF,20%,C0402_H32,14313.01,9912.65,0.000,YES,,,
C2551,"Q_CAP_C0402-22UF,4V,20%,X6S,CH622KMEB02",22UF,20%,C0402_H32,14402.98,10098.63,180.000,NO,,,
C2552,"Q_CAP_C0402-22UF,4V,20%,X6S,CH622KMEB02",22UF,20%,C0402_H32,14402.98,10210.83,0.000,YES,,,
C2553,"Q_CAP_C0402-22UF,4V,20%,X6S,CH622KMEB02",22UF,20%,C0402_H32,14112.83,10079.22,270.000,YES,,,
C2554,"Q_CAP_C0402-22UF,4V,20%,X6S,CH622KMEB02",22UF,20%,C0402_H32,13793.01,10107.65,180.000,YES,,,
C2555,"Q_CAP_C0402-22UF,4V,20%,X6S,CH622KMEB02",22UF,20%,C0402_H32,14402.98,10285.63,180.000,NO,,,
C2556,"Q_CAP_C0402-22UF,4V,20%,X6S,CH622KMEB02",22UF,20%,C0402_H32,14238.01,9977.65,0.000,YES,,,
C2557,"Q_CAP_C0402-22UF,4V,20%,X6S,CH622KMEB02",22UF,20%,C0402_H32,14553.01,9877.65,0.000,YES,,,
C2558,"Q_CAP_C0402-22UF,4V,20%,X6S,CH622KMEB02",22UF,20%,C0402_H32,14316.77,10188.78,180.000,YES,,,
C2559,"Q_CAP_C0402-22UF,4V,20%,X6S,CH622KMEB02",22UF,20%,C0402_H32,14402.98,10173.43,0.000,YES,,,
C2560,"Q_CAP_C0402-22UF,4V,20%,X6S,CH622KMEB02",22UF,20%,C0402_H32,13773.01,10072.65,0.000,YES,,,
C2561,"Q_CAP_C0402-22UF,4V,20%,X6S,CH622KMEB02",22UF,20%,C0402_H32,13787.57,10019.98,300.000,YES,,,
C2562,"Q_CAP_C0402-22UF,4V,20%,X6S,CH622KMEB02",22UF,20%,C0402_H32,14000.63,10079.22,90.000,NO,,,
C2563,"Q_CAP_C0402-22UF,4V,20%,X6S,CH622KMEB02",22UF,20%,C0402_H32,14316.77,10188.78,0.000,NO,,,
C2564,"Q_CAP_C0402-22UF,4V,20%,X6S,CH622KMEB02",22UF,20%,C0402_H32,14316.77,10147.44,0.000,NO,,,
C2565,"Q_CAP_C0402-22UF,4V,20%,X6S,CH622KMEB02",22UF,20%,C0402_H32,14316.77,10147.44,180.000,YES,,,
C2566,"Q_CAP_C0402-22UF,4V,20%,X6S,CH622KMEB02",22UF,20%,C0402_H32,14403.01,9877.65,0.000,YES,,,
C2567,"Q_CAP_C0402-22UF,4V,20%,X6S,CH622KMEB02",22UF,20%,C0402_H32,13787.37,9930.08,60.000,YES,,,
C2568,"Q_CAP_C0402-22UF,4V,20%,X6S,CH622KMEB02",22UF,20%,C0402_H32,14000.63,10079.22,270.000,YES,,,
C2569,"Q_CAP_C0402-22UF,4V,20%,X6S,CH622KMEB02",22UF,20%,C0402_H32,13943.01,9977.65,0.000,YES,,,
C2570,"Q_CAP_C0402-22UF,4V,20%,X6S,CH622KMEB02",22UF,20%,C0402_H32,14672.50,10312.44,0.000,YES,,,
C2571,"Q_CAP_C0402-22UF,4V,20%,X6S,CH622KMEB02",22UF,20%,C0402_H32,14402.98,10173.43,180.000,NO,,,
C2572,"Q_CAP_C0402-22UF,4V,20%,X6S,CH622KMEB02",22UF,20%,C0402_H32,14125.87,10147.44,0.000,NO,,,
C2573,"Q_CAP_C0402-22UF,4V,20%,X6S,CH622KMEB02",22UF,20%,C0402_H32,14214.41,10147.44,0.000,NO,,,
C2574,"Q_CAP_C0402-22UF,4V,20%,X6S,CH622KMEB02",22UF,20%,C0402_H32,13773.01,10342.65,0.000,YES,,,
C2575,"Q_CAP_C0402-22UF,4V,20%,X6S,CH622KMEB02",22UF,20%,C0402_H32,13848.01,10072.65,180.000,YES,,,
C2576,"Q_CAP_C0402-22UF,4V,20%,X6S,CH622KMEB02",22UF,20%,C0402_H32,13943.01,9912.65,0.000,YES,,,
C2577,"Q_CAP_C0402-22UF,4V,20%,X6S,CH622KMEB02",22UF,20%,C0402_H32,14552.20,10225.59,0.000,YES,,,
C2578,"Q_CAP_C0402-22UF,4V,20%,X6S,CH622KMEB02",22UF,20%,C0402_H32,14698.01,10072.65,0.000,YES,,,
C2579,"Q_CAP_C0402-22UF,4V,20%,X6S,CH622KMEB02",22UF,20%,C0402_H32,14628.01,10007.65,0.000,YES,,,
C2580,"Q_CAP_C0402-22UF,4V,20%,X6S,CH622KMEB02",22UF,20%,C0402_H32,14225.04,10079.22,270.000,YES,,,
C2581,"Q_CAP_C0402-22UF,4V,20%,X6S,CH622KMEB02",22UF,20%,C0402_H32,13773.01,10282.65,0.000,YES,,,
C2582,"Q_CAP_C0402-22UF,4V,20%,X6S,CH622KMEB02",22UF,20%,C0402_H32,13868.01,9977.65,0.000,YES,,,
C2583,"Q_CAP_C0402-22UF,4V,20%,X6S,CH622KMEB02",22UF,20%,C0402_H32,14698.01,10154.73,0.000,YES,,,
C2584,"Q_CAP_C0402-22UF,4V,20%,X6S,CH622KMEB02",22UF,20%,C0402_H32,14698.01,10225.59,0.000,YES,,,
C2585,"Q_CAP_C0402-22UF,4V,20%,X6S,CH622KMEB02",22UF,20%,C0402_H32,14698.01,10190.16,0.000,YES,,,
C2586,"Q_CAP_C0402-22UF,4V,20%,X6S,CH622KMEB02",22UF,20%,C0402_H32,14553.01,10007.65,0.000,YES,,,
C2587,"Q_CAP_C0402-22UF,4V,20%,X6S,CH622KMEB02",22UF,20%,C0402_H32,14402.98,10136.03,0.000,YES,,,
C2588,"Q_CAP_C0402-22UF,4V,20%,X6S,CH622KMEB02",22UF,20%,C0402_H32,13868.01,9912.65,0.000,YES,,,
C2589,"Q_CAP_C0402-22UF,4V,20%,X6S,CH622KMEB02",22UF,20%,C0402_H32,14018.01,9912.65,0.000,YES,,,
C2590,"Q_CAP_C0402-22UF,4V,20%,X6S,CH622KMEB02",22UF,20%,C0402_H32,14598.49,10312.44,0.000,YES,,,
C2591,"Q_CAP_C0402-22UF,4V,20%,X6S,CH622KMEB02",22UF,20%,C0402_H32,14402.98,10136.03,180.000,NO,,,
C2592,"Q_CAP_C0402-22UF,4V,20%,X6S,CH622KMEB02",22UF,20%,C0402_H32,14698.01,9877.65,0.000,YES,,,
C2593,"Q_CAP_C0402-22UF,4V,20%,X6S,CH622KMEB02",22UF,20%,C0402_H32,14088.01,9912.65,0.000,YES,,,
C2594,"Q_CAP_C0402-22UF,4V,20%,X6S,CH622KMEB02",22UF,20%,C0402_H32,14402.98,10285.63,0.000,YES,,,
C2595,"Q_CAP_C0402-22UF,4V,20%,X6S,CH622KMEB02",22UF,20%,C0402_H32,14163.01,9897.65,180.000,YES,,,
C2596,"Q_CAP_C0402-22UF,4V,20%,X6S,CH622KMEB02",22UF,20%,C0402_H32,13843.01,10282.65,180.000,YES,,,
C2597,"Q_CAP_C0402-22UF,4V,20%,X6S,CH622KMEB02",22UF,20%,C0402_H32,13706.77,10374.88,0.000,YES,,,
C2598,"Q_CAP_C0402-22UF,4V,20%,X6S,CH622KMEB02",22UF,20%,C0402_H32,14027.40,10188.78,180.000,YES,,,
C2599,"Q_CAP_C0402-22UF,4V,20%,X6S,CH622KMEB02",22UF,20%,C0402_H32,13933.08,10173.43,0.000,NO,,,
C2600,"Q_CAP_C0402-22UF,4V,20%,X6S,CH622KMEB02",22UF,20%,C0402_H32,14548.01,10472.65,0.000,YES,,,
C2601,"Q_CAP_C0402-22UF,4V,20%,X6S,CH622KMEB02",22UF,20%,C0402_H32,14075.48,10305.03,270.000,NO,,,
C2602,"Q_CAP_C0402-22UF,4V,20%,X6S,CH622KMEB02",22UF,20%,C0402_H32,13953.01,10407.65,0.000,YES,,,
C2603,"Q_CAP_C0402-22UF,4V,20%,X6S,CH622KMEB02",22UF,20%,C0402_H32,13733.01,10472.65,0.000,YES,,,
C2604,"Q_CAP_C0402-22UF,4V,20%,X6S,CH622KMEB02",22UF,20%,C0402_H32,13636.77,10374.88,0.000,YES,,,
C2605,"Q_CAP_C0402-22UF,4V,20%,X6S,CH622KMEB02",22UF,20%,C0402_H32,13636.77,10309.88,0.000,YES,,,
C2606,"Q_CAP_C0402-22UF,4V,20%,X6S,CH622KMEB02",22UF,20%,C0402_H32,13933.08,10136.03,0.000,NO,,,
C2607,"Q_CAP_C0402-22UF,4V,20%,X6S,CH622KMEB02",22UF,20%,C0402_H32,14028.01,10407.65,0.000,YES,,,
C2608,"Q_CAP_C0402-22UF,4V,20%,X6S,CH622KMEB02",22UF,20%,C0402_H32,13878.01,10407.65,0.000,YES,,,
C2609,"Q_CAP_C0402-22UF,4V,20%,X6S,CH622KMEB02",22UF,20%,C0402_H32,14038.08,10305.03,90.000,YES,,,
C2610,"Q_CAP_C0402-22UF,4V,20%,X6S,CH622KMEB02",22UF,20%,C0402_H32,14150.28,10305.03,90.000,YES,,,
C2611,"Q_CAP_C0402-22UF,4V,20%,X6S,CH622KMEB02",22UF,20%,C0402_H32,13792.08,10225.59,180.000,YES,,,
C2612,"Q_CAP_C0402-22UF,4V,20%,X6S,CH622KMEB02",22UF,20%,C0402_H32,13636.77,10434.88,0.000,YES,,,
C2613,"Q_CAP_C0402-22UF,4V,20%,X6S,CH622KMEB02",22UF,20%,C0402_H32,13933.08,10248.23,180.000,YES,,,
C2614,"Q_CAP_C0402-22UF,4V,20%,X6S,CH622KMEB02",22UF,20%,C0402_H32,14125.83,10188.78,0.000,NO,,,
C2615,"Q_CAP_C0402-22UF,4V,20%,X6S,CH622KMEB02",22UF,20%,C0402_H32,14000.68,10305.03,90.000,YES,,,
C2616,"Q_CAP_C0402-22UF,4V,20%,X6S,CH622KMEB02",22UF,20%,C0402_H32,14125.83,10188.78,180.000,YES,,,
C2617,"Q_CAP_C0402-22UF,4V,20%,X6S,CH622KMEB02",22UF,20%,C0402_H32,14112.88,10305.03,90.000,YES,,,
C2618,"Q_CAP_C0402-22UF,4V,20%,X6S,CH622KMEB02",22UF,20%,C0402_H32,13642.48,10154.73,180.000,YES,,,
C2619,"Q_CAP_C0402-22UF,4V,20%,X6S,CH622KMEB02",22UF,20%,C0402_H32,13718.01,10107.65,180.000,YES,,,
C2620,"Q_CAP_C0402-22UF,4V,20%,X6S,CH622KMEB02",22UF,20%,C0402_H32,13933.08,10210.83,180.000,YES,,,
C2621,"Q_CAP_C0402-22UF,4V,20%,X6S,CH622KMEB02",22UF,20%,C0402_H32,14125.83,10230.12,180.000,YES,,,
C2622,"Q_CAP_C0402-22UF,4V,20%,X6S,CH622KMEB02",22UF,20%,C0402_H32,14262.49,10305.03,270.000,NO,,,
C2623,"Q_CAP_C0402-22UF,4V,20%,X6S,CH622KMEB02",22UF,20%,C0402_H32,14173.01,10427.65,0.000,YES,,,
C2624,"Q_CAP_C0402-22UF,4V,20%,X6S,CH622KMEB02",22UF,20%,C0402_H32,14316.77,10230.12,180.000,YES,,,
C2625,"Q_CAP_C0402-22UF,4V,20%,X6S,CH622KMEB02",22UF,20%,C0402_H32,13643.01,10107.65,180.000,YES,,,
C2626,"Q_CAP_C0402-22UF,4V,20%,X6S,CH622KMEB02",22UF,20%,C0402_H32,13706.77,10434.88,0.000,YES,,,
C2627,"Q_CAP_C0402-22UF,4V,20%,X6S,CH622KMEB02",22UF,20%,C0402_H32,13933.08,10323.03,180.000,NO,,,
C2628,"Q_CAP_C0402-22UF,4V,20%,X6S,CH622KMEB02",22UF,20%,C0402_H32,14688.01,10407.65,0.000,YES,,,
C2629,"Q_CAP_C0402-22UF,4V,20%,X6S,CH622KMEB02",22UF,20%,C0402_H32,13808.01,10472.65,0.000,YES,,,
C2630,"Q_CAP_C0402-22UF,4V,20%,X6S,CH622KMEB02",22UF,20%,C0402_H32,14543.01,10407.65,0.000,YES,,,
C2631,"Q_CAP_C0402-22UF,4V,20%,X6S,CH622KMEB02",22UF,20%,C0402_H32,13717.28,10225.59,180.000,YES,,,
C2632,"Q_CAP_C0402-22UF,4V,20%,X6S,CH622KMEB02",22UF,20%,C0402_H32,13717.28,10190.16,180.000,YES,,,
C2633,"Q_CAP_C0402-22UF,4V,20%,X6S,CH622KMEB02",22UF,20%,C0402_H32,14337.29,10305.03,270.000,NO,,,
C2634,"Q_CAP_C0402-22UF,4V,20%,X6S,CH622KMEB02",22UF,20%,C0402_H32,14262.49,10305.03,90.000,YES,,,
C2635,"Q_CAP_C0402-22UF,4V,20%,X6S,CH622KMEB02",22UF,20%,C0402_H32,14225.08,10305.03,270.000,NO,,,
C2636,"Q_CAP_C0402-22UF,4V,20%,X6S,CH622KMEB02",22UF,20%,C0402_H32,14187.68,10305.03,90.000,YES,,,
C2637,"Q_CAP_C0402-22UF,4V,20%,X6S,CH622KMEB02",22UF,20%,C0402_H32,13792.08,10154.73,180.000,YES,,,
C2638,"Q_CAP_C0402-22UF,4V,20%,X6S,CH622KMEB02",22UF,20%,C0402_H32,13933.08,10173.43,180.000,YES,,,
C2639,"Q_CAP_C0402-22UF,4V,20%,X6S,CH622KMEB02",22UF,20%,C0402_H32,14693.01,10472.65,0.000,YES,,,
C2640,"Q_CAP_C0402-22UF,4V,20%,X6S,CH622KMEB02",22UF,20%,C0402_H32,14398.01,10472.65,0.000,YES,,,
C2641,"Q_CAP_C0402-22UF,4V,20%,X6S,CH622KMEB02",22UF,20%,C0402_H32,14299.89,10305.03,270.000,NO,,,
C2642,"Q_CAP_C0402-22UF,4V,20%,X6S,CH622KMEB02",22UF,20%,C0402_H32,14038.08,10305.03,270.000,NO,,,
C2643,"Q_CAP_C0402-22UF,4V,20%,X6S,CH622KMEB02",22UF,20%,C0402_H32,13717.28,10154.73,180.000,YES,,,
C2644,"Q_CAP_C0402-22UF,4V,20%,X6S,CH622KMEB02",22UF,20%,C0402_H32,13933.08,10136.03,180.000,YES,,,
C2645,"Q_CAP_C0402-22UF,4V,20%,X6S,CH622KMEB02",22UF,20%,C0402_H32,14473.01,10407.65,0.000,YES,,,
C2646,"Q_CAP_C0402-22UF,4V,20%,X6S,CH622KMEB02",22UF,20%,C0402_H32,14248.01,10472.65,0.000,YES,,,
C2647,"Q_CAP_C0402-22UF,4V,20%,X6S,CH622KMEB02",22UF,20%,C0402_H32,14562.39,10372.65,0.000,YES,,,
C2648,"Q_CAP_C0402-22UF,4V,20%,X6S,CH622KMEB02",22UF,20%,C0402_H32,14173.01,10387.65,0.000,YES,,,
C2649,"Q_CAP_C0402-22UF,4V,20%,X6S,CH622KMEB02",22UF,20%,C0402_H32,13792.08,10190.16,180.000,YES,,,
C2650,"Q_CAP_C0402-22UF,4V,20%,X6S,CH622KMEB02",22UF,20%,C0402_H32,13706.77,10309.88,0.000,YES,,,
C2651,"Q_CAP_C0402-22UF,4V,20%,X6S,CH622KMEB02",22UF,20%,C0402_H32,14618.01,10407.65,0.000,YES,,,
C2652,"Q_CAP_C0402-22UF,4V,20%,X6S,CH622KMEB02",22UF,20%,C0402_H32,14618.01,10472.65,0.000,YES,,,
C2653,"Q_CAP_C0402-22UF,4V,20%,X6S,CH622KMEB02",22UF,20%,C0402_H32,14398.01,10407.65,0.000,YES,,,
C2654,"Q_CAP_C0402-22UF,4V,20%,X6S,CH622KMEB02",22UF,20%,C0402_H32,13642.48,10190.16,180.000,YES,,,
C2655,"Q_CAP_C0402-22UF,4V,20%,X6S,CH622KMEB02",22UF,20%,C0402_H32,13642.48,10225.59,180.000,YES,,,
C2656,"Q_CAP_C0402-22UF,4V,20%,X6S,CH622KMEB02",22UF,20%,C0402_H32,14323.01,10472.65,0.000,YES,,,
C2657,"Q_CAP_C0402-22UF,4V,20%,X6S,CH622KMEB02",22UF,20%,C0402_H32,14214.41,10230.12,0.000,NO,,,
C2658,"Q_CAP_C0402-22UF,4V,20%,X6S,CH622KMEB02",22UF,20%,C0402_H32,14225.08,10305.03,90.000,YES,,,
C2659,"Q_CAP_C0402-10UF,6.3V,20%,X6S,CH6101MEB01",10UF,20%,C0402,3876.16,10497.66,0.000,YES,,,
C2660,"Q_CAP_C0402-22UF,4V,20%,X6S,CH622KMEB02",22UF,20%,C0402_H32,4171.66,10098.64,180.000,YES,,,
C2661,"Q_CAP_C0402-22UF,4V,20%,X6S,CH622KMEB02",22UF,20%,C0402_H32,3882.10,10037.66,0.000,YES,,,
C2662,"Q_CAP_C0402-10UF,6.3V,20%,X6S,CH6101MEB01",10UF,20%,C0402,3896.16,10532.66,0.000,YES,,,
C2663,"Q_CAP_C0402-22UF,4V,20%,X6S,CH622KMEB02",22UF,20%,C0402_H32,3901.71,9944.88,180.000,YES,,,
C2664,"Q_CAP_C0402-22UF,4V,20%,X6S,CH622KMEB02",22UF,20%,C0402_H32,4266.16,10147.66,0.000,NO,,,
C2665,"Q_CAP_C0402-22UF,4V,20%,X6S,CH622KMEB02",22UF,20%,C0402_H32,3971.71,9944.88,180.000,YES,,,
C2667,"Q_CAP_C0402-22UF,4V,20%,X6S,CH622KMEB02",22UF,20%,C0402_H32,4171.66,10098.64,0.000,NO,,,
C2668,"Q_CAP_C0402-22UF,4V,20%,X6S,CH622KMEB02",22UF,20%,C0402_H32,4266.16,10147.66,180.000,YES,,,
C2669,"Q_CAP_C0402-22UF,4V,20%,X6S,CH622KMEB02",22UF,20%,C0402_H32,3902.71,9877.66,180.000,YES,,,
C2670,"Q_CAP_C0402-22UF,4V,20%,X6S,CH622KMEB02",22UF,20%,C0402_H32,3897.71,9817.66,180.000,YES,,,
C2671,"Q_CAP_C0402-22UF,4V,20%,X6S,CH622KMEB02",22UF,20%,C0402_H32,4171.66,10061.23,0.000,NO,,,
C2672,"Q_CAP_C0402-22UF,4V,20%,X6S,CH622KMEB02",22UF,20%,C0402_H32,3902.71,10002.66,180.000,YES,,,
C2673,"Q_CAP_C0402-22UF,4V,20%,X6S,CH622KMEB02",22UF,20%,C0402_H32,3977.71,9877.66,180.000,YES,,,
C3888,"Q_CAP_C0402-22UF,4V,20%,X6S,CH622KMEB02",22UF,20%,C0402_H32,14214.41,10147.44,180.000,YES,,,
C3889,"Q_CAP_C0402-22UF,4V,20%,X6S,CH622KMEB02",22UF,20%,C0402_H32,14125.83,10147.44,180.000,YES,,,
C3890,"Q_CAP_C0402-22UF,4V,20%,X6S,CH622KMEB02",22UF,20%,C0402_H32,14028.01,10472.65,0.000,YES,,,
C3891,"Q_CAP_C0402-22UF,4V,20%,X6S,CH622KMEB02",22UF,20%,C0402_H32,14337.29,10305.03,90.000,YES,,,
C3892,"Q_CAP_C0402-22UF,4V,20%,X6S,CH622KMEB02",22UF,20%,C0402_H32,14402.98,10323.03,0.000,YES,,,
C3893,"Q_CAP_C0402-22UF,4V,20%,X6S,CH622KMEB02",22UF,20%,C0402_H32,14316.77,10230.12,0.000,NO,,,
C3894,"Q_CAP_C0402-22UF,4V,20%,X6S,CH622KMEB02",22UF,20%,C0402_H32,14383.01,9977.65,0.000,YES,,,
C3895,"Q_CAP_C0402-22UF,4V,20%,X6S,CH622KMEB02",22UF,20%,C0402_H32,14038.03,10079.22,90.000,NO,,,
C3896,"Q_CAP_C0402-22UF,4V,20%,X6S,CH622KMEB02",22UF,20%,C0402_H32,14458.01,9912.65,0.000,YES,,,
C3897,"Q_CAP_C0402-22UF,4V,20%,X6S,CH622KMEB02",22UF,20%,C0402_H32,13933.08,10098.63,0.000,NO,,,
C3898,"Q_CAP_C0402-22UF,4V,20%,X6S,CH622KMEB02",22UF,20%,C0402_H32,14027.40,10230.12,0.000,NO,,,
C3899,"Q_CAP_C0402-22UF,4V,20%,X6S,CH622KMEB02",22UF,20%,C0402_H32,14027.40,10188.78,0.000,NO,,,
C3900,"Q_CAP_C0402-22UF,4V,20%,X6S,CH622KMEB02",22UF,20%,C0402_H32,4575.82,10079.23,90.000,NO,,,
C3901,"Q_CAP_C0402-22UF,4V,20%,X6S,CH622KMEB02",22UF,20%,C0402_H32,4426.22,10079.23,270.000,YES,,,
C3902,"Q_CAP_C0402-22UF,4V,20%,X6S,CH622KMEB02",22UF,20%,C0402_H32,4266.59,10407.66,0.000,YES,,,
C3903,"Q_CAP_C0402-22UF,4V,20%,X6S,CH622KMEB02",22UF,20%,C0402_H32,4191.59,10407.66,0.000,YES,,,
C3904,"Q_CAP_C0402-22UF,4V,20%,X6S,CH622KMEB02",22UF,20%,C0402_H32,4411.59,10387.66,0.000,YES,,,
C3905,"Q_CAP_C0402-22UF,4V,20%,X6S,CH622KMEB02",22UF,20%,C0402_H32,4411.59,10427.66,0.000,YES,,,
C3906,"Q_CAP_C0402-22UF,4V,20%,X6S,CH622KMEB02",22UF,20%,C0402_H32,4501.02,10079.23,90.000,NO,,,
C3907,"Q_CAP_C0402-22UF,4V,20%,X6S,CH622KMEB02",22UF,20%,C0402_H32,4501.02,10079.23,270.000,YES,,,
C3908,"Q_CAP_C0402-22UF,4V,20%,X6S,CH622KMEB02",22UF,20%,C0402_H32,4463.62,10079.23,270.000,YES,,,
C3909,"Q_CAP_C0402-22UF,4V,20%,X6S,CH622KMEB02",22UF,20%,C0402_H32,4171.66,10061.23,180.000,YES,,,
C3910,"Q_CAP_C0402-22UF,4V,20%,X6S,CH622KMEB02",22UF,20%,C0402_H32,4171.66,10210.84,180.000,YES,,,
C3911,"Q_CAP_C0402-22UF,4V,20%,X6S,CH622KMEB02",22UF,20%,C0402_H32,4171.66,10285.64,0.000,NO,,,
C3912,"Q_CAP_C0402-22UF,4V,20%,X6S,CH622KMEB02",22UF,20%,C0402_H32,4790.78,10225.60,0.000,YES,,,
C3913,"Q_CAP_C0402-22UF,4V,20%,X6S,CH622KMEB02",22UF,20%,C0402_H32,4896.59,10277.45,0.000,YES,,,
C3914,"Q_CAP_C0402-22UF,4V,20%,X6S,CH622KMEB02",22UF,20%,C0402_H32,4790.78,10154.74,0.000,YES,,,
C3915,"Q_CAP_C0402-22UF,4V,20%,X6S,CH622KMEB02",22UF,20%,C0402_H32,4866.59,10154.74,0.000,YES,,,
C3916,"Q_CAP_C0402-22UF,4V,20%,X6S,CH622KMEB02",22UF,20%,C0402_H32,4790.78,10190.17,0.000,YES,,,
C3917,"Q_CAP_C0402-22UF,4V,20%,X6S,CH622KMEB02",22UF,20%,C0402_H32,4821.59,10277.45,0.000,YES,,,
C3918,"Q_CAP_C0402-22UF,4V,20%,X6S,CH622KMEB02",22UF,20%,C0402_H32,4866.59,10072.66,0.000,YES,,,
C3919,"Q_CAP_C0402-22UF,4V,20%,X6S,CH622KMEB02",22UF,20%,C0402_H32,4856.59,10472.66,0.000,YES,,,
C3920,"Q_CAP_C0402-22UF,4V,20%,X6S,CH622KMEB02",22UF,20%,C0402_H32,4171.66,10323.04,180.000,NO,,,
C3921,"Q_CAP_C0402-22UF,4V,20%,X6S,CH622KMEB02",22UF,20%,C0402_H32,4239.26,10305.04,90.000,YES,,,
C3922,"Q_CAP_C0402-22UF,4V,20%,X6S,CH622KMEB02",22UF,20%,C0402_H32,3971.59,10472.66,0.000,YES,,,
C3925,"Q_CAP_C0402-22UF,4V,20%,X6S,CH622KMEB02",22UF,20%,C0402_H32,14150.24,10079.22,270.000,YES,,,
C3926,"Q_CAP_C0402-22UF,4V,20%,X6S,CH622KMEB02",22UF,20%,C0402_H32,14214.41,10188.78,180.000,YES,,,
C3927,"Q_CAP_C0402-22UF,4V,20%,X6S,CH622KMEB02",22UF,20%,C0402_H32,14187.64,10079.22,90.000,NO,,,
C3928,"Q_CAP_C0402-22UF,4V,20%,X6S,CH622KMEB02",22UF,20%,C0402_H32,14112.83,10079.22,90.000,NO,,,
C3929,"Q_CAP_C0402-22UF,4V,20%,X6S,CH622KMEB02",22UF,20%,C0402_H32,14150.24,10079.22,90.000,NO,,,
C3930,"Q_CAP_C0402-22UF,4V,20%,X6S,CH622KMEB02",22UF,20%,C0402_H32,14075.43,10079.22,90.000,NO,,,
C3931,"Q_CAP_C0402-22UF,4V,20%,X6S,CH622KMEB02",22UF,20%,C0402_H32,14162.26,9937.65,180.000,YES,,,
C3932,"Q_CAP_C0402-22UF,4V,20%,X6S,CH622KMEB02",22UF,20%,C0402_H32,13953.01,10472.65,0.000,YES,,,
C3933,"Q_CAP_C0402-22UF,4V,20%,X6S,CH622KMEB02",22UF,20%,C0402_H32,13878.01,10472.65,0.000,YES,,,
C3934,"Q_CAP_C0402-22UF,4V,20%,X6S,CH622KMEB02",22UF,20%,C0402_H32,14098.01,10472.65,0.000,YES,,,
C3935,"Q_CAP_C0402-22UF,4V,20%,X6S,CH622KMEB02",22UF,20%,C0402_H32,13933.08,10323.03,0.000,YES,,,
C4178,"Q_CAP_C0402-22UF,4V,20%,X6S,CH622KMEB02",22UF,20%,C0402_H32,13752.77,9782.65,180.000,YES,,,
C4179,"Q_CAP_C0402-22UF,4V,20%,X6S,CH622KMEB02",22UF,20%,C0402_H32,14328.01,9877.65,0.000,YES,,,
C5000,"Q_CAP_0402-1000PF,50V,5%,X7R,TMP_QCH21006JB10",1000PF,5%,C0402,15729.06,13576.78,90.000,YES,,,
C5001,"Q_CAP_0402-1000PF,50V,5%,X7R,TMP_QCH21006JB10",1000PF,5%,C0402,7911.52,4393.44,0.000,NO,,,
C5002,"Q_CAP_0402-1000PF,50V,5%,X7R,TMP_QCH21006JB10",1000PF,5%,C0402,7766.69,4194.64,0.000,NO,,,
C5003,"Q_CAP_0402-1000PF,50V,5%,X7R,TMP_QCH21006JB10",1000PF,5%,C0402,3576.07,5504.15,0.000,NO,,,
C5004,"Q_CAP_0402-1000PF,50V,5%,X7R,TMP_QCH21006JB10",1000PF,5%,C0402,11826.00,14330.00,0.000,NO,,,
C5005,"Q_CAP_0402-1000PF,50V,5%,X7R,TMP_QCH21006JB10",1000PF,5%,C0402,11895.00,14145.00,180.000,YES,,,
C5006,"Q_CAP_0402-1000PF,50V,5%,X7R,TMP_QCH21006JB10",1000PF,5%,C0402,885.00,14260.00,180.000,YES,,,
C5009,"Q_CAP_0402-1000PF,50V,5%,X7R,TMP_QCH21006JB10",1000PF,5%,C0402,16311.67,14480.16,180.000,NO,,,
C5010,"Q_CAP_0402-1000PF,50V,5%,X7R,TMP_QCH21006JB10",1000PF,5%,C0402,6207.77,13907.32,180.000,NO,,,
C5011,"Q_CAP_0402-1000PF,50V,5%,X7R,TMP_QCH21006JB10",1000PF,5%,C0402,14658.32,5394.02,90.000,YES,,,
C5012,"Q_CAP_0402-1000PF,50V,5%,X7R,TMP_QCH21006JB10",1000PF,5%,C0402,3551.57,5504.15,180.000,YES,,,
C5013,"Q_CAP_0402-1000PF,50V,5%,X7R,TMP_QCH21006JB10",1000PF,5%,C0402,11895.00,14375.00,180.000,NO,,,
C5014,"Q_CAP_0402-1000PF,50V,5%,X7R,TMP_QCH21006JB10",1000PF,5%,C0402,3821.84,4703.51,90.000,NO,,,
C5015,"Q_CAP_0402-1000PF,50V,5%,EMPTY,TMP_QCH21006JB10",NA,5%,C0402,18126.22,1748.69,0.000,YES,,,
C5016,"Q_CAP_0402-1000PF,50V,5%,X7R,TMP_QCH21006JB10",1000PF,5%,C0402,8080.75,4226.87,0.000,NO,,,
C5017,"Q_CAP_0402-1000PF,50V,5%,X7R,TMP_QCH21006JB10",1000PF,5%,C0402,14642.57,5378.27,180.000,NO,,,
C5018,"Q_CAP_0402-1000PF,50V,5%,X7R,TMP_QCH21006JB10",1000PF,5%,C0402,14602.57,5649.77,0.000,NO,,,
C5019,"Q_CAP_0402-1000PF,50V,5%,X7R,TMP_QCH21006JB10",1000PF,5%,C0402,3481.57,5728.40,270.000,NO,,,
C5020,"Q_CAP_0402-1000PF,50V,5%,X7R,TMP_QCH21006JB10",1000PF,5%,C0402,885.00,14355.00,180.000,NO,,,
C5022,"Q_CAP_0402-1000PF,50V,5%,X7R,TMP_QCH21006JB10",1000PF,5%,C0402,885.00,14400.00,180.000,YES,,,
C5023,"Q_CAP_0402-1000PF,50V,5%,X7R,TMP_QCH21006JB10",1000PF,5%,C0402,15486.37,12623.14,180.000,NO,,,
C5024,"Q_CAP_0402-1000PF,50V,5%,X7R,TMP_QCH21006JB10",1000PF,5%,C0402,6017.71,12665.98,0.000,NO,,,
C5032,"Q_CAP_C0805-10UF,25V,10%,X6S,CH6104KEA00",10UF,10%,C0805_H61,13125.06,975.27,270.000,NO,,,
C5229,"Q_CAP_C0402-1UF,25V,10%,EMPTY,CH5104KEB02",NA,10%,C0402,567.22,4370.26,90.000,YES,,,
C5232,"Q_CAP_C0402-0.1UF,25V,10%,EMPTY,CH4104KEB00",NA,10%,C0402,322.55,4411.30,0.000,YES,,,
C5234,"Q_CAP_C0402-0.1UF,25V,10%,EMPTY,CH4104KEB00",NA,10%,C0402,607.61,4369.59,90.000,YES,,,
C5236,"Q_CAP_C0402-0.1UF,25V,10%,EMPTY,CH4104KEB00",NA,10%,C0402,639.28,4436.77,180.000,YES,,,
C6000,"Q_CAP_0402-0.1UF,25V,10%,X7R,CH4104K1B00",0.1UF,10%,C0402,5821.93,916.73,90.000,NO,,,
C6003,"Q_CAP_0402-0.1UF,25V,10%,X7R,CH4104K1B00",0.1UF,10%,C0402,5733.60,1243.60,90.000,NO,,,
C6004,"Q_CAP_0402-0.1UF,25V,10%,X7R,CH4104K1B00",0.1UF,10%,C0402,5683.60,1243.60,90.000,NO,,,
C6005,"Q_CAP_0402-0.1UF,25V,10%,X7R,CH4104K1B00",0.1UF,10%,C0402,1092.00,16577.52,0.000,NO,,,
C6006,"Q_CAP_0402-0.1UF,25V,10%,X7R,CH4104K1B00",0.1UF,10%,C0402,1091.95,16627.19,0.000,NO,,,
C6007,"Q_CAP_0402-0.1UF,25V,10%,X7R,CH4104K1B00",0.1UF,10%,C0402,1572.85,16793.84,180.000,NO,,,
C6008,"Q_CAP_0402-0.1UF,25V,10%,X7R,CH4104K1B00",0.1UF,10%,C0402,1572.85,16742.39,180.000,NO,,,
C6009,"Q_CAP_C0402-1UF,25V,10%,X6S,CH5104KEB02",1UF,10%,C0402,594.27,16543.87,0.000,YES,,,
C6010,"Q_CAP_C0805-10UF,16V,10%,X6S,CH6103KEA00",10UF,10%,C0805_H57,584.27,16488.87,0.000,YES,,,
C6011,"Q_CAP_0402-0.1UF,25V,10%,X7R,CH4104K1B00",0.1UF,10%,C0402,854.42,16671.27,0.000,NO,,,
C6012,"Q_CAP_0402-0.1UF,25V,10%,X7R,CH4104K1B00",0.1UF,10%,C0402,854.83,16631.38,0.000,NO,,,
C6013,"Q_CAP_0402-0.1UF,25V,10%,X7R,CH4104K1B00",0.1UF,10%,C0402,5733.60,1212.10,270.000,NO,,,
C6014,"Q_CAP_0402-0.1UF,25V,10%,X7R,CH4104K1B00",0.1UF,10%,C0402,5683.60,1212.10,270.000,NO,,,
C6015,"Q_CAP_DIFFBUS_C0402-DIFF BUS_0.33UF,6.3V,10%,X6S,SA",,,C0402_DIFF-BUS,5562.80,1245.15,270.000,NO,,,
C6016,"Q_CAP_DIFFBUS_C0402-DIFF BUS_0.33UF,6.3V,10%,X6S,SA",,,C0402_DIFF-BUS,5512.80,1245.15,270.000,NO,,,
C6017,"Q_CAP_0402-0.1UF,25V,10%,X7R,CH4104K1B00",0.1UF,10%,C0402,5562.80,1213.65,90.000,NO,,,
C6018,"Q_CAP_0402-0.1UF,25V,10%,X7R,CH4104K1B00",0.1UF,10%,C0402,5512.80,1213.65,90.000,NO,,,
C6019,"Q_CAP_DIFFBUS_C0402-DIFF BUS_0.33UF,6.3V,10%,X6S,SA",,,C0402_DIFF-BUS,4936.55,1289.42,0.000,NO,,,
C6020,"Q_CAP_DIFFBUS_C0402-DIFF BUS_0.33UF,6.3V,10%,X6S,SA",,,C0402_DIFF-BUS,4936.55,1339.42,0.000,NO,,,
C6021,"Q_CAP_DIFFBUS_C0402-DIFF BUS_0.33UF,6.3V,10%,X6S,SA",,,C0402_DIFF-BUS,4905.05,1289.42,180.000,NO,,,
C6022,"Q_CAP_DIFFBUS_C0402-DIFF BUS_0.33UF,6.3V,10%,X6S,SA",,,C0402_DIFF-BUS,4905.05,1339.42,180.000,NO,,,
C6023,"Q_CAP_0402-0.1UF,25V,10%,X7R,CH4104K1B00",0.1UF,10%,C0402,4856.55,1443.92,180.000,NO,,,
C6024,"Q_CAP_0402-0.1UF,25V,10%,X7R,CH4104K1B00",0.1UF,10%,C0402,4856.55,1394.92,180.000,NO,,,
C6025,"Q_CAP_0402-0.1UF,25V,10%,X7R,CH4104K1B00",0.1UF,10%,C0402,4825.05,1443.92,0.000,NO,,,
C6026,"Q_CAP_0402-0.1UF,25V,10%,X7R,CH4104K1B00",0.1UF,10%,C0402,4825.05,1394.92,0.000,NO,,,
C6027,"Q_CAP_C0805-22UF,16V,20%,X6S,CH6223MEA00",22UF,20%,C0805_H57,5575.78,1990.41,0.000,NO,,,
C6028,"Q_CAP_0402-470PF,50V,10%,X7R,TMP_QCH14706KB18",470PF,10%,C0402,5575.78,1935.41,0.000,NO,,,
C6030,"Q_CAP_C0603-22UF,6.3V,20%,X6S,CH6221ME900",22UF,20%,C0603,5372.42,1615.28,90.000,YES,,,
C6031,"Q_CAP_C0402-1UF,25V,10%,X6S,CH5104KEB02",1UF,10%,C0402,5308.67,1669.37,0.000,YES,,,
C6032,"Q_CAP_0402-0.1UF,25V,10%,X7R,CH4104K1B00",0.1UF,10%,C0402,5256.18,1614.48,90.000,YES,,,
C6033,"Q_CAP_C0402-0.01UF,50V,10%,X7R,CH31006KB18",0.01UF,10%,C0402,5216.18,1614.48,90.000,YES,,,
C6034,"Q_CAP_0402-0.1UF,25V,10%,X7R,CH4104K1B00",0.1UF,10%,C0402,5308.67,1619.19,0.000,YES,,,
C6035,"Q_CAP_C0402-0.01UF,50V,10%,X7R,CH31006KB18",0.01UF,10%,C0402,5308.67,1579.19,0.000,YES,,,
C6036,"Q_CAP_0402-0.1UF,25V,10%,X7R,CH4104K1B00",0.1UF,10%,C0402,5355.91,1452.07,0.000,YES,,,
C6037,"Q_CAP_C0402-0.01UF,50V,10%,X7R,CH31006KB18",0.01UF,10%,C0402,5355.91,1412.07,0.000,YES,,,
C6038,"Q_CAP_0402-0.1UF,25V,10%,X7R,CH4104K1B00",0.1UF,10%,C0402,5355.91,1332.07,0.000,YES,,,
C6039,"Q_CAP_C0402-0.01UF,50V,10%,X7R,CH31006KB18",0.01UF,10%,C0402,5355.91,1372.07,0.000,YES,,,
C6040,"Q_CAP_C0402-0.01UF,50V,10%,X7R,CH31006KB18",0.01UF,10%,C0402,5176.18,1614.48,90.000,YES,,,
C6041,"Q_CAP_0402-0.1UF,25V,10%,X7R,CH4104K1B00",0.1UF,10%,C0402,5136.18,1614.48,90.000,YES,,,
C6042,"Q_CAP_C0603-22UF,6.3V,20%,X6S,CH6221ME900",22UF,20%,C0603,5533.80,1409.93,270.000,YES,,,
C6043,"Q_CAP_C0402-1UF,25V,10%,X6S,CH5104KEB02",1UF,10%,C0402,5483.80,1319.93,90.000,YES,,,
C6044,"Q_CAP_0402-0.1UF,25V,10%,X7R,CH4104K1B00",0.1UF,10%,C0402,5446.80,1389.93,270.000,YES,,,
C6045,"Q_CAP_C0402-0.01UF,50V,10%,X7R,CH31006KB18",0.01UF,10%,C0402,5486.80,1389.93,270.000,YES,,,
C6046,"Q_CAP_C0603-22UF,6.3V,20%,X6S,CH6221ME900",22UF,20%,C0603,5437.49,1265.17,270.000,YES,,,
C6047,"Q_CAP_C0402-1UF,25V,10%,X6S,CH5104KEB02",1UF,10%,C0402,5388.76,1254.89,270.000,YES,,,
C6048,"Q_CAP_0402-0.1UF,25V,10%,X7R,CH4104K1B00",0.1UF,10%,C0402,5285.91,1332.07,180.000,YES,,,
C6049,"Q_CAP_C0402-0.01UF,50V,10%,X7R,CH31006KB18",0.01UF,10%,C0402,5230.91,1307.07,270.000,YES,,,
C6050,"Q_CAP_0402-0.1UF,25V,10%,X7R,CH4104K1B00",0.1UF,10%,C0402,5190.91,1307.07,270.000,YES,,,
C6051,"Q_CAP_C0402-0.01UF,50V,10%,X7R,CH31006KB18",0.01UF,10%,C0402,5190.91,1237.07,270.000,YES,,,
C6052,"Q_CAP_0402-0.1UF,25V,10%,X7R,CH4104K1B00",0.1UF,10%,C0402,5348.76,1254.89,270.000,YES,,,
C6053,"Q_CAP_C0402-0.01UF,50V,10%,X7R,CH31006KB18",0.01UF,10%,C0402,5285.91,1292.07,180.000,YES,,,
C6054,"Q_CAP_C0402-0.001UF,50V,10%,X7R,CH30106KB19",0.001UF,10%,C0402,5059.26,1404.98,180.000,YES,,,
C6055,"Q_CAP_C0402-0.01UF,50V,10%,X7R,CH31006KB18",0.01UF,10%,C0402,4975.42,1385.98,0.000,YES,,,
C6056,"Q_CAP_C0402-0.001UF,50V,10%,X7R,CH30106KB19",0.001UF,10%,C0402,5458.80,1484.93,180.000,YES,,,
C6057,"Q_CAP_C0402-0.01UF,50V,10%,X7R,CH31006KB18",0.01UF,10%,C0402,5458.80,1444.93,180.000,YES,,,
C6058,"Q_CAP_C0402-0.001UF,50V,10%,X7R,CH30106KB19",0.001UF,10%,C0402,5458.80,1524.93,180.000,YES,,,
C6059,"Q_CAP_C0402-0.01UF,50V,10%,X7R,CH31006KB18",0.01UF,10%,C0402,5458.80,1564.93,180.000,YES,,,
C6060,"Q_CAP_C0402-0.001UF,50V,10%,X7R,CH30106KB19",0.001UF,10%,C0402,4996.52,1530.45,90.000,YES,,,
C6061,"Q_CAP_C0402-0.01UF,50V,10%,X7R,CH31006KB18",0.01UF,10%,C0402,4956.52,1530.45,90.000,YES,,,
C6062,"Q_CAP_C0402-0.001UF,50V,10%,X7R,CH30106KB19",0.001UF,10%,C0402,5046.70,1460.45,270.000,YES,,,
C6063,"Q_CAP_C0402-0.01UF,50V,10%,X7R,CH31006KB18",0.01UF,10%,C0402,5086.70,1460.45,270.000,YES,,,
C6064,"Q_CAP_0402-0.1UF,25V,10%,X7R,CH4104K1B00",0.1UF,10%,C0402,5134.21,1244.98,180.000,YES,,,
C6065,"Q_CAP_C0402-1UF,25V,10%,X6S,CH5104KEB02",1UF,10%,C0402,5145.76,1299.98,270.000,YES,,,
C6066,"Q_CAP_C0603-22UF,6.3V,20%,X6S,CH6221ME900",22UF,20%,C0603,5012.56,1230.68,0.000,YES,,,
C6067,"Q_CAP_C0402-0.001UF,50V,10%,X7R,CH30106KB19",0.001UF,10%,C0402,5355.91,1492.07,0.000,YES,,,
C6068,"Q_CAP_C0402-0.01UF,50V,10%,X7R,CH31006KB18",0.01UF,10%,C0402,5355.91,1532.07,0.000,YES,,,
C6069,"Q_CAP_C0402-0.001UF,50V,10%,X7R,CH30106KB19",0.001UF,10%,C0402,5458.80,1644.93,180.000,YES,,,
C6070,"Q_CAP_C0402-0.01UF,50V,10%,X7R,CH31006KB18",0.01UF,10%,C0402,5458.80,1604.93,180.000,YES,,,
C6071,"Q_CAP_C0402-0.001UF,50V,10%,X7R,CH30106KB19",0.001UF,10%,C0402,5071.32,1578.98,180.000,YES,,,
C6072,"Q_CAP_C0402-0.01UF,50V,10%,X7R,CH31006KB18",0.01UF,10%,C0402,5071.32,1538.98,180.000,YES,,,
C6073,"Q_CAP_C0402-0.001UF,50V,10%,X7R,CH30106KB19",0.001UF,10%,C0402,4975.42,1435.45,0.000,YES,,,
C6074,"Q_CAP_C0402-0.01UF,50V,10%,X7R,CH31006KB18",0.01UF,10%,C0402,4975.42,1475.45,0.000,YES,,,
C6075,"Q_CAP_C0402-0.001UF,50V,10%,X7R,CH30106KB19",0.001UF,10%,C0402,4995.76,1293.98,270.000,YES,,,
C6076,"Q_CAP_C0402-0.01UF,50V,10%,X7R,CH31006KB18",0.01UF,10%,C0402,5035.76,1293.98,270.000,YES,,,
C6077,"Q_CAP_0402-0.1UF,25V,10%,X7R,CH4104K1B00",0.1UF,10%,C0402,5046.18,1651.48,270.000,YES,,,
C6078,"Q_CAP_C0402-1UF,25V,10%,X6S,CH5104KEB02",1UF,10%,C0402,5086.18,1651.48,270.000,YES,,,
C6079,"Q_CAP_C0603-22UF,6.3V,20%,X6S,CH6221ME900",22UF,20%,C0603,4995.86,1644.18,270.000,YES,,,
C6080,"Q_CAP_C0402-0.01UF,50V,10%,X7R,CH31006KB18",0.01UF,10%,C0402,5090.76,1324.98,0.000,YES,,,
C6081,"Q_CAP_0402-0.1UF,25V,10%,X7R,CH4104K1B00",0.1UF,10%,C0402,5090.76,1364.98,0.000,YES,,,
C6082,"Q_CAP_C0402-1UF,25V,10%,X6S,CH5104KEB02",1UF,10%,C0402,5090.76,1284.98,0.000,YES,,,
C6083,"Q_CAP_0402-0.1UF,25V,10%,X7R,CH4104K1B00",0.1UF,10%,C0402,4509.05,2709.11,0.000,NO,,,
C6084,"Q_CAP_0402-0.1UF,25V,10%,EMPTY,CH4104K1B00",NA,10%,C0402,7058.15,16589.56,90.000,YES,,,
C6085,"Q_CAP_0402-0.1UF,25V,10%,EMPTY,CH4104K1B00",NA,10%,C0402,4795.68,2810.93,180.000,YES,,,
C6086,"Q_CAP_0402-0.1UF,25V,10%,X7R,CH4104K1B00",0.1UF,10%,C0402,16863.08,16964.27,180.000,NO,,,
C6087,"Q_CAP_0402-0.1UF,25V,10%,X7R,CH4104K1B00",0.1UF,10%,C0402,16935.27,16964.22,0.000,NO,,,
C6088,"Q_CAP_C0805-10UF,16V,10%,X6S,CH6103KEA00",10UF,10%,C0805_H57,3921.53,2131.95,90.000,NO,,,
C6089,"Q_CAP_C0402-1UF,25V,10%,X6S,CH5104KEB02",1UF,10%,C0402,3867.03,1253.37,270.000,NO,,,
C6090,"Q_CAP_C0402-12PF,50V,5%,C0G,CH01206JB05",12PF,5%,C0402,4147.01,991.48,180.000,NO,,,
C6091,"Q_CAP_C0402-12PF,50V,5%,C0G,CH01206JB05",12PF,5%,C0402,4218.01,991.48,0.000,NO,,,
C6092,"Q_CAP_C0402-1UF,25V,10%,X6S,CH5104KEB02",1UF,10%,C0402,4313.01,1282.97,180.000,YES,,,
C6093,"Q_CAP_C0402-1PF,50V,0.05P,COG,CH-106T0B00",1PF,0.05P,C0402,4313.01,1242.09,180.000,YES,,,
C6094,"Q_CAP_C0402-0.01UF,50V,10%,X7R,CH31006KB18",0.01UF,10%,C0402,4408.74,1061.12,90.000,YES,,,
C6095,"Q_CAP_0402-0.1UF,25V,10%,X7R,CH4104K1B00",0.1UF,10%,C0402,4313.01,1322.97,180.000,YES,,,
C6096,"Q_CAP_C0402-1PF,50V,0.05P,COG,CH-106T0B00",1PF,0.05P,C0402,4297.26,1130.05,270.000,YES,,,
C6097,"Q_CAP_C0402-0.01UF,50V,10%,X7R,CH31006KB18",0.01UF,10%,C0402,4288.74,1061.12,90.000,YES,,,
C6098,"Q_CAP_0402-0.1UF,25V,10%,X7R,CH4104K1B00",0.1UF,10%,C0402,4368.74,1061.12,90.000,YES,,,
C6099,"Q_CAP_C0402-1PF,50V,0.05P,COG,CH-106T0B00",1PF,0.05P,C0402,4255.48,1163.60,270.000,YES,,,
C6100,"Q_CAP_C0402-0.01UF,50V,10%,X7R,CH31006KB18",0.01UF,10%,C0402,4248.74,1061.12,90.000,YES,,,
C6101,"Q_CAP_0402-0.1UF,25V,10%,X7R,CH4104K1B00",0.1UF,10%,C0402,4208.74,1061.12,90.000,YES,,,
C6102,"Q_CAP_C0402-1PF,50V,0.05P,COG,CH-106T0B00",1PF,0.05P,C0402,4220.48,1163.60,270.000,YES,,,
C6103,"Q_CAP_C0402-0.01UF,50V,10%,X7R,CH31006KB18",0.01UF,10%,C0402,4328.74,1061.12,90.000,YES,,,
C6104,"Q_CAP_0402-0.1UF,25V,10%,X7R,CH4104K1B00",0.1UF,10%,C0402,4332.26,1130.05,270.000,YES,,,
C6105,"Q_CAP_C0805-10UF,25V,10%,X6S,CH6104KEA00",10UF,10%,C0805_H61,4480.90,1352.42,90.000,YES,,,
C6106,"Q_CAP_C0402-1PF,50V,0.05P,COG,CH-106T0B00",1PF,0.05P,C0402,4481.93,1024.90,0.000,YES,,,
C6107,"Q_CAP_C0402-0.01UF,50V,10%,X7R,CH31006KB18",0.01UF,10%,C0402,4488.90,1120.07,270.000,YES,,,
C6108,"Q_CAP_0402-0.1UF,25V,10%,X7R,CH4104K1B00",0.1UF,10%,C0402,4528.90,1120.07,270.000,YES,,,
C6109,"Q_CAP_C0402-1PF,50V,0.05P,COG,CH-106T0B00",1PF,0.05P,C0402,4271.90,1381.42,90.000,YES,,,
C6110,"Q_CAP_C0402-0.01UF,50V,10%,X7R,CH31006KB18",0.01UF,10%,C0402,4427.90,1381.42,90.000,YES,,,
C6111,"Q_CAP_0402-0.1UF,25V,10%,X7R,CH4104K1B00",0.1UF,10%,C0402,4388.90,1381.42,90.000,YES,,,
C6112,"Q_CAP_C0402-1PF,50V,0.05P,COG,CH-106T0B00",1PF,0.05P,C0402,4207.48,1233.60,90.000,YES,,,
C6113,"Q_CAP_C0402-0.01UF,50V,10%,X7R,CH31006KB18",0.01UF,10%,C0402,4481.93,1064.90,0.000,YES,,,
C6114,"Q_CAP_0402-0.1UF,25V,10%,X7R,CH4104K1B00",0.1UF,10%,C0402,4310.90,1381.42,90.000,YES,,,
C6115,"Q_CAP_C0402-1PF,50V,0.05P,COG,CH-106T0B00",1PF,0.05P,C0402,4349.90,1381.42,90.000,YES,,,
C6116,"Q_CAP_C0402-0.01UF,50V,10%,X7R,CH31006KB18",0.01UF,10%,C0402,4554.57,1024.64,90.000,YES,,,
C6117,"Q_CAP_0402-0.1UF,25V,10%,X7R,CH4104K1B00",0.1UF,10%,C0402,4610.32,1080.39,180.000,YES,,,
C6118,"Q_CAP_C0805-10UF,25V,10%,X6S,CH6104KEA00",10UF,10%,C0805_H61,4550.99,1200.07,0.000,YES,,,
C6119,"Q_CAP_C0402-1PF,50V,0.05P,COG,CH-106T0B00",1PF,0.05P,C0402,4610.32,1120.39,180.000,YES,,,
C6120,"Q_CAP_C0402-0.01UF,50V,10%,X7R,CH31006KB18",0.01UF,10%,C0402,4594.57,1024.64,90.000,YES,,,
C6121,"Q_CAP_0402-0.1UF,25V,10%,X7R,CH4104K1B00",0.1UF,10%,C0402,4313.01,1202.09,180.000,YES,,,
C6122,"Q_CAP_C0402-100NF,50V,10%,X7R,CH4106K1B01",100NF,10%,C0402,6795.00,5225.00,90.000,NO,,,
C6500,"Q_CAP_0402-0.1UF,25V,10%,X7R,CH4104K1B00",0.1UF,10%,C0402,4685.00,4915.00,270.000,NO,,,
C6501,"Q_CAP_DIFFBUS_C0201-DIFF BUS_0.22UF,6.3V,20%,X6S,SA",,,C0201_DIFF-BUS,11995.39,16413.36,270.000,NO,,,
C6502,"Q_CAP_DIFFBUS_C0201-DIFF BUS_0.22UF,6.3V,20%,X6S,SA",,,C0201_DIFF-BUS,11959.39,16413.36,270.000,NO,,,
C6503,"Q_CAP_DIFFBUS_C0201-DIFF BUS_0.22UF,6.3V,20%,X6S,SA",,,C0201_DIFF-BUS,12115.99,16413.36,270.000,NO,,,
C6504,"Q_CAP_DIFFBUS_C0201-DIFF BUS_0.22UF,6.3V,20%,X6S,SA",,,C0201_DIFF-BUS,12079.99,16413.36,270.000,NO,,,
C6505,"Q_CAP_DIFFBUS_C0201-DIFF BUS_0.22UF,6.3V,20%,X6S,SA",,,C0201_DIFF-BUS,12236.59,16413.36,270.000,NO,,,
C6506,"Q_CAP_DIFFBUS_C0201-DIFF BUS_0.22UF,6.3V,20%,X6S,SA",,,C0201_DIFF-BUS,12200.59,16413.36,270.000,NO,,,
C6507,"Q_CAP_DIFFBUS_C0201-DIFF BUS_0.22UF,6.3V,20%,X6S,SA",,,C0201_DIFF-BUS,12357.19,16413.36,270.000,NO,,,
C6508,"Q_CAP_DIFFBUS_C0201-DIFF BUS_0.22UF,6.3V,20%,X6S,SA",,,C0201_DIFF-BUS,12321.19,16413.36,270.000,NO,,,
C6509,"Q_CAP_DIFFBUS_C0201-DIFF BUS_0.22UF,6.3V,20%,X6S,SA",,,C0201_DIFF-BUS,12477.79,16413.36,270.000,NO,,,
C6510,"Q_CAP_DIFFBUS_C0201-DIFF BUS_0.22UF,6.3V,20%,X6S,SA",,,C0201_DIFF-BUS,12441.79,16413.36,270.000,NO,,,
C6511,"Q_CAP_DIFFBUS_C0201-DIFF BUS_0.22UF,6.3V,20%,X6S,SA",,,C0201_DIFF-BUS,12598.39,16413.36,270.000,NO,,,
C6512,"Q_CAP_DIFFBUS_C0201-DIFF BUS_0.22UF,6.3V,20%,X6S,SA",,,C0201_DIFF-BUS,12562.39,16413.36,270.000,NO,,,
C6513,"Q_CAP_DIFFBUS_C0201-DIFF BUS_0.22UF,6.3V,20%,X6S,SA",,,C0201_DIFF-BUS,12718.99,16413.36,270.000,NO,,,
C6514,"Q_CAP_DIFFBUS_C0201-DIFF BUS_0.22UF,6.3V,20%,X6S,SA",,,C0201_DIFF-BUS,12682.99,16413.36,270.000,NO,,,
C6515,"Q_CAP_DIFFBUS_C0201-DIFF BUS_0.22UF,6.3V,20%,X6S,SA",,,C0201_DIFF-BUS,12839.59,16413.36,270.000,NO,,,
C6516,"Q_CAP_DIFFBUS_C0201-DIFF BUS_0.22UF,6.3V,20%,X6S,SA",,,C0201_DIFF-BUS,12803.59,16413.36,270.000,NO,,,
C6517,"Q_CAP_DIFFBUS_C0201-DIFF BUS_0.22UF,6.3V,20%,X6S,SA",,,C0201_DIFF-BUS,12960.19,16413.36,270.000,NO,,,
C6518,"Q_CAP_DIFFBUS_C0201-DIFF BUS_0.22UF,6.3V,20%,X6S,SA",,,C0201_DIFF-BUS,12924.19,16413.36,270.000,NO,,,
C6519,"Q_CAP_DIFFBUS_C0201-DIFF BUS_0.22UF,6.3V,20%,X6S,SA",,,C0201_DIFF-BUS,13080.79,16413.36,270.000,NO,,,
C6520,"Q_CAP_DIFFBUS_C0201-DIFF BUS_0.22UF,6.3V,20%,X6S,SA",,,C0201_DIFF-BUS,13044.79,16413.36,270.000,NO,,,
C6521,"Q_CAP_DIFFBUS_C0201-DIFF BUS_0.22UF,6.3V,20%,X6S,SA",,,C0201_DIFF-BUS,13201.39,16413.36,270.000,NO,,,
C6522,"Q_CAP_DIFFBUS_C0201-DIFF BUS_0.22UF,6.3V,20%,X6S,SA",,,C0201_DIFF-BUS,13165.39,16413.36,270.000,NO,,,
C6523,"Q_CAP_DIFFBUS_C0201-DIFF BUS_0.22UF,6.3V,20%,X6S,SA",,,C0201_DIFF-BUS,13321.99,16413.36,270.000,NO,,,
C6524,"Q_CAP_DIFFBUS_C0201-DIFF BUS_0.22UF,6.3V,20%,X6S,SA",,,C0201_DIFF-BUS,13285.99,16413.36,270.000,NO,,,
C6525,"Q_CAP_DIFFBUS_C0201-DIFF BUS_0.22UF,6.3V,20%,X6S,SA",,,C0201_DIFF-BUS,13442.59,16413.36,270.000,NO,,,
C6526,"Q_CAP_DIFFBUS_C0201-DIFF BUS_0.22UF,6.3V,20%,X6S,SA",,,C0201_DIFF-BUS,13406.59,16413.36,270.000,NO,,,
C6527,"Q_CAP_DIFFBUS_C0201-DIFF BUS_0.22UF,6.3V,20%,X6S,SA",,,C0201_DIFF-BUS,13563.19,16413.36,270.000,NO,,,
C6528,"Q_CAP_DIFFBUS_C0201-DIFF BUS_0.22UF,6.3V,20%,X6S,SA",,,C0201_DIFF-BUS,13527.19,16413.36,270.000,NO,,,
C6529,"Q_CAP_DIFFBUS_C0201-DIFF BUS_0.22UF,6.3V,20%,X6S,SA",,,C0201_DIFF-BUS,13683.79,16413.36,270.000,NO,,,
C6530,"Q_CAP_DIFFBUS_C0201-DIFF BUS_0.22UF,6.3V,20%,X6S,SA",,,C0201_DIFF-BUS,13647.79,16413.36,270.000,NO,,,
C6531,"Q_CAP_DIFFBUS_C0201-DIFF BUS_0.22UF,6.3V,20%,X6S,SA",,,C0201_DIFF-BUS,13804.39,16413.36,270.000,NO,,,
C6532,"Q_CAP_DIFFBUS_C0201-DIFF BUS_0.22UF,6.3V,20%,X6S,SA",,,C0201_DIFF-BUS,13768.39,16413.36,270.000,NO,,,
C6533,"Q_CAP_DIFFBUS_C0201-DIFF BUS_0.22UF,6.3V,20%,X6S,SA",,,C0201_DIFF-BUS,12055.69,16413.36,90.000,YES,,,
C6534,"Q_CAP_DIFFBUS_C0201-DIFF BUS_0.22UF,6.3V,20%,X6S,SA",,,C0201_DIFF-BUS,12019.69,16413.36,90.000,YES,,,
C6535,"Q_CAP_DIFFBUS_C0201-DIFF BUS_0.22UF,6.3V,20%,X6S,SA",,,C0201_DIFF-BUS,12176.29,16413.36,90.000,YES,,,
C6536,"Q_CAP_DIFFBUS_C0201-DIFF BUS_0.22UF,6.3V,20%,X6S,SA",,,C0201_DIFF-BUS,12140.29,16413.36,90.000,YES,,,
C6537,"Q_CAP_DIFFBUS_C0201-DIFF BUS_0.22UF,6.3V,20%,X6S,SA",,,C0201_DIFF-BUS,12296.89,16413.36,90.000,YES,,,
C6538,"Q_CAP_DIFFBUS_C0201-DIFF BUS_0.22UF,6.3V,20%,X6S,SA",,,C0201_DIFF-BUS,12260.89,16413.36,90.000,YES,,,
C6539,"Q_CAP_DIFFBUS_C0201-DIFF BUS_0.22UF,6.3V,20%,X6S,SA",,,C0201_DIFF-BUS,12417.49,16413.36,90.000,YES,,,
C6540,"Q_CAP_DIFFBUS_C0201-DIFF BUS_0.22UF,6.3V,20%,X6S,SA",,,C0201_DIFF-BUS,12381.49,16413.36,90.000,YES,,,
C6541,"Q_CAP_DIFFBUS_C0201-DIFF BUS_0.22UF,6.3V,20%,X6S,SA",,,C0201_DIFF-BUS,12538.09,16413.36,90.000,YES,,,
C6542,"Q_CAP_DIFFBUS_C0201-DIFF BUS_0.22UF,6.3V,20%,X6S,SA",,,C0201_DIFF-BUS,12502.09,16413.36,90.000,YES,,,
C6543,"Q_CAP_DIFFBUS_C0201-DIFF BUS_0.22UF,6.3V,20%,X6S,SA",,,C0201_DIFF-BUS,12658.69,16413.36,90.000,YES,,,
C6544,"Q_CAP_DIFFBUS_C0201-DIFF BUS_0.22UF,6.3V,20%,X6S,SA",,,C0201_DIFF-BUS,12622.69,16413.36,90.000,YES,,,
C6545,"Q_CAP_DIFFBUS_C0201-DIFF BUS_0.22UF,6.3V,20%,X6S,SA",,,C0201_DIFF-BUS,12779.29,16413.36,90.000,YES,,,
C6546,"Q_CAP_DIFFBUS_C0201-DIFF BUS_0.22UF,6.3V,20%,X6S,SA",,,C0201_DIFF-BUS,12743.29,16413.36,90.000,YES,,,
C6547,"Q_CAP_DIFFBUS_C0201-DIFF BUS_0.22UF,6.3V,20%,X6S,SA",,,C0201_DIFF-BUS,12899.89,16413.36,90.000,YES,,,
C6548,"Q_CAP_DIFFBUS_C0201-DIFF BUS_0.22UF,6.3V,20%,X6S,SA",,,C0201_DIFF-BUS,12863.89,16413.36,90.000,YES,,,
C6549,"Q_CAP_DIFFBUS_C0201-DIFF BUS_0.22UF,6.3V,20%,X6S,SA",,,C0201_DIFF-BUS,13020.49,16413.36,90.000,YES,,,
C6550,"Q_CAP_DIFFBUS_C0201-DIFF BUS_0.22UF,6.3V,20%,X6S,SA",,,C0201_DIFF-BUS,12984.49,16413.36,90.000,YES,,,
C6551,"Q_CAP_DIFFBUS_C0201-DIFF BUS_0.22UF,6.3V,20%,X6S,SA",,,C0201_DIFF-BUS,13141.09,16413.36,90.000,YES,,,
C6552,"Q_CAP_DIFFBUS_C0201-DIFF BUS_0.22UF,6.3V,20%,X6S,SA",,,C0201_DIFF-BUS,13105.09,16413.36,90.000,YES,,,
C6553,"Q_CAP_DIFFBUS_C0201-DIFF BUS_0.22UF,6.3V,20%,X6S,SA",,,C0201_DIFF-BUS,13261.69,16413.36,90.000,YES,,,
C6554,"Q_CAP_DIFFBUS_C0201-DIFF BUS_0.22UF,6.3V,20%,X6S,SA",,,C0201_DIFF-BUS,13225.69,16413.36,90.000,YES,,,
C6555,"Q_CAP_DIFFBUS_C0201-DIFF BUS_0.22UF,6.3V,20%,X6S,SA",,,C0201_DIFF-BUS,13382.29,16413.36,90.000,YES,,,
C6556,"Q_CAP_DIFFBUS_C0201-DIFF BUS_0.22UF,6.3V,20%,X6S,SA",,,C0201_DIFF-BUS,13346.29,16413.36,90.000,YES,,,
C6557,"Q_CAP_DIFFBUS_C0201-DIFF BUS_0.22UF,6.3V,20%,X6S,SA",,,C0201_DIFF-BUS,13502.89,16413.36,90.000,YES,,,
C6558,"Q_CAP_DIFFBUS_C0201-DIFF BUS_0.22UF,6.3V,20%,X6S,SA",,,C0201_DIFF-BUS,13466.89,16413.36,90.000,YES,,,
C6559,"Q_CAP_DIFFBUS_C0201-DIFF BUS_0.22UF,6.3V,20%,X6S,SA",,,C0201_DIFF-BUS,13623.49,16413.36,90.000,YES,,,
C6560,"Q_CAP_DIFFBUS_C0201-DIFF BUS_0.22UF,6.3V,20%,X6S,SA",,,C0201_DIFF-BUS,13587.49,16413.36,90.000,YES,,,
C6561,"Q_CAP_DIFFBUS_C0201-DIFF BUS_0.22UF,6.3V,20%,X6S,SA",,,C0201_DIFF-BUS,13744.09,16413.36,90.000,YES,,,
C6562,"Q_CAP_DIFFBUS_C0201-DIFF BUS_0.22UF,6.3V,20%,X6S,SA",,,C0201_DIFF-BUS,13708.09,16413.36,90.000,YES,,,
C6563,"Q_CAP_DIFFBUS_C0201-DIFF BUS_0.22UF,6.3V,20%,X6S,SA",,,C0201_DIFF-BUS,13864.69,16413.36,90.000,YES,,,
C6564,"Q_CAP_DIFFBUS_C0201-DIFF BUS_0.22UF,6.3V,20%,X6S,SA",,,C0201_DIFF-BUS,13828.69,16413.36,90.000,YES,,,
C6565,"Q_CAP_DIFFBUS_C0201-DIFF BUS_0.22UF,6.3V,20%,X6S,SA",,,C0201_DIFF-BUS,14633.13,16324.27,270.000,NO,,,
C6566,"Q_CAP_DIFFBUS_C0201-DIFF BUS_0.22UF,6.3V,20%,X6S,SA",,,C0201_DIFF-BUS,14597.13,16324.27,270.000,NO,,,
C6567,"Q_CAP_DIFFBUS_C0201-DIFF BUS_0.22UF,6.3V,20%,X6S,SA",,,C0201_DIFF-BUS,14757.73,16413.36,270.000,NO,,,
C6568,"Q_CAP_DIFFBUS_C0201-DIFF BUS_0.22UF,6.3V,20%,X6S,SA",,,C0201_DIFF-BUS,14721.73,16413.36,270.000,NO,,,
C6569,"Q_CAP_DIFFBUS_C0201-DIFF BUS_0.22UF,6.3V,20%,X6S,SA",,,C0201_DIFF-BUS,14878.33,16413.36,270.000,NO,,,
C6570,"Q_CAP_DIFFBUS_C0201-DIFF BUS_0.22UF,6.3V,20%,X6S,SA",,,C0201_DIFF-BUS,14842.33,16413.36,270.000,NO,,,
C6571,"Q_CAP_DIFFBUS_C0201-DIFF BUS_0.22UF,6.3V,20%,X6S,SA",,,C0201_DIFF-BUS,14998.93,16413.36,270.000,NO,,,
C6572,"Q_CAP_DIFFBUS_C0201-DIFF BUS_0.22UF,6.3V,20%,X6S,SA",,,C0201_DIFF-BUS,14962.93,16413.36,270.000,NO,,,
C6573,"Q_CAP_DIFFBUS_C0201-DIFF BUS_0.22UF,6.3V,20%,X6S,SA",,,C0201_DIFF-BUS,15119.53,16413.36,270.000,NO,,,
C6574,"Q_CAP_DIFFBUS_C0201-DIFF BUS_0.22UF,6.3V,20%,X6S,SA",,,C0201_DIFF-BUS,15083.53,16413.36,270.000,NO,,,
C6575,"Q_CAP_DIFFBUS_C0201-DIFF BUS_0.22UF,6.3V,20%,X6S,SA",,,C0201_DIFF-BUS,15240.13,16413.36,270.000,NO,,,
C6576,"Q_CAP_DIFFBUS_C0201-DIFF BUS_0.22UF,6.3V,20%,X6S,SA",,,C0201_DIFF-BUS,15204.13,16413.36,270.000,NO,,,
C6577,"Q_CAP_DIFFBUS_C0201-DIFF BUS_0.22UF,6.3V,20%,X6S,SA",,,C0201_DIFF-BUS,15360.73,16413.36,270.000,NO,,,
C6578,"Q_CAP_DIFFBUS_C0201-DIFF BUS_0.22UF,6.3V,20%,X6S,SA",,,C0201_DIFF-BUS,15324.73,16413.36,270.000,NO,,,
C6579,"Q_CAP_DIFFBUS_C0201-DIFF BUS_0.22UF,6.3V,20%,X6S,SA",,,C0201_DIFF-BUS,15481.33,16413.36,270.000,NO,,,
C6580,"Q_CAP_DIFFBUS_C0201-DIFF BUS_0.22UF,6.3V,20%,X6S,SA",,,C0201_DIFF-BUS,15445.33,16413.36,270.000,NO,,,
C6581,"Q_CAP_DIFFBUS_C0201-DIFF BUS_0.22UF,6.3V,20%,X6S,SA",,,C0201_DIFF-BUS,15601.93,16413.36,270.000,NO,,,
C6582,"Q_CAP_DIFFBUS_C0201-DIFF BUS_0.22UF,6.3V,20%,X6S,SA",,,C0201_DIFF-BUS,15565.93,16413.36,270.000,NO,,,
C6583,"Q_CAP_DIFFBUS_C0201-DIFF BUS_0.22UF,6.3V,20%,X6S,SA",,,C0201_DIFF-BUS,15722.53,16413.36,270.000,NO,,,
C6584,"Q_CAP_DIFFBUS_C0201-DIFF BUS_0.22UF,6.3V,20%,X6S,SA",,,C0201_DIFF-BUS,15686.53,16413.36,270.000,NO,,,
C6585,"Q_CAP_DIFFBUS_C0201-DIFF BUS_0.22UF,6.3V,20%,X6S,SA",,,C0201_DIFF-BUS,15843.13,16413.36,270.000,NO,,,
C6586,"Q_CAP_DIFFBUS_C0201-DIFF BUS_0.22UF,6.3V,20%,X6S,SA",,,C0201_DIFF-BUS,15807.13,16413.36,270.000,NO,,,
C6587,"Q_CAP_DIFFBUS_C0201-DIFF BUS_0.22UF,6.3V,20%,X6S,SA",,,C0201_DIFF-BUS,15963.73,16413.36,270.000,NO,,,
C6588,"Q_CAP_DIFFBUS_C0201-DIFF BUS_0.22UF,6.3V,20%,X6S,SA",,,C0201_DIFF-BUS,15927.73,16413.36,270.000,NO,,,
C6589,"Q_CAP_DIFFBUS_C0201-DIFF BUS_0.22UF,6.3V,20%,X6S,SA",,,C0201_DIFF-BUS,16084.33,16413.36,270.000,NO,,,
C6590,"Q_CAP_DIFFBUS_C0201-DIFF BUS_0.22UF,6.3V,20%,X6S,SA",,,C0201_DIFF-BUS,16048.33,16413.36,270.000,NO,,,
C6591,"Q_CAP_DIFFBUS_C0201-DIFF BUS_0.22UF,6.3V,20%,X6S,SA",,,C0201_DIFF-BUS,16204.93,16413.36,270.000,NO,,,
C6592,"Q_CAP_DIFFBUS_C0201-DIFF BUS_0.22UF,6.3V,20%,X6S,SA",,,C0201_DIFF-BUS,16168.93,16413.36,270.000,NO,,,
C6593,"Q_CAP_DIFFBUS_C0201-DIFF BUS_0.22UF,6.3V,20%,X6S,SA",,,C0201_DIFF-BUS,16325.53,16413.36,270.000,NO,,,
C6594,"Q_CAP_DIFFBUS_C0201-DIFF BUS_0.22UF,6.3V,20%,X6S,SA",,,C0201_DIFF-BUS,16289.53,16413.36,270.000,NO,,,
C6595,"Q_CAP_DIFFBUS_C0201-DIFF BUS_0.22UF,6.3V,20%,X6S,SA",,,C0201_DIFF-BUS,16446.13,16413.36,270.000,NO,,,
C6596,"Q_CAP_DIFFBUS_C0201-DIFF BUS_0.22UF,6.3V,20%,X6S,SA",,,C0201_DIFF-BUS,16410.13,16413.36,270.000,NO,,,
C6597,"Q_CAP_DIFFBUS_C0201-DIFF BUS_0.22UF,6.3V,20%,X6S,SA",,,C0201_DIFF-BUS,14697.43,16413.36,90.000,YES,,,
C6598,"Q_CAP_DIFFBUS_C0201-DIFF BUS_0.22UF,6.3V,20%,X6S,SA",,,C0201_DIFF-BUS,14661.43,16413.36,90.000,YES,,,
C6599,"Q_CAP_DIFFBUS_C0201-DIFF BUS_0.22UF,6.3V,20%,X6S,SA",,,C0201_DIFF-BUS,14818.03,16413.36,90.000,YES,,,
C6600,"Q_CAP_DIFFBUS_C0201-DIFF BUS_0.22UF,6.3V,20%,X6S,SA",,,C0201_DIFF-BUS,14782.03,16413.36,90.000,YES,,,
C6601,"Q_CAP_DIFFBUS_C0201-DIFF BUS_0.22UF,6.3V,20%,X6S,SA",,,C0201_DIFF-BUS,14938.63,16413.36,90.000,YES,,,
C6602,"Q_CAP_DIFFBUS_C0201-DIFF BUS_0.22UF,6.3V,20%,X6S,SA",,,C0201_DIFF-BUS,14902.63,16413.36,90.000,YES,,,
C6603,"Q_CAP_DIFFBUS_C0201-DIFF BUS_0.22UF,6.3V,20%,X6S,SA",,,C0201_DIFF-BUS,15059.23,16413.36,90.000,YES,,,
C6604,"Q_CAP_DIFFBUS_C0201-DIFF BUS_0.22UF,6.3V,20%,X6S,SA",,,C0201_DIFF-BUS,15023.23,16413.36,90.000,YES,,,
C6605,"Q_CAP_DIFFBUS_C0201-DIFF BUS_0.22UF,6.3V,20%,X6S,SA",,,C0201_DIFF-BUS,15179.83,16413.36,90.000,YES,,,
C6606,"Q_CAP_DIFFBUS_C0201-DIFF BUS_0.22UF,6.3V,20%,X6S,SA",,,C0201_DIFF-BUS,15143.83,16413.36,90.000,YES,,,
C6607,"Q_CAP_DIFFBUS_C0201-DIFF BUS_0.22UF,6.3V,20%,X6S,SA",,,C0201_DIFF-BUS,15300.43,16413.36,90.000,YES,,,
C6608,"Q_CAP_DIFFBUS_C0201-DIFF BUS_0.22UF,6.3V,20%,X6S,SA",,,C0201_DIFF-BUS,15264.43,16413.36,90.000,YES,,,
C6609,"Q_CAP_DIFFBUS_C0201-DIFF BUS_0.22UF,6.3V,20%,X6S,SA",,,C0201_DIFF-BUS,15421.03,16413.36,90.000,YES,,,
C6610,"Q_CAP_DIFFBUS_C0201-DIFF BUS_0.22UF,6.3V,20%,X6S,SA",,,C0201_DIFF-BUS,15385.03,16413.36,90.000,YES,,,
C6611,"Q_CAP_DIFFBUS_C0201-DIFF BUS_0.22UF,6.3V,20%,X6S,SA",,,C0201_DIFF-BUS,15541.63,16413.36,90.000,YES,,,
C6612,"Q_CAP_DIFFBUS_C0201-DIFF BUS_0.22UF,6.3V,20%,X6S,SA",,,C0201_DIFF-BUS,15505.63,16413.36,90.000,YES,,,
C6613,"Q_CAP_DIFFBUS_C0201-DIFF BUS_0.22UF,6.3V,20%,X6S,SA",,,C0201_DIFF-BUS,15662.23,16413.36,90.000,YES,,,
C6614,"Q_CAP_DIFFBUS_C0201-DIFF BUS_0.22UF,6.3V,20%,X6S,SA",,,C0201_DIFF-BUS,15626.23,16413.36,90.000,YES,,,
C6615,"Q_CAP_DIFFBUS_C0201-DIFF BUS_0.22UF,6.3V,20%,X6S,SA",,,C0201_DIFF-BUS,15782.83,16413.36,90.000,YES,,,
C6616,"Q_CAP_DIFFBUS_C0201-DIFF BUS_0.22UF,6.3V,20%,X6S,SA",,,C0201_DIFF-BUS,15746.83,16413.36,90.000,YES,,,
C6617,"Q_CAP_DIFFBUS_C0201-DIFF BUS_0.22UF,6.3V,20%,X6S,SA",,,C0201_DIFF-BUS,15903.43,16413.36,90.000,YES,,,
C6618,"Q_CAP_DIFFBUS_C0201-DIFF BUS_0.22UF,6.3V,20%,X6S,SA",,,C0201_DIFF-BUS,15867.43,16413.36,90.000,YES,,,
C6619,"Q_CAP_DIFFBUS_C0201-DIFF BUS_0.22UF,6.3V,20%,X6S,SA",,,C0201_DIFF-BUS,16024.03,16413.36,90.000,YES,,,
C6620,"Q_CAP_DIFFBUS_C0201-DIFF BUS_0.22UF,6.3V,20%,X6S,SA",,,C0201_DIFF-BUS,15988.03,16413.36,90.000,YES,,,
C6621,"Q_CAP_DIFFBUS_C0201-DIFF BUS_0.22UF,6.3V,20%,X6S,SA",,,C0201_DIFF-BUS,16144.63,16413.36,90.000,YES,,,
C6622,"Q_CAP_DIFFBUS_C0201-DIFF BUS_0.22UF,6.3V,20%,X6S,SA",,,C0201_DIFF-BUS,16108.63,16413.36,90.000,YES,,,
C6623,"Q_CAP_DIFFBUS_C0201-DIFF BUS_0.22UF,6.3V,20%,X6S,SA",,,C0201_DIFF-BUS,16265.23,16413.36,90.000,YES,,,
C6624,"Q_CAP_DIFFBUS_C0201-DIFF BUS_0.22UF,6.3V,20%,X6S,SA",,,C0201_DIFF-BUS,16229.23,16413.36,90.000,YES,,,
C6625,"Q_CAP_DIFFBUS_C0201-DIFF BUS_0.22UF,6.3V,20%,X6S,SA",,,C0201_DIFF-BUS,16385.83,16413.36,90.000,YES,,,
C6626,"Q_CAP_DIFFBUS_C0201-DIFF BUS_0.22UF,6.3V,20%,X6S,SA",,,C0201_DIFF-BUS,16349.83,16413.36,90.000,YES,,,
C6627,"Q_CAP_DIFFBUS_C0201-DIFF BUS_0.22UF,6.3V,20%,X6S,SA",,,C0201_DIFF-BUS,16506.43,16413.36,90.000,YES,,,
C6628,"Q_CAP_DIFFBUS_C0201-DIFF BUS_0.22UF,6.3V,20%,X6S,SA",,,C0201_DIFF-BUS,16470.43,16413.36,90.000,YES,,,
C6629,"Q_CAP_DIFFBUS_C0201-DIFF BUS_0.22UF,6.3V,20%,X6S,SA",,,C0201_DIFF-BUS,1916.66,16083.36,270.000,NO,,,
C6630,"Q_CAP_DIFFBUS_C0201-DIFF BUS_0.22UF,6.3V,20%,X6S,SA",,,C0201_DIFF-BUS,1880.66,16083.36,270.000,NO,,,
C6631,"Q_CAP_DIFFBUS_C0201-DIFF BUS_0.22UF,6.3V,20%,X6S,SA",,,C0201_DIFF-BUS,2037.26,16083.36,270.000,NO,,,
C6632,"Q_CAP_DIFFBUS_C0201-DIFF BUS_0.22UF,6.3V,20%,X6S,SA",,,C0201_DIFF-BUS,2001.26,16083.36,270.000,NO,,,
C6633,"Q_CAP_DIFFBUS_C0201-DIFF BUS_0.22UF,6.3V,20%,X6S,SA",,,C0201_DIFF-BUS,2157.86,16083.36,270.000,NO,,,
C6634,"Q_CAP_DIFFBUS_C0201-DIFF BUS_0.22UF,6.3V,20%,X6S,SA",,,C0201_DIFF-BUS,2121.86,16083.36,270.000,NO,,,
C6635,"Q_CAP_DIFFBUS_C0201-DIFF BUS_0.22UF,6.3V,20%,X6S,SA",,,C0201_DIFF-BUS,2278.46,16083.36,270.000,NO,,,
C6636,"Q_CAP_DIFFBUS_C0201-DIFF BUS_0.22UF,6.3V,20%,X6S,SA",,,C0201_DIFF-BUS,2242.46,16083.36,270.000,NO,,,
C6637,"Q_CAP_DIFFBUS_C0201-DIFF BUS_0.22UF,6.3V,20%,X6S,SA",,,C0201_DIFF-BUS,2399.06,16083.36,270.000,NO,,,
C6638,"Q_CAP_DIFFBUS_C0201-DIFF BUS_0.22UF,6.3V,20%,X6S,SA",,,C0201_DIFF-BUS,2363.06,16083.36,270.000,NO,,,
C6639,"Q_CAP_DIFFBUS_C0201-DIFF BUS_0.22UF,6.3V,20%,X6S,SA",,,C0201_DIFF-BUS,2519.66,16083.36,270.000,NO,,,
C6640,"Q_CAP_DIFFBUS_C0201-DIFF BUS_0.22UF,6.3V,20%,X6S,SA",,,C0201_DIFF-BUS,2483.66,16083.36,270.000,NO,,,
C6641,"Q_CAP_DIFFBUS_C0201-DIFF BUS_0.22UF,6.3V,20%,X6S,SA",,,C0201_DIFF-BUS,2640.26,16083.36,270.000,NO,,,
C6642,"Q_CAP_DIFFBUS_C0201-DIFF BUS_0.22UF,6.3V,20%,X6S,SA",,,C0201_DIFF-BUS,2604.26,16083.36,270.000,NO,,,
C6643,"Q_CAP_DIFFBUS_C0201-DIFF BUS_0.22UF,6.3V,20%,X6S,SA",,,C0201_DIFF-BUS,2760.86,16083.36,270.000,NO,,,
C6644,"Q_CAP_DIFFBUS_C0201-DIFF BUS_0.22UF,6.3V,20%,X6S,SA",,,C0201_DIFF-BUS,2724.86,16083.36,270.000,NO,,,
C6645,"Q_CAP_DIFFBUS_C0201-DIFF BUS_0.22UF,6.3V,20%,X6S,SA",,,C0201_DIFF-BUS,2881.46,16083.36,270.000,NO,,,
C6646,"Q_CAP_DIFFBUS_C0201-DIFF BUS_0.22UF,6.3V,20%,X6S,SA",,,C0201_DIFF-BUS,2845.46,16083.36,270.000,NO,,,
C6647,"Q_CAP_DIFFBUS_C0201-DIFF BUS_0.22UF,6.3V,20%,X6S,SA",,,C0201_DIFF-BUS,3002.06,16083.36,270.000,NO,,,
C6648,"Q_CAP_DIFFBUS_C0201-DIFF BUS_0.22UF,6.3V,20%,X6S,SA",,,C0201_DIFF-BUS,2966.06,16083.36,270.000,NO,,,
C6649,"Q_CAP_DIFFBUS_C0201-DIFF BUS_0.22UF,6.3V,20%,X6S,SA",,,C0201_DIFF-BUS,3122.66,16083.36,270.000,NO,,,
C6650,"Q_CAP_DIFFBUS_C0201-DIFF BUS_0.22UF,6.3V,20%,X6S,SA",,,C0201_DIFF-BUS,3086.66,16083.36,270.000,NO,,,
C6651,"Q_CAP_DIFFBUS_C0201-DIFF BUS_0.22UF,6.3V,20%,X6S,SA",,,C0201_DIFF-BUS,3243.26,16083.36,270.000,NO,,,
C6652,"Q_CAP_DIFFBUS_C0201-DIFF BUS_0.22UF,6.3V,20%,X6S,SA",,,C0201_DIFF-BUS,3207.26,16083.36,270.000,NO,,,
C6653,"Q_CAP_DIFFBUS_C0201-DIFF BUS_0.22UF,6.3V,20%,X6S,SA",,,C0201_DIFF-BUS,3363.86,16083.36,270.000,NO,,,
C6654,"Q_CAP_DIFFBUS_C0201-DIFF BUS_0.22UF,6.3V,20%,X6S,SA",,,C0201_DIFF-BUS,3327.86,16083.36,270.000,NO,,,
C6655,"Q_CAP_DIFFBUS_C0201-DIFF BUS_0.22UF,6.3V,20%,X6S,SA",,,C0201_DIFF-BUS,3484.46,16083.36,270.000,NO,,,
C6656,"Q_CAP_DIFFBUS_C0201-DIFF BUS_0.22UF,6.3V,20%,X6S,SA",,,C0201_DIFF-BUS,3448.46,16083.36,270.000,NO,,,
C6657,"Q_CAP_DIFFBUS_C0201-DIFF BUS_0.22UF,6.3V,20%,X6S,SA",,,C0201_DIFF-BUS,3605.06,16083.36,270.000,NO,,,
C6658,"Q_CAP_DIFFBUS_C0201-DIFF BUS_0.22UF,6.3V,20%,X6S,SA",,,C0201_DIFF-BUS,3569.06,16083.36,270.000,NO,,,
C6659,"Q_CAP_DIFFBUS_C0201-DIFF BUS_0.22UF,6.3V,20%,X6S,SA",,,C0201_DIFF-BUS,3725.66,16083.36,270.000,NO,,,
C6660,"Q_CAP_DIFFBUS_C0201-DIFF BUS_0.22UF,6.3V,20%,X6S,SA",,,C0201_DIFF-BUS,3689.66,16083.36,270.000,NO,,,
C6661,"Q_CAP_DIFFBUS_C0201-DIFF BUS_0.22UF,6.3V,20%,X6S,SA",,,C0201_DIFF-BUS,1976.96,16083.36,90.000,YES,,,
C6662,"Q_CAP_DIFFBUS_C0201-DIFF BUS_0.22UF,6.3V,20%,X6S,SA",,,C0201_DIFF-BUS,1940.96,16083.36,90.000,YES,,,
C6663,"Q_CAP_DIFFBUS_C0201-DIFF BUS_0.22UF,6.3V,20%,X6S,SA",,,C0201_DIFF-BUS,2097.56,16083.36,90.000,YES,,,
C6664,"Q_CAP_DIFFBUS_C0201-DIFF BUS_0.22UF,6.3V,20%,X6S,SA",,,C0201_DIFF-BUS,2061.56,16083.36,90.000,YES,,,
C6665,"Q_CAP_DIFFBUS_C0201-DIFF BUS_0.22UF,6.3V,20%,X6S,SA",,,C0201_DIFF-BUS,2218.16,16083.36,90.000,YES,,,
C6666,"Q_CAP_DIFFBUS_C0201-DIFF BUS_0.22UF,6.3V,20%,X6S,SA",,,C0201_DIFF-BUS,2182.16,16083.36,90.000,YES,,,
C6667,"Q_CAP_DIFFBUS_C0201-DIFF BUS_0.22UF,6.3V,20%,X6S,SA",,,C0201_DIFF-BUS,2338.76,16083.36,90.000,YES,,,
C6668,"Q_CAP_DIFFBUS_C0201-DIFF BUS_0.22UF,6.3V,20%,X6S,SA",,,C0201_DIFF-BUS,2302.76,16083.36,90.000,YES,,,
C6669,"Q_CAP_DIFFBUS_C0201-DIFF BUS_0.22UF,6.3V,20%,X6S,SA",,,C0201_DIFF-BUS,2459.36,16083.36,90.000,YES,,,
C6670,"Q_CAP_DIFFBUS_C0201-DIFF BUS_0.22UF,6.3V,20%,X6S,SA",,,C0201_DIFF-BUS,2423.36,16083.36,90.000,YES,,,
C6671,"Q_CAP_DIFFBUS_C0201-DIFF BUS_0.22UF,6.3V,20%,X6S,SA",,,C0201_DIFF-BUS,2579.96,16083.36,90.000,YES,,,
C6672,"Q_CAP_DIFFBUS_C0201-DIFF BUS_0.22UF,6.3V,20%,X6S,SA",,,C0201_DIFF-BUS,2543.96,16083.36,90.000,YES,,,
C6673,"Q_CAP_DIFFBUS_C0201-DIFF BUS_0.22UF,6.3V,20%,X6S,SA",,,C0201_DIFF-BUS,2700.56,16083.36,90.000,YES,,,
C6674,"Q_CAP_DIFFBUS_C0201-DIFF BUS_0.22UF,6.3V,20%,X6S,SA",,,C0201_DIFF-BUS,2664.56,16083.36,90.000,YES,,,
C6675,"Q_CAP_DIFFBUS_C0201-DIFF BUS_0.22UF,6.3V,20%,X6S,SA",,,C0201_DIFF-BUS,2821.16,16083.36,90.000,YES,,,
C6676,"Q_CAP_DIFFBUS_C0201-DIFF BUS_0.22UF,6.3V,20%,X6S,SA",,,C0201_DIFF-BUS,2785.16,16083.36,90.000,YES,,,
C6677,"Q_CAP_DIFFBUS_C0201-DIFF BUS_0.22UF,6.3V,20%,X6S,SA",,,C0201_DIFF-BUS,2941.76,16083.36,90.000,YES,,,
C6678,"Q_CAP_DIFFBUS_C0201-DIFF BUS_0.22UF,6.3V,20%,X6S,SA",,,C0201_DIFF-BUS,2905.76,16083.36,90.000,YES,,,
C6679,"Q_CAP_DIFFBUS_C0201-DIFF BUS_0.22UF,6.3V,20%,X6S,SA",,,C0201_DIFF-BUS,3062.36,16083.36,90.000,YES,,,
C6680,"Q_CAP_DIFFBUS_C0201-DIFF BUS_0.22UF,6.3V,20%,X6S,SA",,,C0201_DIFF-BUS,3026.36,16083.36,90.000,YES,,,
C6681,"Q_CAP_DIFFBUS_C0201-DIFF BUS_0.22UF,6.3V,20%,X6S,SA",,,C0201_DIFF-BUS,3182.96,16083.36,90.000,YES,,,
C6682,"Q_CAP_DIFFBUS_C0201-DIFF BUS_0.22UF,6.3V,20%,X6S,SA",,,C0201_DIFF-BUS,3146.96,16083.36,90.000,YES,,,
C6683,"Q_CAP_DIFFBUS_C0201-DIFF BUS_0.22UF,6.3V,20%,X6S,SA",,,C0201_DIFF-BUS,3303.56,16083.36,90.000,YES,,,
C6684,"Q_CAP_DIFFBUS_C0201-DIFF BUS_0.22UF,6.3V,20%,X6S,SA",,,C0201_DIFF-BUS,3267.56,16083.36,90.000,YES,,,
C6685,"Q_CAP_DIFFBUS_C0201-DIFF BUS_0.22UF,6.3V,20%,X6S,SA",,,C0201_DIFF-BUS,3424.16,16083.36,90.000,YES,,,
C6686,"Q_CAP_DIFFBUS_C0201-DIFF BUS_0.22UF,6.3V,20%,X6S,SA",,,C0201_DIFF-BUS,3388.16,16083.36,90.000,YES,,,
C6687,"Q_CAP_DIFFBUS_C0201-DIFF BUS_0.22UF,6.3V,20%,X6S,SA",,,C0201_DIFF-BUS,3544.76,16083.36,90.000,YES,,,
C6688,"Q_CAP_DIFFBUS_C0201-DIFF BUS_0.22UF,6.3V,20%,X6S,SA",,,C0201_DIFF-BUS,3508.76,16083.36,90.000,YES,,,
C6689,"Q_CAP_DIFFBUS_C0201-DIFF BUS_0.22UF,6.3V,20%,X6S,SA",,,C0201_DIFF-BUS,3665.36,16083.36,90.000,YES,,,
C6690,"Q_CAP_DIFFBUS_C0201-DIFF BUS_0.22UF,6.3V,20%,X6S,SA",,,C0201_DIFF-BUS,3629.36,16083.36,90.000,YES,,,
C6691,"Q_CAP_DIFFBUS_C0201-DIFF BUS_0.22UF,6.3V,20%,X6S,SA",,,C0201_DIFF-BUS,3785.96,16083.36,90.000,YES,,,
C6692,"Q_CAP_DIFFBUS_C0201-DIFF BUS_0.22UF,6.3V,20%,X6S,SA",,,C0201_DIFF-BUS,3749.96,16083.36,90.000,YES,,,
C6693,"Q_CAP_DIFFBUS_C0201-DIFF BUS_0.22UF,6.3V,20%,X6S,SA",,,C0201_DIFF-BUS,4558.39,16083.36,270.000,NO,,,
C6694,"Q_CAP_DIFFBUS_C0201-DIFF BUS_0.22UF,6.3V,20%,X6S,SA",,,C0201_DIFF-BUS,4522.39,16083.36,270.000,NO,,,
C6695,"Q_CAP_DIFFBUS_C0201-DIFF BUS_0.22UF,6.3V,20%,X6S,SA",,,C0201_DIFF-BUS,4678.99,16083.36,270.000,NO,,,
C6696,"Q_CAP_DIFFBUS_C0201-DIFF BUS_0.22UF,6.3V,20%,X6S,SA",,,C0201_DIFF-BUS,4642.99,16083.36,270.000,NO,,,
C6697,"Q_CAP_DIFFBUS_C0201-DIFF BUS_0.22UF,6.3V,20%,X6S,SA",,,C0201_DIFF-BUS,4799.59,16083.36,270.000,NO,,,
C6698,"Q_CAP_DIFFBUS_C0201-DIFF BUS_0.22UF,6.3V,20%,X6S,SA",,,C0201_DIFF-BUS,4763.59,16083.36,270.000,NO,,,
C6699,"Q_CAP_DIFFBUS_C0201-DIFF BUS_0.22UF,6.3V,20%,X6S,SA",,,C0201_DIFF-BUS,4920.19,16083.36,270.000,NO,,,
C6700,"Q_CAP_DIFFBUS_C0201-DIFF BUS_0.22UF,6.3V,20%,X6S,SA",,,C0201_DIFF-BUS,4884.19,16083.36,270.000,NO,,,
C6701,"Q_CAP_DIFFBUS_C0201-DIFF BUS_0.22UF,6.3V,20%,X6S,SA",,,C0201_DIFF-BUS,5040.79,16083.36,270.000,NO,,,
C6702,"Q_CAP_DIFFBUS_C0201-DIFF BUS_0.22UF,6.3V,20%,X6S,SA",,,C0201_DIFF-BUS,5004.79,16083.36,270.000,NO,,,
C6703,"Q_CAP_DIFFBUS_C0201-DIFF BUS_0.22UF,6.3V,20%,X6S,SA",,,C0201_DIFF-BUS,5161.39,16083.36,270.000,NO,,,
C6704,"Q_CAP_DIFFBUS_C0201-DIFF BUS_0.22UF,6.3V,20%,X6S,SA",,,C0201_DIFF-BUS,5125.39,16083.36,270.000,NO,,,
C6705,"Q_CAP_DIFFBUS_C0201-DIFF BUS_0.22UF,6.3V,20%,X6S,SA",,,C0201_DIFF-BUS,5281.99,16083.36,270.000,NO,,,
C6706,"Q_CAP_DIFFBUS_C0201-DIFF BUS_0.22UF,6.3V,20%,X6S,SA",,,C0201_DIFF-BUS,5245.99,16083.36,270.000,NO,,,
C6707,"Q_CAP_DIFFBUS_C0201-DIFF BUS_0.22UF,6.3V,20%,X6S,SA",,,C0201_DIFF-BUS,5402.59,16083.36,270.000,NO,,,
C6708,"Q_CAP_DIFFBUS_C0201-DIFF BUS_0.22UF,6.3V,20%,X6S,SA",,,C0201_DIFF-BUS,5366.59,16083.36,270.000,NO,,,
C6709,"Q_CAP_DIFFBUS_C0201-DIFF BUS_0.22UF,6.3V,20%,X6S,SA",,,C0201_DIFF-BUS,5523.19,16083.36,270.000,NO,,,
C6710,"Q_CAP_DIFFBUS_C0201-DIFF BUS_0.22UF,6.3V,20%,X6S,SA",,,C0201_DIFF-BUS,5487.19,16083.36,270.000,NO,,,
C6711,"Q_CAP_DIFFBUS_C0201-DIFF BUS_0.22UF,6.3V,20%,X6S,SA",,,C0201_DIFF-BUS,5643.79,16083.36,270.000,NO,,,
C6712,"Q_CAP_DIFFBUS_C0201-DIFF BUS_0.22UF,6.3V,20%,X6S,SA",,,C0201_DIFF-BUS,5607.79,16083.36,270.000,NO,,,
C6713,"Q_CAP_DIFFBUS_C0201-DIFF BUS_0.22UF,6.3V,20%,X6S,SA",,,C0201_DIFF-BUS,5764.39,16083.36,270.000,NO,,,
C6714,"Q_CAP_DIFFBUS_C0201-DIFF BUS_0.22UF,6.3V,20%,X6S,SA",,,C0201_DIFF-BUS,5728.39,16083.36,270.000,NO,,,
C6715,"Q_CAP_DIFFBUS_C0201-DIFF BUS_0.22UF,6.3V,20%,X6S,SA",,,C0201_DIFF-BUS,5884.99,16083.36,270.000,NO,,,
C6716,"Q_CAP_DIFFBUS_C0201-DIFF BUS_0.22UF,6.3V,20%,X6S,SA",,,C0201_DIFF-BUS,5848.99,16083.36,270.000,NO,,,
C6717,"Q_CAP_DIFFBUS_C0201-DIFF BUS_0.22UF,6.3V,20%,X6S,SA",,,C0201_DIFF-BUS,6005.59,16083.36,270.000,NO,,,
C6718,"Q_CAP_DIFFBUS_C0201-DIFF BUS_0.22UF,6.3V,20%,X6S,SA",,,C0201_DIFF-BUS,5969.59,16083.36,270.000,NO,,,
C6719,"Q_CAP_DIFFBUS_C0201-DIFF BUS_0.22UF,6.3V,20%,X6S,SA",,,C0201_DIFF-BUS,6126.19,16083.36,270.000,NO,,,
C6720,"Q_CAP_DIFFBUS_C0201-DIFF BUS_0.22UF,6.3V,20%,X6S,SA",,,C0201_DIFF-BUS,6090.19,16083.36,270.000,NO,,,
C6721,"Q_CAP_DIFFBUS_C0201-DIFF BUS_0.22UF,6.3V,20%,X6S,SA",,,C0201_DIFF-BUS,6246.79,16083.36,270.000,NO,,,
C6722,"Q_CAP_DIFFBUS_C0201-DIFF BUS_0.22UF,6.3V,20%,X6S,SA",,,C0201_DIFF-BUS,6210.79,16083.36,270.000,NO,,,
C6723,"Q_CAP_DIFFBUS_C0201-DIFF BUS_0.22UF,6.3V,20%,X6S,SA",,,C0201_DIFF-BUS,6367.39,16083.36,270.000,NO,,,
C6724,"Q_CAP_DIFFBUS_C0201-DIFF BUS_0.22UF,6.3V,20%,X6S,SA",,,C0201_DIFF-BUS,6331.39,16083.36,270.000,NO,,,
C6725,"Q_CAP_DIFFBUS_C0201-DIFF BUS_0.22UF,6.3V,20%,X6S,SA",,,C0201_DIFF-BUS,4618.69,16083.36,90.000,YES,,,
C6726,"Q_CAP_DIFFBUS_C0201-DIFF BUS_0.22UF,6.3V,20%,X6S,SA",,,C0201_DIFF-BUS,4582.69,16083.36,90.000,YES,,,
C6727,"Q_CAP_DIFFBUS_C0201-DIFF BUS_0.22UF,6.3V,20%,X6S,SA",,,C0201_DIFF-BUS,4739.29,16083.36,90.000,YES,,,
C6728,"Q_CAP_DIFFBUS_C0201-DIFF BUS_0.22UF,6.3V,20%,X6S,SA",,,C0201_DIFF-BUS,4703.29,16083.36,90.000,YES,,,
C6729,"Q_CAP_DIFFBUS_C0201-DIFF BUS_0.22UF,6.3V,20%,X6S,SA",,,C0201_DIFF-BUS,4859.89,16083.36,90.000,YES,,,
C6730,"Q_CAP_DIFFBUS_C0201-DIFF BUS_0.22UF,6.3V,20%,X6S,SA",,,C0201_DIFF-BUS,4823.89,16083.36,90.000,YES,,,
C6731,"Q_CAP_DIFFBUS_C0201-DIFF BUS_0.22UF,6.3V,20%,X6S,SA",,,C0201_DIFF-BUS,4980.49,16083.36,90.000,YES,,,
C6732,"Q_CAP_DIFFBUS_C0201-DIFF BUS_0.22UF,6.3V,20%,X6S,SA",,,C0201_DIFF-BUS,4944.49,16083.36,90.000,YES,,,
C6733,"Q_CAP_DIFFBUS_C0201-DIFF BUS_0.22UF,6.3V,20%,X6S,SA",,,C0201_DIFF-BUS,5101.09,16083.36,90.000,YES,,,
C6734,"Q_CAP_DIFFBUS_C0201-DIFF BUS_0.22UF,6.3V,20%,X6S,SA",,,C0201_DIFF-BUS,5065.09,16083.36,90.000,YES,,,
C6735,"Q_CAP_DIFFBUS_C0201-DIFF BUS_0.22UF,6.3V,20%,X6S,SA",,,C0201_DIFF-BUS,5221.69,16083.36,90.000,YES,,,
C6736,"Q_CAP_DIFFBUS_C0201-DIFF BUS_0.22UF,6.3V,20%,X6S,SA",,,C0201_DIFF-BUS,5185.69,16083.36,90.000,YES,,,
C6737,"Q_CAP_DIFFBUS_C0201-DIFF BUS_0.22UF,6.3V,20%,X6S,SA",,,C0201_DIFF-BUS,5342.29,16083.36,90.000,YES,,,
C6738,"Q_CAP_DIFFBUS_C0201-DIFF BUS_0.22UF,6.3V,20%,X6S,SA",,,C0201_DIFF-BUS,5306.29,16083.36,90.000,YES,,,
C6739,"Q_CAP_DIFFBUS_C0201-DIFF BUS_0.22UF,6.3V,20%,X6S,SA",,,C0201_DIFF-BUS,5462.89,16083.36,90.000,YES,,,
C6740,"Q_CAP_DIFFBUS_C0201-DIFF BUS_0.22UF,6.3V,20%,X6S,SA",,,C0201_DIFF-BUS,5426.89,16083.36,90.000,YES,,,
C6741,"Q_CAP_DIFFBUS_C0201-DIFF BUS_0.22UF,6.3V,20%,X6S,SA",,,C0201_DIFF-BUS,5583.49,16083.36,90.000,YES,,,
C6742,"Q_CAP_DIFFBUS_C0201-DIFF BUS_0.22UF,6.3V,20%,X6S,SA",,,C0201_DIFF-BUS,5547.49,16083.36,90.000,YES,,,
C6743,"Q_CAP_DIFFBUS_C0201-DIFF BUS_0.22UF,6.3V,20%,X6S,SA",,,C0201_DIFF-BUS,5704.09,16083.36,90.000,YES,,,
C6744,"Q_CAP_DIFFBUS_C0201-DIFF BUS_0.22UF,6.3V,20%,X6S,SA",,,C0201_DIFF-BUS,5668.09,16083.36,90.000,YES,,,
C6745,"Q_CAP_DIFFBUS_C0201-DIFF BUS_0.22UF,6.3V,20%,X6S,SA",,,C0201_DIFF-BUS,5824.69,16083.36,90.000,YES,,,
C6746,"Q_CAP_DIFFBUS_C0201-DIFF BUS_0.22UF,6.3V,20%,X6S,SA",,,C0201_DIFF-BUS,5788.69,16083.36,90.000,YES,,,
C6747,"Q_CAP_DIFFBUS_C0201-DIFF BUS_0.22UF,6.3V,20%,X6S,SA",,,C0201_DIFF-BUS,5945.29,16083.36,90.000,YES,,,
C6748,"Q_CAP_DIFFBUS_C0201-DIFF BUS_0.22UF,6.3V,20%,X6S,SA",,,C0201_DIFF-BUS,5909.29,16083.36,90.000,YES,,,
C6749,"Q_CAP_DIFFBUS_C0201-DIFF BUS_0.22UF,6.3V,20%,X6S,SA",,,C0201_DIFF-BUS,6065.89,16083.36,90.000,YES,,,
C6750,"Q_CAP_DIFFBUS_C0201-DIFF BUS_0.22UF,6.3V,20%,X6S,SA",,,C0201_DIFF-BUS,6029.89,16083.36,90.000,YES,,,
C6751,"Q_CAP_DIFFBUS_C0201-DIFF BUS_0.22UF,6.3V,20%,X6S,SA",,,C0201_DIFF-BUS,6186.49,16083.36,90.000,YES,,,
C6752,"Q_CAP_DIFFBUS_C0201-DIFF BUS_0.22UF,6.3V,20%,X6S,SA",,,C0201_DIFF-BUS,6150.49,16083.36,90.000,YES,,,
C6753,"Q_CAP_DIFFBUS_C0201-DIFF BUS_0.22UF,6.3V,20%,X6S,SA",,,C0201_DIFF-BUS,6307.09,16083.36,90.000,YES,,,
C6754,"Q_CAP_DIFFBUS_C0201-DIFF BUS_0.22UF,6.3V,20%,X6S,SA",,,C0201_DIFF-BUS,6271.09,16083.36,90.000,YES,,,
C6755,"Q_CAP_DIFFBUS_C0201-DIFF BUS_0.22UF,6.3V,20%,X6S,SA",,,C0201_DIFF-BUS,6427.69,16083.36,90.000,YES,,,
C6756,"Q_CAP_DIFFBUS_C0201-DIFF BUS_0.22UF,6.3V,20%,X6S,SA",,,C0201_DIFF-BUS,6391.69,16083.36,90.000,YES,,,
C6757,"Q_CAP_0402-0.1UF,25V,10%,EMPTY,CH4104K1B00",NA,10%,C0402,9426.48,11378.43,180.000,NO,,,
C6758,"Q_CAP_0402-1000PF,50V,5%,X7R,TMP_QCH21006JB10",1000PF,5%,C0402,9382.32,11410.58,0.000,YES,,,
C7000,"Q_CAPP_SMLF-470UF,2.5V,20%,SPCAP,CH747LM8818",470UF,20%,TAJ_DXC,12731.28,16108.30,180.000,NO,,,
C7001,"Q_CAPP_SMLF-470UF,2.5V,20%,SPCAP,CH747LM8818",470UF,20%,TAJ_DXC,15373.02,16108.30,180.000,NO,,,
C7002,"Q_CAP_C0805-47UF,4V,20%,X6S,CH647KMEA04",47UF,20%,C0805_H57,15600.74,16147.42,90.000,NO,,,
C7003,"Q_CAP_C0805-47UF,4V,20%,X6S,CH647KMEA04",47UF,20%,C0805_H57,12959.60,16151.52,90.000,NO,,,
C7004,"Q_CAPP_SMLF-470UF,2.5V,20%,SPCAP,CH747LM8818",470UF,20%,TAJ_DXC,2653.15,15778.30,180.000,NO,,,
C7005,"Q_CAPP_SMLF-470UF,2.5V,20%,SPCAP,CH747LM8818",470UF,20%,TAJ_DXC,5294.28,15778.30,180.000,NO,,,
C7006,"Q_CAP_C0805-47UF,4V,20%,X6S,CH647KMEA04",47UF,20%,C0805_H57,5524.00,15821.52,90.000,NO,,,
C7007,"Q_CAP_C0805-47UF,4V,20%,X6S,CH647KMEA04",47UF,20%,C0805_H57,2927.47,15822.22,90.000,NO,,,
C7008,"Q_CAPP_SMLF-470UF,2.5V,20%,SPCAP,CH747LM8818",470UF,20%,TAJ_DXC,12145.55,15334.45,180.000,YES,,,
C7009,"Q_CAPP_SMLF-470UF,2.5V,20%,SPCAP,CH747LM8818",470UF,20%,TAJ_DXC,12518.41,15334.45,0.000,YES,,,
C7010,"Q_CAP_C0805-100UF,4V,20%,X6S,CH710KMEA01",100UF,20%,C0805_H61,11872.52,15332.47,0.000,YES,,,
C7011,"Q_CAPP_SMLF-470UF,2.5V,20%,SPCAP,CH747LM8818",470UF,20%,TAJ_DXC,13426.17,15334.45,180.000,YES,,,
C7012,"Q_CAPP_SMLF-470UF,2.5V,20%,SPCAP,CH747LM8818",470UF,20%,TAJ_DXC,13799.03,15334.45,0.000,YES,,,
C7013,"Q_CAP_C0805-100UF,4V,20%,X6S,CH710KMEA01",100UF,20%,C0805_H61,13153.52,15353.45,0.000,YES,,,
C7014,"Q_CAPP_SMLF-470UF,2.5V,20%,SPCAP,CH747LM8818",470UF,20%,TAJ_DXC,16440.77,15334.45,0.000,YES,,,
C7015,"Q_CAPP_SMLF-470UF,2.5V,20%,SPCAP,CH747LM8818",470UF,20%,TAJ_DXC,16067.91,15334.45,180.000,YES,,,
C7016,"Q_CAP_C0805-100UF,4V,20%,X6S,CH710KMEA01",100UF,20%,C0805_H61,15794.92,15355.71,0.000,YES,,,
C7017,"Q_CAPP_SMLF-470UF,2.5V,20%,SPCAP,CH747LM8818",470UF,20%,TAJ_DXC,14787.29,15334.45,180.000,YES,,,
C7018,"Q_CAPP_SMLF-470UF,2.5V,20%,SPCAP,CH747LM8818",470UF,20%,TAJ_DXC,15160.15,15334.45,0.000,YES,,,
C7019,"Q_CAP_C0805-100UF,4V,20%,X6S,CH710KMEA01",100UF,20%,C0805_H61,14515.82,15357.43,0.000,YES,,,
C7020,"Q_CAPP_SMLF-470UF,2.5V,20%,SPCAP,CH747LM8818",470UF,20%,TAJ_DXC,2439.68,15004.45,0.000,YES,,,
C7021,"Q_CAPP_SMLF-470UF,2.5V,20%,SPCAP,CH747LM8818",470UF,20%,TAJ_DXC,2066.82,15004.45,180.000,YES,,,
C7022,"Q_CAP_C0805-100UF,4V,20%,X6S,CH710KMEA01",100UF,20%,C0805_H61,1808.22,15024.50,0.000,YES,,,
C7023,"Q_CAPP_SMLF-470UF,2.5V,20%,SPCAP,CH747LM8818",470UF,20%,TAJ_DXC,3720.30,15004.45,0.000,YES,,,
C7024,"Q_CAPP_SMLF-470UF,2.5V,20%,SPCAP,CH747LM8818",470UF,20%,TAJ_DXC,3347.44,15004.45,180.000,YES,,,
C7025,"Q_CAP_C0805-100UF,4V,20%,X6S,CH710KMEA01",100UF,20%,C0805_H61,3073.72,15009.38,0.000,YES,,,
C7026,"Q_CAPP_SMLF-470UF,2.5V,20%,SPCAP,CH747LM8818",470UF,20%,TAJ_DXC,6362.03,15004.45,0.000,YES,,,
C7027,"Q_CAPP_SMLF-470UF,2.5V,20%,SPCAP,CH747LM8818",470UF,20%,TAJ_DXC,5989.17,15004.45,180.000,YES,,,
C7028,"Q_CAP_C0805-100UF,4V,20%,X6S,CH710KMEA01",100UF,20%,C0805_H61,5716.42,15019.85,0.000,YES,,,
C7029,"Q_CAPP_SMLF-470UF,2.5V,20%,SPCAP,CH747LM8818",470UF,20%,TAJ_DXC,4708.55,15004.45,180.000,YES,,,
C7030,"Q_CAPP_SMLF-470UF,2.5V,20%,SPCAP,CH747LM8818",470UF,20%,TAJ_DXC,5081.41,15004.45,0.000,YES,,,
C7031,"Q_CAP_C0805-100UF,4V,20%,X6S,CH710KMEA01",100UF,20%,C0805_H61,4434.02,15012.67,0.000,YES,,,
C7032,"Q_CAPP_SMLF-470UF,2.5V,20%,SPCAP,CH747LM8818",470UF,20%,TAJ_DXC,12355.50,16106.48,0.000,NO,,,
C7033,"Q_CAP_C0805-47UF,4V,20%,X6S,CH647KMEA04",47UF,20%,C0805_H57,12057.58,16157.74,90.000,NO,,,
C7034,"Q_CAP_C0805-47UF,4V,20%,X6S,CH647KMEA04",47UF,20%,C0805_H57,12126.08,16157.74,90.000,NO,,,
C7035,"Q_CAP_C0805-47UF,4V,20%,X6S,CH647KMEA04",47UF,20%,C0805_H57,13029.08,16151.64,90.000,NO,,,
C7036,"Q_CAP_C0805-47UF,4V,20%,X6S,CH647KMEA04",47UF,20%,C0805_H57,15669.78,16148.64,90.000,NO,,,
C7037,"Q_CAPP_SMLF-470UF,2.5V,20%,SPCAP,CH747LM8818",470UF,20%,TAJ_DXC,2279.10,15777.78,0.000,NO,,,
C7038,"Q_CAP_C0805-47UF,4V,20%,X6S,CH647KMEA04",47UF,20%,C0805_H57,2047.68,15826.34,90.000,NO,,,
C7039,"Q_CAP_C0805-47UF,4V,20%,X6S,CH647KMEA04",47UF,20%,C0805_H57,2999.38,15823.84,90.000,NO,,,
C7040,"Q_CAP_C0805-47UF,4V,20%,X6S,CH647KMEA04",47UF,20%,C0805_H57,5593.48,15822.24,90.000,NO,,,
C7041,"Q_CAP_C0805-47UF,4V,20%,X6S,CH647KMEA04",47UF,20%,C0805_H57,1978.53,15826.10,90.000,NO,,,
C7500,"Q_CAP_C0201-0.1UF,10V,10%,X7S,CH4102K6E00",0.1UF,10%,C0201,8885.00,13075.00,0.000,YES,,,
C7501,"Q_CAP_C0201-0.1UF,10V,10%,X7S,CH4102K6E00",0.1UF,10%,C0201,4123.69,15635.20,180.000,NO,,,
C7502,"Q_CAP_C0201-0.1UF,10V,10%,X7S,CH4102K6E00",0.1UF,10%,C0201,4356.08,15639.07,180.000,NO,,,
C7503,"Q_CAP_C0201-0.1UF,10V,10%,X7S,CH4102K6E00",0.1UF,10%,C0201,6508.00,16524.00,180.000,NO,,,
C7504,"Q_CAP_C0201-0.1UF,10V,10%,X7S,CH4102K6E00",0.1UF,10%,C0201,6755.86,16527.59,180.000,NO,,,
C7510,"Q_CAP_C0201-0.1UF,10V,10%,X7S,CH4102K6E00",0.1UF,10%,C0201,11903.34,16652.26,90.000,NO,,,
C8000,"Q_CAP_0402-1000PF,50V,5%,EMPTY,TMP_QCH21006JB10",NA,5%,C0402,3842.17,16739.85,0.000,YES,,,
C8001,"Q_CAP_0402-0.1UF,25V,10%,EMPTY,CH4104K1B00",NA,10%,C0402,400.00,3195.00,270.000,YES,,,
C8002,"Q_CAP_0402-0.1UF,25V,10%,EMPTY,CH4104K1B00",NA,10%,C0402,365.00,3195.00,270.000,YES,,,
C8003,"Q_CAP_0402-0.1UF,25V,10%,EMPTY,CH4104K1B00",NA,10%,C0402,660.00,2900.00,0.000,NO,,,
C8004,"Q_CAP_0402-0.1UF,25V,10%,EMPTY,CH4104K1B00",NA,10%,C0402,525.00,3035.00,0.000,NO,,,
C8005,"Q_CAP_0402-0.1UF,25V,10%,X7R,CH4104K1B00",0.1UF,10%,C0402,8224.11,4230.99,0.000,NO,,,
C8006,"Q_CAP_0402-0.1UF,25V,10%,X7R,CH4104K1B00",0.1UF,10%,C0402,10230.00,4020.00,180.000,NO,,,
C8007,"Q_CAP_0402-0.1UF,25V,10%,X7R,CH4104K1B00",0.1UF,10%,C0402,7407.03,5692.45,180.000,YES,,,
C8008,"Q_CAP_0402-0.1UF,25V,10%,X7R,CH4104K1B00",0.1UF,10%,C0402,16370.00,3815.00,180.000,NO,,,
C8009,"Q_CAP_0402-0.1UF,25V,10%,X7R,CH4104K1B00",0.1UF,10%,C0402,3120.00,2410.00,180.000,NO,,,
C8010,"Q_CAP_0402-0.1UF,25V,10%,X7R,CH4104K1B00",0.1UF,10%,C0402,8795.00,3015.00,180.000,NO,,,
C8011,"Q_CAP_0402-0.1UF,25V,10%,EMPTY,CH4104K1B00",NA,10%,C0402,7673.81,16717.41,90.000,NO,,,
C8012,"Q_CAP_C0402-1UF,25V,10%,EMPTY,CH5104KEB02",NA,10%,C0402,7850.00,5680.00,90.000,YES,,,
C8013,"Q_CAP_0402-0.1UF,25V,10%,EMPTY,CH4104K1B00",NA,10%,C0402,7915.00,5430.00,90.000,YES,,,
C8014,"Q_CAP_C0402-100NF,50V,10%,EMPTY,CH4106K1B01",NA,10%,C0402,7365.00,16630.00,0.000,YES,,,
C8015,"Q_CAP_C0402-100NF,50V,10%,EMPTY,CH4106K1B01",NA,10%,C0402,7263.02,16622.38,90.000,YES,,,
C8016,"Q_CAP_C0402-100NF,50V,10%,EMPTY,CH4106K1B01",NA,10%,C0402,7397.26,16888.39,0.000,YES,,,
C8017,"Q_CAP_C0402-100NF,50V,10%,EMPTY,CH4106K1B01",NA,10%,C0402,5015.00,4280.00,90.000,NO,,,
C8018,"Q_CAP_C0402-100NF,50V,10%,EMPTY,CH4106K1B01",NA,10%,C0402,5185.00,4310.00,270.000,NO,,,
C8019,"Q_CAP_C0402-100NF,50V,10%,X7R,CH4106K1B01",100NF,10%,C0402,5380.00,4455.00,0.000,NO,,,
C8020,"Q_CAP_C0402-100NF,50V,10%,EMPTY,CH4106K1B01",NA,10%,C0402,5620.00,4510.00,0.000,NO,,,
C8021,"Q_CAP_C0402-100NF,50V,10%,EMPTY,CH4106K1B01",NA,10%,C0402,5735.00,4660.00,0.000,NO,,,
C8022,"Q_CAP_C0402-100NF,50V,10%,X7R,CH4106K1B01",100NF,10%,C0402,5475.00,4590.00,180.000,NO,,,
C8066,"Q_CAP_0402-1000PF,50V,5%,X7R,TMP_QCH21006JB10",1000PF,5%,C0402,11378.46,14579.48,270.000,NO,,,
C8069,"Q_CAP_0402-1000PF,50V,5%,X7R,TMP_QCH21006JB10",1000PF,5%,C0402,11985.00,14285.00,180.000,NO,,,
C8070,"Q_CAP_0402-1000PF,50V,5%,EMPTY,TMP_QCH21006JB10",NA,5%,C0402,11985.00,14330.00,180.000,NO,,,
C8072,"Q_CAP_0402-1000PF,50V,5%,EMPTY,TMP_QCH21006JB10",NA,5%,C0402,11985.00,14145.00,180.000,NO,,,
C8246,"Q_CAP_0402-1000PF,50V,5%,EMPTY,TMP_QCH21006JB10",NA,5%,C0402,3551.57,5744.15,0.000,YES,,,
C8356,"Q_CAP_0402-1000PF,50V,5%,X7R,TMP_QCH21006JB10",1000PF,5%,C0402,763.78,14106.55,270.000,NO,,,
C8359,"Q_CAP_0402-1000PF,50V,5%,X7R,TMP_QCH21006JB10",1000PF,5%,C0402,975.00,14355.00,180.000,NO,,,
C8360,"Q_CAP_0402-1000PF,50V,5%,EMPTY,TMP_QCH21006JB10",NA,5%,C0402,975.00,14400.00,180.000,NO,,,
C8362,"Q_CAP_0402-1000PF,50V,5%,EMPTY,TMP_QCH21006JB10",NA,5%,C0402,975.00,14260.00,180.000,NO,,,
C8641,"Q_CAP_0402-1000PF,50V,5%,EMPTY,TMP_QCH21006JB10",NA,5%,C0402,6208.38,13828.64,180.000,NO,,,
C9000,"Q_CAP_0402-1000PF,50V,5%,EMPTY,TMP_QCH21006JB10",NA,5%,C0402,14344.97,16235.04,180.000,NO,,,
C9001,"Q_CAP_0402-1000PF,50V,5%,EMPTY,TMP_QCH21006JB10",NA,5%,C0402,6793.05,16358.42,180.000,NO,,,
C9002,"Q_CAP_0402-1000PF,50V,5%,EMPTY,TMP_QCH21006JB10",NA,5%,C0402,14343.09,16139.04,180.000,NO,,,
C9003,"Q_CAP_C0402-1UF,25V,10%,EMPTY,CH5104KEB02",NA,10%,C0402,7097.71,16589.65,90.000,YES,,,
C9004,"Q_CAP_C0402-1UF,25V,10%,EMPTY,CH5104KEB02",NA,10%,C0402,5865.00,4595.00,270.000,NO,,,
C9005,"Q_CAP_0402-0.1UF,25V,10%,X7R,CH4104K1B00",0.1UF,10%,C0402,6380.00,4240.00,90.000,NO,,,
C9007,"Q_CAP_0402-0.1UF,25V,10%,X7R,CH4104K1B00",0.1UF,10%,C0402,6045.00,4120.00,0.000,NO,,,
C9008,"Q_CAP_0402-0.1UF,25V,10%,X7R,CH4104K1B00",0.1UF,10%,C0402,8605.00,3955.00,0.000,NO,,,
C9050,"Q_CAP_0402-0.1UF,25V,10%,X7R,CH4104K1B00",0.1UF,10%,C0402,8542.00,4012.80,180.000,NO,,,
C9051,"Q_CAP_0402-0.1UF,25V,10%,X7R,CH4104K1B00",0.1UF,10%,C0402,2552.70,2134.70,270.000,NO,,,
C9102,"Q_CAP_DIFFBUS_C0201-DIFF BUS_0.22UF,6.3V,20%,X6S,SA",,,C0201_DIFF-BUS,7107.42,1855.87,0.000,NO,,,
C9103,"Q_CAP_DIFFBUS_C0201-DIFF BUS_0.22UF,6.3V,20%,X6S,SA",,,C0201_DIFF-BUS,7107.42,1891.87,0.000,NO,,,
C9104,"Q_CAP_DIFFBUS_C0201-DIFF BUS_0.22UF,6.3V,20%,X6S,SA",,,C0201_DIFF-BUS,7107.42,1735.87,0.000,NO,,,
C9105,"Q_CAP_DIFFBUS_C0201-DIFF BUS_0.22UF,6.3V,20%,X6S,SA",,,C0201_DIFF-BUS,7107.42,1771.87,0.000,NO,,,
C9226,"Q_CAP_C0402-0.22UF,25V,10%,X7R,CH4224K1B01",0.22UF,10%,C0402,15678.36,5724.47,90.000,YES,,,
C9922,"Q_CAP_C0603-22UF,6.3V,20%,X6S,CH6221ME900",22UF,20%,C0603,6697.70,1972.72,180.000,YES,,,
C10179,"Q_CAP_C0402-22UF,4V,20%,X6S,CH622KMEB02",22UF,20%,C0402_H32,14403.01,9817.65,0.000,YES,,,
D1,"BAT547F-BAT547F,SMLF,IC,BC0BAT54Z53",,,SOT23_123XB,16715.72,2101.91,180.000,NO,,,
D5,"Q_LED_SMLF-LED_BLUE,LTST-C281TBKT-5A,IC,BEBL0172Z00",,,LED2S_0402,13374.40,626.94,90.000,NO,,,
D6,"Q_LED_SMLF-LED_YELLOW,LTST-C190KSKT-P,IC,BEYL0159ZA",,,LED_1921XA,13493.50,636.94,90.000,NO,,,
D7,"Q_LED_SMLF-LED_YELLOW,LTST-C190KSKT-P,IC,BEYL0159ZA",,,LED_1921XA,13017.10,636.94,90.000,NO,,,
D8,"Q_LED_SMLF-LED_YELLOW,LTST-C190KSKT-P,IC,BEYL0159ZA",,,LED_1921XA,13136.20,636.94,90.000,NO,,,
D9,"Q_LED_SMLF-LED_BLUE,LTST-C281TBKT-5A,IC,BEBL0172Z00",,,LED2S_0402,13255.30,626.94,90.000,NO,,,
D46,"Q_LED_SMLF-LED_BLUE,LTST-C281TBKT-5A,IC,BEBL0172Z00",,,LED2S_0402,13737.50,626.94,90.000,NO,,,
D49,"Q_LED_SMLF-LED_BLUE,LTST-C281TBKT-5A,IC,BEBL0172Z00",,,LED2S_0402,13615.50,626.94,90.000,NO,,,
D73,"Q_LED_SMLF-LED_BLUE,LTST-C281TBKT-5A,IC,BEBL0172Z00",,,LED2S_0402,12700.94,2759.78,90.000,NO,,,
D74,"Q_LED_SMLF-LED_BLUE,LTST-C281TBKT-5A,IC,BEBL0172Z00",,,LED2S_0402,12780.94,2759.78,90.000,NO,,,
D75,"Q_LED_SMLF-LED_BLUE,LTST-C281TBKT-5A,IC,BEBL0172Z00",,,LED2S_0402,12860.94,2759.78,90.000,NO,,,
D76,"Q_LED_SMLF-LED_BLUE,LTST-C281TBKT-5A,IC,BEBL0172Z00",,,LED2S_0402,12940.94,2759.78,90.000,NO,,,
D77,"Q_LED_SMLF-LED_BLUE,LTST-C281TBKT-5A,IC,BEBL0172Z00",,,LED2S_0402,13020.94,2759.78,90.000,NO,,,
D78,"Q_LED_SMLF-LED_BLUE,LTST-C281TBKT-5A,IC,BEBL0172Z00",,,LED2S_0402,13100.94,2759.78,90.000,NO,,,
D79,"Q_LED_SMLF-LED_BLUE,LTST-C281TBKT-5A,IC,BEBL0172Z00",,,LED2S_0402,13180.94,2759.78,90.000,NO,,,
D80,"Q_LED_SMLF-LED_BLUE,LTST-C281TBKT-5A,IC,BEBL0172Z00",,,LED2S_0402,13260.94,2759.78,90.000,NO,,,
D81,"Q_LED_SMLF-LED_BLUE,LTST-C281TBKT-5A,IC,BEBL0172Z00",,,LED2S_0402,13340.94,2759.78,90.000,NO,,,
D82,"Q_LED_SMLF-LED_BLUE,LTST-C281TBKT-5A,IC,BEBL0172Z00",,,LED2S_0402,13420.94,2759.78,90.000,NO,,,
D83,"Q_LED_SMLF-LED_BLUE,LTST-C281TBKT-5A,IC,BEBL0172Z00",,,LED2S_0402,13500.94,2759.78,90.000,NO,,,
D84,"Q_LED_SMLF-LED_BLUE,LTST-C281TBKT-5A,IC,BEBL0172Z00",,,LED2S_0402,13580.94,2759.78,90.000,NO,,,
D85,"Q_LED_SMLF-LED_BLUE,LTST-C281TBKT-5A,IC,BEBL0172Z00",,,LED2S_0402,13660.94,2759.78,90.000,NO,,,
D88,"Q_LED_SMLF-LED_BLUE,LTST-C281TBKT-5A,IC,BEBL0172Z00",,,LED2S_0402,12300.94,2759.78,90.000,NO,,,
D91,"Q_LED_SMLF-LED_BLUE,LTST-C281TBKT-5A,IC,BEBL0172Z00",,,LED2S_0402,12540.94,2759.78,90.000,NO,,,
D93,"Q_LED_SMLF-LED_BLUE,LTST-C281TBKT-5A,IC,BEBL0172Z00",,,LED2S_0402,12220.94,2759.78,90.000,NO,,,
D96,"Q_LED_SMLF-LED_BLUE,LTST-C281TBKT-5A,IC,BEBL0172Z00",,,LED2S_0402,12620.94,2759.78,90.000,NO,,,
D98,"Q_LED_SMLF-LED_BLUE,LTST-C281TBKT-5A,IC,BEBL0172Z00",,,LED2S_0402,12380.94,2759.78,90.000,NO,,,
D99,"Q_LED_SMLF-LED_BLUE,LTST-C281TBKT-5A,IC,BEBL0172Z00",,,LED2S_0402,12460.94,2759.78,90.000,NO,,,
D6000,"Q_LED_SMLF-LED_BLUE,LTST-C281TBKT-5A,IC,BEBL0172Z00",,,LED2S_0402,12140.94,2759.78,90.000,NO,,,
D8000,"Q_LED_SMLF-LED_BLUE,LTST-C281TBKT-5A,IC,BEBL0172Z00",,,LED2S_0402,14201.19,2444.50,180.000,NO,,,
D8001,"Q_LED_SMLF-LED_BLUE,LTST-C281TBKT-5A,IC,BEBL0172Z00",,,LED2S_0402,1503.18,2289.58,90.000,NO,,,
D8002,"Q_LED_SMLF-LED_YELLOW,LTST-C190KSKT-P,IC,BEYL0159ZA",,,LED_1921XA,7535.00,1995.00,90.000,NO,,,
D8003,"SCHOTTKY_12-B0530WS7F,SMLF,EMPTY,BC000530Z41",,,SOD323XB,8055.00,4095.00,0.000,NO,,,
D8004,"SCHOTTKY_12-B0530WS7F,SMLF,EMPTY,BC000530Z41",,,SOD323XB,8065.00,3995.00,0.000,NO,,,
D8005,"SCHOTTKY_12-B0530WS7F,SMLF,EMPTY,BC000530Z41",,,SOD323XB,5890.00,4860.00,180.000,NO,,,
D8006,"SCHOTTKY_12-B0530WS7F,SMLF,EMPTY,BC000530Z41",,,SOD323XB,7940.00,3660.00,0.000,NO,,,
DB1,"TDR_3P_TH2-EMPTY,N_A",,,TDR_3P_C85P67_141_100M_Q,18882.73,8376.32,0.000,NO,,,
DB2,"TDR_3P_TH2-EMPTY,N_A",,,TDR_3P_C85P67_141_100M_Q,18877.11,4636.80,0.000,NO,,,
DB3,"TDR_3P_TH2-EMPTY,N_A",,,TDR_3P_C85P67_141_100M_Q,18872.40,7966.58,180.000,NO,,,
DB4,"TDR_3P_TH2-EMPTY,N_A",,,TDR_3P_C85P67_141_100M_Q,18875.79,11715.32,180.000,NO,,,
DB5,"TDR_3P_TH2-EMPTY,N_A",,,TDR_3P_C85P67_141_100M_Q,18667.90,4633.89,0.000,YES,,,
DB6,"TDR_3P_TH2-EMPTY,N_A",,,TDR_3P_C85P67_141_100M_Q,18667.90,11712.55,180.000,YES,,,
DB7,"TDR_3P_TH2-EMPTY,N_A",,,TDR_3P_C85P67_141_100M_Q,18647.06,17221.95,180.000,NO,,,
DB8,"TDR_3P_TH2-EMPTY,N_A",,,TDR_3P_C85P67_141_100M_Q,18649.86,13902.34,0.000,NO,,,
DB9,"TDR_3P_TH2-EMPTY,N_A",,,TDR_3P_C85P67_141_100M_Q,18868.62,941.07,0.000,NO,,,
DB10,"TDR_3P_TH2-EMPTY,N_A",,,TDR_3P_C85P67_141_100M_Q,18873.40,4240.13,180.000,NO,,,
DB11,"TDR_3P_TH2-EMPTY,N_A",,,TDR_3P_C85P67_141_100M_Q,18861.77,17225.07,180.000,YES,,,
DB12,"TDR_3P_TH2-EMPTY,N_A",,,TDR_3P_C85P67_141_100M_Q,20761.28,4240.13,180.000,YES,,,
DB13,"TDR_3P_TH2-EMPTY,N_A",,,TDR_3P_C85P67_141_100M_Q,18656.48,7969.13,180.000,YES,,,
DB14,"TDR_3P_TH2-EMPTY,N_A",,,TDR_3P_C85P67_141_100M_Q,18672.95,8375.83,0.000,YES,,,
DB15,"TDR_3P_TH2-EMPTY,N_A",,,TDR_3P_C85P67_141_100M_Q,18862.23,13912.83,0.000,YES,,,
DB16,"TDR_3P_TH2-EMPTY,N_A",,,TDR_3P_C85P67_141_100M_Q,20770.12,951.28,0.000,YES,,,
FS1,"Q_FUSE_SMLF-20A/125V,IC,DKK00XFU000",,,F4012,9291.47,16417.23,0.000,NO,,,
H2,"HOLE_TH-EMPTY,HOLE1226",,,HOLE_C6-2D3-73B6-2I5-53_RO6-53_NPB,18245.66,15709.88,0.000,NO,,,
H3,"HOLE_TH-EMPTY,HOLE1226",,,HOLE_C6-2D3-73B6-2I5-53_RO6-53_NPB,270.48,15332.28,0.000,NO,,,
H5,"HOLE_TH-EMPTY,HOLE1226",,,HOLE_C6-2D3-73B6-2I5-53_RO6-53_NPB,1372.84,15332.28,0.000,NO,,,
H8,"HOLE_TH-EMPTY,HOLE1226",,,HOLE_C6-2D3-73B6-2I5-53_RO6-53_NPB,8736.22,11452.75,0.000,NO,,,
H10,"HOLE_TH-EMPTY,HOLE1226",,,HOLE_C6-2D3-73B6-2I5-53_RO6-53_NPB,17143.30,15709.84,0.000,NO,,,
H11,"HOLE_TH-EMPTY,HOLE1226",,,HOLE_C6-2D3-73B6-2I5-53_RO6-53_NPB,795.90,13693.50,0.000,NO,,,
H12,"HOLE_TH-EMPTY,HOLE1226",,,HOLE_C6-2D3-73B6-2I5-53_RO6-53_NPB,9838.58,11452.75,0.000,NO,,,
H13,"HOLE_TH-EMPTY,HOLE1226",,,HOLE_C6-2D3-73B6-2I5-53_RO6-53_NPB,2764.40,13575.39,0.000,NO,,,
H21,"HOLE_TH-EMPTY,HOLE1226",,,HOLE_C6-2D3-73B6-2I5-53_RO6-53_NPB,4437.64,13398.23,0.000,NO,,,
H22,"HOLE_TH-EMPTY,HOLE1226",,,HOLE_C6-2D3-73B6-2I5-53_RO6-53_NPB,6814.40,13851.38,0.000,NO,,,
H27,"HOLE_TH-EMPTY,DUMMY50",,,HOLE_TOOLINGD125N_T2-0,18046.50,16672.92,0.000,NO,,,
H28,"HOLE_TH-EMPTY,DUMMY50",,,HOLE_TOOLINGD125N_T2-0,440.00,1542.00,0.000,NO,,,
H29,"HOLE_TH-EMPTY,DUMMY50",,,HOLE_TOOLINGD125N_T2-0,18004.49,1261.94,0.000,NO,,,
H30,"HOLE_TH-EMPTY,DUMMY50",,,HOLE_TOOLINGD125N_T2-0,318.18,14242.57,0.000,NO,,,
H31,"HOLE_TH-EMPTY,HOLE1248",,,HOLE_C4-5D3-8B8I5-6_RO6-6_NPT_RB,2770.98,1852.36,0.000,NO,,,
H32,"HOLE_TH-EMPTY,HOLE1248",,,HOLE_C4-5D3-8B8I5-6_RO6-6_NPT_RB,3952.08,1852.36,0.000,NO,,,
H33,"HOLE_TH-EMPTY,HOLE1226",,,HOLE_C6-2D3-73B6-2I5-53_RO6-53_NPB,16297.32,13835.23,0.000,NO,,,
H34,"HOLE_TH-EMPTY,HOLE1226",,,HOLE_C6-2D3-73B6-2I5-53_RO6-53_NPB,17399.68,13835.27,0.000,NO,,,
H37,"HOLE_TH-EMPTY,HOLE1226",,,HOLE_C6-2D3-73B6-2I5-53_RO6-53_NPB,12498.12,13575.39,0.000,NO,,,
H38,"HOLE_TH-EMPTY,HOLE1226",,,HOLE_C6-2D3-73B6-2I5-53_RO6-53_NPB,15335.52,6823.42,0.000,NO,,,
H43,"HOLE_TH-EMPTY,HOLE1226",,,HOLE_C6-2D3-73B6-2I5-53_RO6-53_NPB,4201.25,6560.08,0.000,NO,,,
H44,"HOLE_TH-EMPTY,HOLE1226",,,HOLE_C6-2D3-73B6-2I5-53_RO6-53_NPB,14171.34,13398.23,0.000,NO,,,
H49,"HOLE_TH-EMPTY,HOLE1226",,,HOLE_C6-2D3-73B6-2I5-53_RO6-53_NPB,7916.78,13851.38,0.000,NO,,,
H50,"HOLE_TH-EMPTY,HOLE1226",,,HOLE_C6-2D3-73B6-2I5-53_RO6-53_NPB,10529.60,13693.50,0.000,NO,,,
H53,"HOLE_TH-EMPTY,HOLE1226",,,HOLE_C6-2D3-73B6-2I5-53_RO6-53_NPB,16648.90,6429.72,0.000,NO,,,
H54,"HOLE_TH-EMPTY,HOLE1226",,,HOLE_C6-2D3-73B6-2I5-53_RO6-53_NPB,13702.84,5823.03,0.000,NO,,,
H74,"HOLE_TH-EMPTY,HOLE1247",,,H_OB6-4X8OBD3-2X4-8B6-4X8N_RO6X7-6_NPM,2503.26,1852.36,90.000,NO,,,
H75,"HOLE_TH-EMPTY,HOLE1247",,,H_OB6-4X8OBD3-2X4-8B6-4X8N_RO6X7-6_NPM,3684.37,1852.36,90.000,NO,,,
H76,"HOLE_TH-EMPTY,HOLE1187",,,HOLE_R4-2X5D2B4_IX0-1T_NPM_RB,9446.85,1551.97,0.000,NO,,,
H77,"HOLE_TH-EMPTY,HOLE1187",,,HOLE_R4-2X5D2B4_IX0-1T_NPM_RB,9001.97,1751.77,0.000,NO,,,
H86,"HOLE_TH-EMPTY,HOLE596",,,HOLE_C10D5-6B10_NPB,10458.66,877.95,0.000,NO,,,
H87,"HOLE_TH-EMPTY,HOLE596",,,HOLE_C10D5-6B10_NPB,14996.06,877.95,0.000,NO,,,
H88,"HOLE_TH-EMPTY,HOLE596",,,HOLE_C10D5-6B10_NPB,407.08,6318.89,0.000,NO,,,
H89,"HOLE_TH-EMPTY,HOLE596",,,HOLE_C10D5-6B10_NPB,6610.24,6318.90,0.000,NO,,,
H90,"HOLE_TH-EMPTY,HOLE372",,,HOLE_C5D3-1N,17669.29,17149.60,0.000,NO,,,
H91,"HOLE_TH-EMPTY,HOLE596",,,HOLE_C10D5-6B10_NPB,275.59,877.95,0.000,NO,,,
H92,"HOLE_TH-EMPTY,HOLE596",,,HOLE_C10D5-6B10_NPB,8007.87,877.95,0.000,NO,,,
H93,"HOLE_TH-EMPTY,HOLE596",,,HOLE_C10D5-6B10_NPB,3736.22,877.95,0.000,NO,,,
H94,"HOLE_TH-EMPTY,HOLE596",,,HOLE_C10D5-6B10_NPB,3956.71,17149.60,0.000,NO,,,
H95,"HOLE_TH-EMPTY,HOLE596",,,HOLE_C10D5-6B10_NPB,18167.72,13688.97,0.000,NO,,,
H96,"HOLE_TH-EMPTY,HOLE596",,,HOLE_C10D5-6B10_NPB,18299.21,877.95,0.000,NO,,,
H97,"HOLE_TH-EMPTY,HOLE596",,,HOLE_C10D5-6B10_NPB,511.80,17149.61,0.000,NO,,,
H98,"HOLE_TH-EMPTY,HOLE596",,,HOLE_C10D5-6B10_NPB,18167.72,6318.89,0.000,NO,,,
H99,"HOLE_TH-EMPTY,HOLE596",,,HOLE_C10D5-6B10_NPB,9316.93,7578.74,0.000,NO,,,
H100,"HOLE_TH-EMPTY,HOLE596",,,HOLE_C10D5-6B10_NPB,9316.92,10728.35,0.000,NO,,,
H101,"HOLE_TH-EMPTY,HOLE596",,,HOLE_C10D5-6B10_NPB,12712.60,6318.90,0.000,NO,,,
H102,"HOLE_TH-EMPTY,HOLE596",,,HOLE_C10D5-6B10_NPB,407.08,13689.08,0.000,NO,,,
H103,"HOLE_TH-EMPTY,HOLE596",,,HOLE_C10D5-6B10_NPB,18062.98,17149.61,0.000,NO,,,
H104,"HOLE_TH-EMPTY,HOLE596",,,HOLE_C10D5-6B10_NPB,11557.09,17149.61,0.000,NO,,,
H105,"HOLE_TH-EMPTY,HOLE596",,,HOLE_C10D5-6B10_NPB,9316.93,13877.95,0.000,NO,,,
H106,"HOLE_TH-EMPTY,HOLE596",,,HOLE_C10D5-6B10_NPB,7076.77,17149.60,0.000,NO,,,
H111,"GND_HOLE_TH-EMPTY,TMP-QGND_HOLE12",,,GND_C8D4B8,8412.40,14203.31,0.000,NO,,,
H112,"GND_HOLE_TH-EMPTY,TMP-QGND_HOLE12",,,GND_C8D4B8,10162.40,14203.31,0.000,NO,,,
H113,"GND_HOLE_TH-EMPTY,GND_HOLE140",,,GND_C10D5-5B10,8056.90,2047.24,0.000,NO,,,
H114,"GND_HOLE_TH-EMPTY,GND_HOLE140",,,GND_C10D5-5B10,10576.59,2047.24,0.000,NO,,,
H115,"GND_HOLE_TH-EMPTY,GND_HOLE514",,,GND_C10D6-5B10_NPM_RB_NSP,9287.40,3216.54,180.000,NO,,,
H124,"HOLE_TH-EMPTY,TMP-C_T2I_ALEX_1121_1",,,HOLE_D10N,17397.45,6054.11,0.000,NO,,,
H125,"HOLE_TH-EMPTY,TMP-C_T2I_ALEX_1121_1",,,HOLE_D10N,10940.76,6053.78,0.000,NO,,,
H126,"HOLE_TH-EMPTY,TMP-C_T2I_ALEX_1121_1",,,HOLE_D10N,7636.02,6054.13,0.000,NO,,,
H127,"HOLE_TH-EMPTY,TMP-C_T2I_ALEX_1121_1",,,HOLE_D10N,1179.33,6053.76,0.000,NO,,,
H128,"HOLE_TH-EMPTY,HOLE596",,,HOLE_C10D5-6B10_NPB,14618.06,17149.61,0.000,NO,,,
H6000,"HOLE_TH-EMPTY,HOLE1226",,,HOLE_C6-2D3-73B6-2I5-53_RO6-53_NPB,17615.75,1591.34,0.000,NO,,,
H6001,"HOLE_TH-EMPTY,HOLE1226",,,HOLE_C6-2D3-73B6-2I5-53_RO6-53_NPB,18381.50,2019.29,0.000,NO,,,
H6002,"HOLE_TH-EMPTY,HOLE1195",,,HOLE_C8D4-2B8_NPB,8875.19,15281.91,270.000,NO,,,
H8027,"HOLE_TH-EMPTY,HOLE1226",,,HOLE_C6-2D3-73B6-2I5-53_RO6-53_NPB,5231.73,5781.74,0.000,NO,,,
H8028,"HOLE_TH-EMPTY,HOLE1226",,,HOLE_C6-2D3-73B6-2I5-53_RO6-53_NPB,2154.18,6580.55,0.000,NO,,,
J90_CON,"TP_TP-EMPTY,TP30",,,TP30,2149.39,-765.54,270.000,NO,,,
J1,"SCONN288_DDR506112002KQ-SCONN288_DDR506112002KQ,SMA",,,DDR288S_1-1VXC,12020.40,10061.42,180.000,NO,,,
J5,"SCONN8_G802M0083150RD3HR-SCONN8_G802M0083150RD3HR,A",,,HEADER2X4SXN,13496.06,2440.94,180.000,NO,,,
J6,"CONN6_HBC1031L200D8H-CONN6_HBC1031-L200D-8H,THLF,IA",,,HEADER2X3XE,11738.58,2072.05,90.000,NO,,,
J7,"SCONN8_G802M0083150RD3HR-SCONN8_G802M0083150RD3HR,A",,,HEADER2X4SXN,311.02,2047.24,0.000,NO,,,
J8,"CONN4_HFK1040L0P1L7H-CONN4_HFK1040-L0P1L-7H,THLF,IA",,,HEADER1X4BHXA,12491.52,603.84,270.000,NO,,,
J13,"CONN4_HFK1040L0P1L7H-CONN4_HFK1040-L0P1L-7H,THLF,IA",,,HEADER1X4BHXA,14311.75,874.32,90.000,NO,,,
J15,"SCONN288_DDR506112002KQ-SCONN288_DDR506112002KQ,SMA",,,DDR288S_1-1VXC,11723.39,10061.42,180.000,NO,,,
J16,"SCONN288_DDR506112002KQ-SCONN288_DDR506112002KQ,SMA",,,DDR288S_1-1VXC,16315.67,10061.42,180.000,NO,,,
J17,"SCONN288_DDR506112002KQ-SCONN288_DDR506112002KQ,SMA",,,DDR288S_1-1VXC,11426.38,10061.42,180.000,NO,,,
J18,"SCONN288_DDR506112002KQ-SCONN288_DDR506112002KQ,SMA",,,DDR288S_1-1VXC,16909.69,10061.42,180.000,NO,,,
J19,"SCONN288_DDR506112002KQ-SCONN288_DDR506112002KQ,SMA",,,DDR288S_1-1VXC,11129.37,10061.42,180.000,NO,,,
J20,"SCONN288_DDR506112002KQ-SCONN288_DDR506112002KQ,SMA",,,DDR288S_1-1VXC,17503.71,10061.42,180.000,NO,,,
J21,"SCONN288_DDR506112002KQ-SCONN288_DDR506112002KQ,SMA",,,DDR288S_1-1VXC,10832.37,10061.42,180.000,NO,,,
J23,"SCONN288_DDR506112002KQ-SCONN288_DDR506112002KQ,SMA",,,DDR288S_1-1VXC,10535.36,10061.42,180.000,NO,,,
J24,"SCONN288_DDR506112002KQ-SCONN288_DDR506112002KQ,SMA",,,DDR288S_1-1VXC,2258.98,10061.43,180.000,NO,,,
J26,"SCONN288_DDR506112002KQ-SCONN288_DDR506112002KQ,SMA",,,DDR288S_1-1VXC,1961.97,10061.43,180.000,NO,,,
J27,"SCONN288_DDR506112002KQ-SCONN288_DDR506112002KQ,SMA",,,DDR288S_1-1VXC,6851.26,10061.43,180.000,NO,,,
J28,"SCONN288_DDR506112002KQ-SCONN288_DDR506112002KQ,SMA",,,DDR288S_1-1VXC,1664.96,10061.43,180.000,NO,,,
J29,"SCONN288_DDR506112002KQ-SCONN288_DDR506112002KQ,SMA",,,DDR288S_1-1VXC,7445.28,10061.43,180.000,NO,,,
J30,"SCONN288_DDR506112002KQ-SCONN288_DDR506112002KQ,SMA",,,DDR288S_1-1VXC,1367.95,10061.43,180.000,NO,,,
J32,"SCONN288_DDR506112002KQ-SCONN288_DDR506112002KQ,SMA",,,DDR288S_1-1VXC,1070.95,10061.43,180.000,NO,,,
J33,"SCONN288_DDR506112002KQ-SCONN288_DDR506112002KQ,SMA",,,DDR288S_1-1VXC,773.94,10061.43,180.000,NO,,,
J35,"SCONN168_ME1016810202011-SCONN168_ME1016810202011,A",,,CON_F168S2H7D_P0-6W2-95_LUH,1866.22,219.29,270.000,NO,,,
J37,"SCONN288_DDR506112002KQ-SCONN288_DDR506112002KQ,SMA",,,DDR288S_1-1VXC,8039.29,10061.43,180.000,NO,,,
J38,"SCONN168_ME1016810202011-SCONN168_ME1016810202011,A",,,CON_F168S2H7D_P0-6W2-95_LUH,16610.31,219.29,270.000,NO,,,
J41,"SCONN168_ME1016810202011-SCONN168_ME1016810202011,A",,,CON_F168S2H7D_P0-6W2-95_LUH,6315.04,427.16,270.000,NO,,,
J45,CONN60_101062636003K02LF-CONN60_10106263-6003K02LFA,,,HSD_M60D4H2D_P2-54W2-54_LDHXB,9387.80,17148.90,270.000,NO,,,
J48,"SCONN8_G802M0083150RD3HR-SCONN8_G802M0083150RD3HR,A",,,HEADER2X4SXN,12633.86,2440.94,0.000,NO,,,
J49,"SCONN8_G802M0083150RD3HR-SCONN8_G802M0083150RD3HR,A",,,HEADER2X4SXN,1140.46,2047.41,0.000,NO,,,
J54,"SCONN20_HSU2101L00007H-SCONN20_HSU2101-L0000-7H,SMA",,,HEADER2X10SXK,15549.11,2317.50,180.000,NO,,,
J57,"CONN8_HBB1081L200D8H-CONN8_HBB1081-L200D-8H,THLF,IA",,,HEADER1X8XA_H340,6090.16,2742.72,270.000,NO,,,
J59,"SCONN75K_APCI0155P004A-SCONN75K_APCI0155-P004A,SMLA",,,CON_F67S2H2D2S_P0-5W7-55_LUVXB_H270,6825.13,1852.36,0.000,NO,,,
J63,"PICOPROBE_BXA-DELTA-L 4.0,SMLF,EMPTY,TP33",,,TRIANG_LAUNCH_3PXB,14420.81,199.89,180.000,NO,,,
J64,"PICOPROBE_BXA-DELTA-L 4.0,SMLF,EMPTY,TP33",,,TRIANG_LAUNCH_3PXB,14420.81,-100.11,0.000,YES,,,
J65,"PICOPROBE_BXA-DELTA-L 4.0,SMLF,EMPTY,TP33",,,TRIANG_LAUNCH_3PXB,14420.81,-200.11,180.000,NO,,,
J66,"PICOPROBE_BXA-DELTA-L 4.0,SMLF,EMPTY,TP33",,,TRIANG_LAUNCH_3PXB,17353.75,-242.12,180.000,NO,,,
J67,"SCONN288_DDR506112002KQ-SCONN288_DDR506112002KQ,SMA",,,DDR288S_1-1VXC,17800.71,10061.42,180.000,NO,,,
J68,"SCONN288_DDR506112002KQ-SCONN288_DDR506112002KQ,SMA",,,DDR288S_1-1VXC,17206.70,10061.42,180.000,NO,,,
J69,"SCONN288_DDR506112002KQ-SCONN288_DDR506112002KQ,SMA",,,DDR288S_1-1VXC,16612.68,10061.42,180.000,NO,,,
J70,"PICOPROBE_BXA-DELTA-L 4.0,SMLF,EMPTY,TP33",,,TRIANG_LAUNCH_3PXB,12400.22,-100.11,180.000,YES,,,
J71,"PICOPROBE_BXA-DELTA-L 4.0,SMLF,EMPTY,TP33",,,TRIANG_LAUNCH_3PXB,12400.22,-200.11,0.000,NO,,,
J72,"PICOPROBE_BXA-DELTA-L 4.0,SMLF,EMPTY,TP33",,,TRIANG_LAUNCH_3PXB,15333.16,-242.12,0.000,NO,,,
J73,"PICOPROBE_BXA-DELTA-L 4.0,SMLF,EMPTY,TP33",,,TRIANG_LAUNCH_3PXB,12400.22,-0.11,0.000,NO,,,
J74,"PICOPROBE_BXA-DELTA-L 4.0,SMLF,EMPTY,TP33",,,TRIANG_LAUNCH_3PXB,15333.16,-342.12,180.000,YES,,,
J75,"PICOPROBE_BXA-DELTA-L 4.0,SMLF,EMPTY,TP33",,,TRIANG_LAUNCH_3PXB,8365.02,-0.11,0.000,NO,,,
J76,"PICOPROBE_BXA-DELTA-L 4.0,SMLF,EMPTY,TP33",,,TRIANG_LAUNCH_3PXB,8365.02,-300.11,180.000,YES,,,
J77,"PICOPROBE_BXA-DELTA-L 4.0,SMLF,EMPTY,TP33",,,TRIANG_LAUNCH_3PXB,3850.23,-238.71,0.000,NO,,,
J78,"PICOPROBE_BXA-DELTA-L 4.0,SMLF,EMPTY,TP33",,,TRIANG_LAUNCH_3PXB,8365.02,199.89,0.000,NO,,,
J79,"PICOPROBE_BXA-DELTA-L 4.0,SMLF,EMPTY,TP33",,,TRIANG_LAUNCH_3PXB,8365.02,-200.11,0.000,NO,,,
J80,"PICOPROBE_BXA-DELTA-L 4.0,SMLF,EMPTY,TP33",,,TRIANG_LAUNCH_3PXB,8365.02,99.89,180.000,YES,,,
J81,"PICOPROBE_BXA-DELTA-L 4.0,SMLF,EMPTY,TP33",,,TRIANG_LAUNCH_3PXB,11832.22,-0.11,180.000,NO,,,
J82,"PICOPROBE_BXA-DELTA-L 4.0,SMLF,EMPTY,TP33",,,TRIANG_LAUNCH_3PXB,11832.22,-300.11,0.000,YES,,,
J83,"PICOPROBE_BXA-DELTA-L 4.0,SMLF,EMPTY,TP33",,,TRIANG_LAUNCH_3PXB,7317.43,-238.71,180.000,NO,,,
J84,"PICOPROBE_BXA-DELTA-L 4.0,SMLF,EMPTY,TP33",,,TRIANG_LAUNCH_3PXB,11832.22,199.89,180.000,NO,,,
J85,"PICOPROBE_BXA-DELTA-L 4.0,SMLF,EMPTY,TP33",,,TRIANG_LAUNCH_3PXB,11832.22,-200.11,180.000,NO,,,
J86,"PICOPROBE_BXA-DELTA-L 4.0,SMLF,EMPTY,TP33",,,TRIANG_LAUNCH_3PXB,11832.22,99.89,0.000,YES,,,
J90,"SCONN56_123276793-SCONN56_1-2327679-3,SMLF,IO,DFHSA",,,CON_F56S2H4D_P0-6W4-6_LUHXA,9224.41,1990.55,180.000,NO,,,
J99,"SCONN288_DDR506112002KQ-SCONN288_DDR506112002KQ,SMA",,,DDR288S_1-1VXC,7742.29,10061.43,180.000,NO,,,
J100,"SCONN288_DDR506112002KQ-SCONN288_DDR506112002KQ,SMA",,,DDR288S_1-1VXC,7148.27,10061.43,180.000,NO,,,
J102,"SCONN288_DDR506112002KQ-SCONN288_DDR506112002KQ,SMA",,,DDR288S_1-1VXC,6554.25,10061.43,180.000,NO,,,
J105,"CONN112_10137002101LF-CONN112_10137002-101LF,THLF,A",,,HSD_F112D8_P2W1-2_RDH,15698.82,17342.12,0.000,NO,,,
J106,"CONN112_10137002101LF-CONN112_10137002-101LF,THLF,A",,,HSD_F112D8_P2W1-2_RDH,15029.52,17342.12,0.000,NO,,,
J107,"CONN112_10137002101LF-CONN112_10137002-101LF,THLF,A",,,HSD_F112D8_P2W1-2_RDH,13057.08,17342.12,0.000,NO,,,
J108,"CONN112_10137002101LF-CONN112_10137002-101LF,THLF,A",,,HSD_F112D8_P2W1-2_RDH,12387.78,17342.12,0.000,NO,,,
J109,"CONN112_10137002101LF-CONN112_10137002-101LF,THLF,A",,,HSD_F112D8_P2W1-2_RDH,5620.08,17342.12,0.000,NO,,,
J110,"CONN112_10137002101LF-CONN112_10137002-101LF,THLF,A",,,HSD_F112D8_P2W1-2_RDH,4950.78,17342.12,0.000,NO,,,
J111,"CONN112_10137002101LF-CONN112_10137002-101LF,THLF,A",,,HSD_F112D8_P2W1-2_RDH,2978.35,17342.12,0.000,NO,,,
J112,"CONN160_10131762101LF-CONN160_10131762-101LF,THLF,A",,,HSD_F160D8_P2W1-2_RDH,2309.05,17342.12,0.000,NO,,,
J114,"PICOPROBE_BXA-DELTA-L 4.0,SMLF,EMPTY,TP33",,,TRIANG_LAUNCH_3PXB,12400.22,-300.11,180.000,YES,,,
J115,"PICOPROBE_BXA-DELTA-L 4.0,SMLF,EMPTY,TP33",,,TRIANG_LAUNCH_3PXB,12400.22,99.89,180.000,YES,,,
J116,"PICOPROBE_BXA-DELTA-L 4.0,SMLF,EMPTY,TP33",,,TRIANG_LAUNCH_3PXB,14420.81,-300.11,0.000,YES,,,
J117,"PICOPROBE_BXA-DELTA-L 4.0,SMLF,EMPTY,TP33",,,TRIANG_LAUNCH_3PXB,14420.81,99.89,0.000,YES,,,
J118,"PICOPROBE_BXA-DELTA-L 4.0,SMLF,EMPTY,TP33",,,TRIANG_LAUNCH_3PXB,3850.23,-138.71,180.000,YES,,,
J119,"PICOPROBE_BXA-DELTA-L 4.0,SMLF,EMPTY,TP33",,,TRIANG_LAUNCH_3PXB,11832.22,-100.11,0.000,YES,,,
J120,"PICOPROBE_BXA-DELTA-L 4.0,SMLF,EMPTY,TP33",,,TRIANG_LAUNCH_3PXB,7317.43,-138.71,0.000,YES,,,
J121,"PICOPROBE_BXA-DELTA-L 4.0,SMLF,EMPTY,TP33",,,TRIANG_LAUNCH_3PXB,8365.02,-100.11,180.000,YES,,,
J122,"CONN1_10165288101LF-CONN1_10165288-101LF,THLF,IO,DA",,,CON_GUIDE-F1XG,14164.37,16982.68,180.000,NO,,,
J123,"CONN1_10165288101LF-CONN1_10165288-101LF,THLF,IO,DA",,,CON_GUIDE-F1XG,4410.43,16982.68,180.000,NO,,,
J212,"CONN10_HBC1051L300D8H-CONN10_HBC1051-L300D-8H,THLFA",,,HEADER2X5XJ,13912.60,1742.13,270.000,NO,,,
J8067,"PICOPROBE_BXA-DELTA-L 4.0,SMLF,EMPTY,TP33",,,TRIANG_LAUNCH_3PXB,14420.81,-0.11,180.000,NO,,,
J8068,"PICOPROBE_BXA-DELTA-L 4.0,SMLF,EMPTY,TP33",,,TRIANG_LAUNCH_3PXB,17353.75,-342.12,0.000,YES,,,
J8069,"PICOPROBE_BXA-DELTA-L 4.0,SMLF,EMPTY,TP33",,,TRIANG_LAUNCH_3PXB,12400.22,199.89,0.000,NO,,,
JP12_12,"TP_TP-EMPTY,TP30",,,TP30,895.39,-765.54,270.000,NO,,,
JP4003_12,"TP_TP-EMPTY,TP30",,,TP30,2035.39,-765.54,270.000,NO,,,
JP6000_23,"TP_TP-EMPTY,TP30",,,TP30,1807.39,-765.54,270.000,NO,,,
JP6001_23,"TP_TP-EMPTY,TP30",,,TP30,1921.39,-765.54,270.000,NO,,,
JP10,"CONN3_210HP1030BR1-CONN3_210-HP1-030BR1,THLF,IO,DFA",,,HEADER1X3XG,7571.84,17227.72,0.000,NO,,,
JP12,"CONN3_210HP1030BR1-CONN3_210-HP1-030BR1,THLF,IO,DFA",,,HEADER1X3XG,12994.39,928.12,180.000,NO,,,
JP4003,"CONN3_210HP1030BR1-CONN3_210-HP1-030BR1,THLF,IO,DFA",,,HEADER1X3XG,10809.70,16609.58,0.000,NO,,,
JP6000,"CONN3_210HP1030BR1-CONN3_210-HP1-030BR1,THLF,IO,DFA",,,HEADER1X3XG,997.29,2898.22,270.000,NO,,,
JP6001,"CONN3_210HP1030BR1-CONN3_210-HP1-030BR1,THLF,IO,DFA",,,HEADER1X3XG,997.29,3102.56,270.000,NO,,,
JP6500,"CONN3_210HP1030BR1-CONN3_210-HP1-030BR1,THLF,IO,DFA",,,HEADER1X3XG,10728.63,14291.76,0.000,NO,,,
L1,"Q_INDUCTOR_SMLF-FCM2012KF-601T/0.5A,IND,CX601T05003",FCM2012KF-601T/0.5A,,L0805,4380.00,16340.00,180.000,NO,,,
L2,"Q_INDUCTOR_SMLF-FCM2012KF-601T/0.5A,IND,CX601T05003",FCM2012KF-601T/0.5A,,L0805,3954.43,16168.22,0.000,NO,,,
L3,"Q_INDUCTOR_SMLF-BLM21SN300SN1D/5A,IND,CX300SN1000",BLM21SN300SN1D/5A,,L0805,2765.84,15140.77,0.000,YES,,,
L4,"Q_INDUCTOR_SMLF-100NH/16A,IND,CV+10G0MZ04",100NH/16A,,L_HCBS4545_4-5X4-5,1666.00,15592.00,270.000,NO,,,
L5,"Q_INDUCTOR_SMLF-BLM21SN300SN1D/5A,IND,CX300SN1000",BLM21SN300SN1D/5A,,L0805,4046.46,15140.77,0.000,YES,,,
L6,"Q_INDUCTOR_SMLF-100NH/16A,IND,CV+10G0MZ04",100NH/16A,,L_HCBS4545_4-5X4-5,2879.95,15453.61,0.000,NO,,,
L7,"Q_INDUCTOR_SMLF-BLM21SN300SN1D/5A,IND,CX300SN1000",BLM21SN300SN1D/5A,,L0805,6706.00,15142.00,180.000,NO,,,
L8,"Q_INDUCTOR_SMLF-100NH/16A,IND,CV+10G0MZ04",100NH/16A,,L_HCBS4545_4-5X4-5,5521.68,15453.61,0.000,NO,,,
L9,"Q_INDUCTOR_SMLF-BLM21SN300SN1D/5A,IND,CX300SN1000",BLM21SN300SN1D/5A,,L0805,5407.57,15140.77,0.000,YES,,,
L10,"Q_INDUCTOR_SMLF-100NH/16A,IND,CV+10G0MZ04",100NH/16A,,L_HCBS4545_4-5X4-5,4241.06,15453.61,0.000,NO,,,
L11,"Q_INDUCTOR_SMLF-BLM21SN300SN1D/5A,IND,CX300SN1000",BLM21SN300SN1D/5A,,L0805,12844.57,15470.77,0.000,YES,,,
L12,"Q_INDUCTOR_SMLF-100NH/16A,IND,CV+10G0MZ04",100NH/16A,,L_HCBS4545_4-5X4-5,11744.73,15922.00,270.000,NO,,,
L13,"Q_INDUCTOR_SMLF-BLM21SN300SN1D/5A,IND,CX300SN1000",BLM21SN300SN1D/5A,,L0805,14125.19,15470.77,0.000,YES,,,
L14,"Q_INDUCTOR_SMLF-100NH/16A,IND,CV+10G0MZ04",100NH/16A,,L_HCBS4545_4-5X4-5,12958.68,15783.61,0.000,NO,,,
L15,"Q_INDUCTOR_SMLF-BLM18PG300SN1D ,IND,TMP_QCX8PG3000A",BLM18PG300SN1D,,L0603,12979.78,1574.95,0.000,NO,,,
L16,"Q_INDUCTOR_SMLF-BLM18PG300SN1D ,IND,TMP_QCX8PG3000A",BLM18PG300SN1D,,L0603,11930.07,1828.51,0.000,NO,,,
L17,"Q_INDUCTOR_SMLF-FCM2012KF-601T/0.5A,IND,CX601T05003",FCM2012KF-601T/0.5A,,L0805,425.52,5470.05,180.000,YES,,,
L18,"Q_INDUCTOR_SMLF-BLM21SN300SN1D/5A,IND,CX300SN1000",BLM21SN300SN1D/5A,,L0805,16784.74,15472.00,180.000,NO,,,
L19,"Q_INDUCTOR_SMLF-FCM2012KF-601T/0.5A,IND,CX601T05003",FCM2012KF-601T/0.5A,,L0805,11100.00,16930.00,270.000,NO,,,
L20,"Q_INDUCTOR_SMLF-FCM2012KF-601T/0.5A,IND,CX601T05003",FCM2012KF-601T/0.5A,,L0805,11088.94,16238.27,90.000,NO,,,
L21,"Q_INDUCTOR_SMLF-100NH/16A,IND,CV+10G0MZ04",100NH/16A,,L_HCBS4545_4-5X4-5,15600.42,15783.61,0.000,NO,,,
L22,"Q_INDUCTOR_SMLF-BLM21SN300SN1D/5A,IND,CX300SN1000",BLM21SN300SN1D/5A,,L0805,15486.31,15470.77,0.000,YES,,,
L23,"Q_INDUCTOR_SMLF-100NH/16A,IND,CV+10G0MZ04",100NH/16A,,L_HCBS4545_4-5X4-5,14319.80,15783.61,0.000,NO,,,
L24,"Q_INDUCTOR_SMLF-BLM18PG300SN1D ,IND,TMP_QCX8PG3000A",BLM18PG300SN1D,,L0603,9530.00,12920.00,0.000,YES,,,
L25,"Q_INDUCTOR_SMLF-BLM18PG300SN1D ,IND,TMP_QCX8PG3000A",BLM18PG300SN1D,,L0603,8386.65,12766.23,180.000,YES,,,
L26,"Q_INDUCTOR_SMLF-BLM15PD121SN1D/1300MA,IND,CX5PD121A",BLM15PD121SN1D/1300MA,,L0402,12860.72,15491.20,180.000,NO,,,
L27,"Q_INDUCTOR_SMLF-BLM15PD121SN1D/1300MA,IND,CX5PD121A",BLM15PD121SN1D/1300MA,,L0402,2781.99,15161.20,180.000,NO,,,
L28,"Q_INDUCTOR_SMLF-BLM15PD121SN1D/1300MA,IND,CX5PD121A",BLM15PD121SN1D/1300MA,,L0402,14141.34,15491.20,180.000,NO,,,
L29,"Q_INDUCTOR_SMLF-BLM15PD121SN1D/1300MA,IND,CX5PD121A",BLM15PD121SN1D/1300MA,,L0402,16821.64,15635.26,180.000,NO,,,
L30,"Q_INDUCTOR_SMLF-BLM15PD121SN1D/1300MA,IND,CX5PD121A",BLM15PD121SN1D/1300MA,,L0402,15502.46,15491.20,180.000,NO,,,
L31,"Q_INDUCTOR_SMLF-BLM15PD121SN1D/1300MA,IND,CX5PD121A",BLM15PD121SN1D/1300MA,,L0402,4062.61,15161.20,180.000,NO,,,
L32,"Q_INDUCTOR_SMLF-BLM15PD121SN1D/1300MA,IND,CX5PD121A",BLM15PD121SN1D/1300MA,,L0402,6742.90,15305.26,180.000,NO,,,
L33,"Q_INDUCTOR_SMLF-BLM15PD121SN1D/1300MA,IND,CX5PD121A",BLM15PD121SN1D/1300MA,,L0402,5423.72,15161.20,180.000,NO,,,
L6000,"Q_INDUCTOR_SMLF-BLM21PG221SN1D,IND,CX1PG221001",BLM21PG221SN1D,,L0805,5572.20,1317.93,0.000,YES,,,
L6001,"Q_INDUCTOR_SMLF-BLM21PG221SN1D,IND,CX1PG221001",BLM21PG221SN1D,,L0805,5413.11,1707.65,0.000,YES,,,
L6003,"Q_INDUCTOR_SMLF-BLM21PG221SN1D,IND,CX1PG221001",BLM21PG221SN1D,,L0805,4151.74,1094.52,270.000,YES,,,
L6004,"Q_INDUCTOR_SMLF-BLM21PG221SN1D,IND,CX1PG221001",BLM21PG221SN1D,,L0805,4555.34,1422.79,90.000,YES,,,
LBL_1,"TP_TP-EMPTY,TP30",,,TP30,1123.39,-765.54,270.000,NO,,,
LBL_2,"TP_TP-EMPTY,TP30",,,TP30,16659.04,19498.23,0.000,YES,,,
ME1,"ME_DUMMY_SYMBOL-QUANTA_LOGO_7X26,MECH,EMPTY,DUMMY1",,,QUANTA_LOGO_7X26,2284.17,3289.53,0.000,NO,,,
ME2,"ME_DUMMY_SYMBOL-WEEE,MECH,EMPTY,DUMMY2",,,WEEE,2578.30,2712.22,0.000,NO,,,
ME3,"ME_DUMMY_SYMBOL-PB-E1_SMALL,MECH,EMPTY,DUMMY3",,,PB-E1_SMALL,2329.52,2816.04,0.000,NO,,,
ME4,"ME_DUMMY_SYMBOL-SNLABEL_27X6,MECH,EMPTY,DUMMY46",,,SNLABEL_27X6,7831.74,16257.78,0.000,NO,,,
ME5,"ME_DUMMY_SYMBOL-CBS_3X558-8,MECH,EMPTY,DUMMY47",,,CBS_3X558-8,12447.15,-5421.40,90.000,NO,,,
ME6,"ME_DUMMY_SYMBOL-PCB_VENDOR_LOGO_15X8,MECH,EMPTY,DUA",,,PCB_VENDOR_LOGO_15X8,5488.98,14012.30,0.000,NO,,,
ME7,"ME_DUMMY_SYMBOL-PICKUP_SMDC20,MECH,EMPTY,DUMMY48",,,PICKUP_SMDC20,3742.68,18793.13,0.000,YES,,,
ME8,"ME_DUMMY_SYMBOL-PICKUP_SMDC20,MECH,EMPTY,DUMMY48",,,PICKUP_SMDC20,15617.96,15178.32,0.000,YES,,,
ME9,"ME_DUMMY_SYMBOL-PICKUP_SMDC20,MECH,EMPTY,DUMMY48",,,PICKUP_SMDC20,11867.06,19263.23,0.000,NO,,,
ME10,"ME_DUMMY_SYMBOL-PICKUP_SMDC20,MECH,EMPTY,DUMMY48",,,PICKUP_SMDC20,2720.42,15076.82,0.000,NO,,,
ME11,"ME_DUMMY_SYMBOL-PICKUP_SMDC20,MECH,EMPTY,DUMMY48",,,PICKUP_SMDC20,9668.87,9529.47,0.000,NO,,,
ME12,"ME_DUMMY_SYMBOL-PICKUP_SMDC20,MECH,EMPTY,DUMMY48",,,PICKUP_SMDC20,2402.50,4407.12,0.000,NO,,,
ME13,"ME_DUMMY_SYMBOL-PICKUP_SMDC20,MECH,EMPTY,DUMMY48",,,PICKUP_SMDC20,14456.16,2486.42,0.000,YES,,,
ME14,"ME_DUMMY_SYMBOL-PICKUP_SMDC20,MECH,EMPTY,DUMMY48",,,PICKUP_SMDC20,9820.00,9710.00,0.000,YES,,,
ME15,"ME_DUMMY_SYMBOL-PICKUP_SMDC20,MECH,EMPTY,DUMMY48",,,PICKUP_SMDC20,15030.00,4070.00,0.000,NO,,,
ME16,"ME_DUMMY_SYMBOL-PICKUP_SMDC20,MECH,EMPTY,DUMMY48",,,PICKUP_SMDC20,1892.00,4440.96,0.000,YES,,,
ME17,"ME_DUMMY_SYMBOL-EFI BIOS LABEL,MECH,EMPTY,DUMMY28_A",,,BIOS-BMCLABEL_10-5X10-5,4615.88,14062.90,0.000,NO,,,
ME29,"ME_DUMMY_SYMBOL-SNLABEL_15X5,MECH,EMPTY,DUMMY36",,,SNLABEL_15X5,14413.94,2978.43,0.000,NO,,,
OSC1,"Q_OSC4P_SMLF-50MHZ,OSC,BF650000032",,,OSC4_XP,8459.15,1028.01,90.000,NO,,,
PC81_C1P0_1,"Q_CAP_C0402-2.2UF,10V,10%,X6S,CH5222KEB01",2.2UF,10%,C0402,13046.30,13187.87,270.000,NO,,,
PC82_C1P0_2,"Q_CAP_C0402-2.2UF,10V,10%,X6S,CH5222KEB01",2.2UF,10%,C0402,12717.26,13188.44,270.000,NO,,,
PC83_2,"Q_CAP_0402-0.1UF,25V,10%,X7R,CH4104K1B00",0.1UF,10%,C0402,12756.20,13379.75,90.000,NO,,,
PC84_1,"Q_CAP_0402-0.1UF,25V,10%,X7R,CH4104K1B00",0.1UF,10%,C0402,13085.24,13379.18,90.000,NO,,,
PC85_1,"Q_CAP_0402-0.1UF,25V,10%,X7R,CH4104K1B00",0.1UF,10%,C0402,13028.46,13360.55,0.000,NO,,,
PC86_2,"Q_CAP_0402-0.1UF,25V,10%,X7R,CH4104K1B00",0.1UF,10%,C0402,12699.42,13361.12,0.000,NO,,,
PC87_1,"Q_CAP_C0402-1UF,25V,10%,X6S,CH5104KEB02",1UF,10%,C0402,13334.39,13193.85,270.000,NO,,,
PC88_2,"Q_CAP_C0402-1UF,25V,10%,X6S,CH5104KEB02",1UF,10%,C0402,13006.86,13194.08,270.000,NO,,,
PC89_1,"Q_CAP_C0805-22UF,16V,20%,X6S,CH6223MEA01",22UF,20%,C0805_H57,13235.46,13190.61,90.000,YES,,,
PC90_2,"Q_CAP_C0805-22UF,16V,20%,X6S,CH6223MEA01",22UF,20%,C0805_H57,12990.20,13191.18,90.000,YES,,,
PC91_1,"Q_CAP_C0805-22UF,16V,20%,X6S,CH6223MEA01",22UF,20%,C0805_H57,13319.24,13190.61,90.000,YES,,,
PC93_2,"Q_CAP_C0805-22UF,16V,20%,X6S,CH6223MEA01",22UF,20%,C0805_H57,12906.42,13343.61,270.000,YES,,,
PC95_1,"Q_CAP_C0805-22UF,16V,20%,X6S,CH6223MEA01",22UF,20%,C0805_H57,13235.46,13343.04,270.000,YES,,,
PC96_2,"Q_CAP_C0805-22UF,16V,20%,X6S,CH6223MEA01",22UF,20%,C0805_H57,12906.42,13191.18,90.000,YES,,,
PC102_1,"Q_CAP_C0805-22UF,4V,20%,X6S,CH622KMEA03",22UF,20%,C0805_H61,13314.43,12848.08,270.000,YES,,,
PC105_1,"Q_CAP_C0805-22UF,4V,20%,X6S,CH622KMEA03",22UF,20%,C0805_H61,13039.60,12846.89,270.000,YES,,,
PC106_2,"Q_CAP_C0805-22UF,4V,20%,X6S,CH622KMEA03",22UF,20%,C0805_H61,12970.83,12846.75,270.000,YES,,,
PC108_2,"Q_CAP_C0805-22UF,4V,20%,X6S,CH622KMEA03",22UF,20%,C0805_H61,12693.50,12843.59,270.000,YES,,,
PC111_6,"Q_CAP_0402-0.1UF,25V,10%,X7R,CH4104K1B00",0.1UF,10%,C0402,13739.06,13574.49,90.000,NO,,,
PC111_C1P0_4,"Q_CAP_C0402-2.2UF,10V,10%,X6S,CH5222KEB01",2.2UF,10%,C0402,12008.39,13650.18,270.000,NO,,,
PC112_C1P0_3,"Q_CAP_C0402-2.2UF,10V,10%,X6S,CH5222KEB01",2.2UF,10%,C0402,12388.30,13188.72,270.000,NO,,,
PC113_4,"Q_CAP_0402-0.1UF,25V,10%,X7R,CH4104K1B00",0.1UF,10%,C0402,12047.33,13841.49,90.000,NO,,,
PC113_C1P0_6,"Q_CAP_C0402-2.2UF,10V,10%,X6S,CH5222KEB01",2.2UF,10%,C0402,13700.12,13383.18,270.000,NO,,,
PC114_3,"Q_CAP_0402-0.1UF,25V,10%,X7R,CH4104K1B00",0.1UF,10%,C0402,12427.24,13380.03,90.000,NO,,,
PC114_6,"Q_CAP_0402-0.1UF,25V,10%,X7R,CH4104K1B00",0.1UF,10%,C0402,13684.06,13557.15,0.000,NO,,,
PC115_4,"Q_CAP_0402-0.1UF,25V,10%,X7R,CH4104K1B00",0.1UF,10%,C0402,12335.16,13656.06,270.000,NO,,,
PC115_6,"Q_CAP_C0402-1UF,25V,10%,X6S,CH5104KEB02",1UF,10%,C0402,13988.21,13389.16,270.000,NO,,,
PC116_3,"Q_CAP_0402-0.1UF,25V,10%,X7R,CH4104K1B00",0.1UF,10%,C0402,12620.96,13426.86,180.000,NO,,,
PC116_6,"Q_CAP_C0805-22UF,16V,20%,X6S,CH6223MEA01",22UF,20%,C0805_H57,13889.28,13538.35,270.000,YES,,,
PC117_4,"Q_CAP_C0402-1UF,25V,10%,X6S,CH5104KEB02",1UF,10%,C0402,12296.48,13656.16,270.000,NO,,,
PC118_3,"Q_CAP_C0402-1UF,25V,10%,X6S,CH5104KEB02",1UF,10%,C0402,12676.39,13192.70,270.000,NO,,,
PC118_6,"Q_CAP_C0805-22UF,16V,20%,X6S,CH6223MEA01",22UF,20%,C0805_H57,13973.06,13385.92,90.000,YES,,,
PC119_4,"Q_CAP_C0805-22UF,16V,20%,X6S,CH6223MEA01",22UF,20%,C0805_H57,12281.33,13652.92,90.000,YES,,,
PC119_6,"Q_CAP_C0805-22UF,16V,20%,X6S,CH6223MEA01",22UF,20%,C0805_H57,13889.28,13385.92,90.000,YES,,,
PC120_3,"Q_CAP_C0805-22UF,16V,20%,X6S,CH6223MEA01",22UF,20%,C0805_H57,12577.46,13191.46,90.000,YES,,,
PC120_6,"Q_CAP_C0805-22UF,4V,20%,X6S,CH622KMEA03",22UF,20%,C0805_H61,13723.05,13042.32,270.000,YES,,,
PC123_4,"Q_CAP_C0805-22UF,16V,20%,X6S,CH6223MEA01",22UF,20%,C0805_H57,12197.55,13805.35,270.000,YES,,,
PC123_6,"Q_CAP_C0805-22UF,4V,20%,X6S,CH622KMEA03",22UF,20%,C0805_H61,14005.02,13043.49,270.000,YES,,,
PC124_3,"Q_CAP_C0805-22UF,16V,20%,X6S,CH6223MEA01",22UF,20%,C0805_H57,12661.24,13191.46,90.000,YES,,,
PC124_6,"Q_CAP_0402-0.1UF,25V,10%,X7R,CH4104K1B00",0.1UF,10%,C0402,2690.61,6459.49,270.000,NO,,,
PC125_4,"Q_CAP_C0805-22UF,16V,20%,X6S,CH6223MEA01",22UF,20%,C0805_H57,12197.55,13652.92,90.000,YES,,,
PC126_3,"Q_CAP_C0805-22UF,16V,20%,X6S,CH6223MEA01",22UF,20%,C0805_H57,12577.46,13343.89,270.000,YES,,,
PC126_C0P1_6,"Q_CAP_C0402-2.2UF,10V,10%,X6S,CH5222KEB01",2.2UF,10%,C0402,2729.55,6650.80,90.000,NO,,,
PC127_4,"Q_CAP_C0805-22UF,4V,20%,X6S,CH622KMEA03",22UF,20%,C0805_H61,12017.32,13310.32,270.000,YES,,,
PC127_6,"Q_CAP_0402-0.1UF,25V,10%,X7R,CH4104K1B00",0.1UF,10%,C0402,2496.27,6409.09,0.000,NO,,,
PC128_4,"Q_CAP_C0805-22UF,4V,20%,X6S,CH622KMEA03",22UF,20%,C0805_H61,12106.32,13310.32,270.000,YES,,,
PC128_6,"Q_CAP_C0402-1UF,25V,10%,X6S,CH5104KEB02",1UF,10%,C0402,2441.25,6647.38,90.000,NO,,,
PC129_3,"Q_CAP_C0805-22UF,4V,20%,X6S,CH622KMEA03",22UF,20%,C0805_H61,12187.96,13310.49,270.000,YES,,,
PC129_6,"Q_CAP_C0805-22UF,16V,20%,X6S,CH6223MEA01",22UF,20%,C0805_H57,2535.51,6500.78,90.000,YES,,,
PC130_3,"Q_CAP_C0805-22UF,4V,20%,X6S,CH622KMEA03",22UF,20%,C0805_H61,12272.96,13310.32,270.000,YES,,,
PC130_6,"Q_CAP_C0805-22UF,16V,20%,X6S,CH6223MEA01",22UF,20%,C0805_H57,2543.12,6648.30,270.000,YES,,,
PC132_5,"Q_CAP_0402-0.1UF,25V,10%,X7R,CH4104K1B00",0.1UF,10%,C0402,13413.24,13381.18,90.000,NO,,,
PC132_6,"Q_CAP_C0805-22UF,16V,20%,X6S,CH6223MEA01",22UF,20%,C0805_H57,2463.12,6648.30,270.000,YES,,,
PC133_C1P0_5,"Q_CAP_C0402-2.2UF,10V,10%,X6S,CH5222KEB01",2.2UF,10%,C0402,13374.30,13189.87,270.000,NO,,,
PC134_5,"Q_CAP_0402-0.1UF,25V,10%,X7R,CH4104K1B00",0.1UF,10%,C0402,13356.46,13362.55,0.000,NO,,,
PC134_6,"Q_CAP_C0805-22UF,4V,20%,X6S,CH622KMEA03",22UF,20%,C0805_H61,2407.11,6983.48,90.000,YES,,,
PC135_5,"Q_CAP_C0402-1UF,25V,10%,X6S,CH5104KEB02",1UF,10%,C0402,13662.39,13195.85,270.000,NO,,,
PC135_6,"Q_CAP_C0805-22UF,4V,20%,X6S,CH622KMEA03",22UF,20%,C0805_H61,2591.57,6982.28,90.000,YES,,,
PC136_5,"Q_CAP_C0805-22UF,16V,20%,X6S,CH6223MEA01",22UF,20%,C0805_H57,13563.46,13345.04,270.000,YES,,,
PC136_6,"Q_CAP_0402-0.1UF,25V,10%,X7R,CH4104K1B00",0.1UF,10%,C0402,3977.77,13574.68,90.000,NO,,,
PC138_5,"Q_CAP_C0805-22UF,16V,20%,X6S,CH6223MEA01",22UF,20%,C0805_H57,13563.46,13192.61,90.000,YES,,,
PC139_5,"Q_CAP_C0805-22UF,16V,20%,X6S,CH6223MEA01",22UF,20%,C0805_H57,13647.24,13192.61,90.000,YES,,,
PC139_C1P1_6,"Q_CAP_C0402-2.2UF,10V,10%,X6S,CH5222KEB01",2.2UF,10%,C0402,3938.83,13383.37,270.000,NO,,,
PC140_5,"Q_CAP_C0805-22UF,4V,20%,X6S,CH622KMEA03",22UF,20%,C0805_H61,13383.30,12848.94,270.000,YES,,,
PC140_6,"Q_CAP_C0402-1UF,25V,10%,X6S,CH5104KEB02",1UF,10%,C0402,4226.92,13389.35,270.000,NO,,,
PC141_5,"Q_CAP_C0805-22UF,4V,20%,X6S,CH622KMEA03",22UF,20%,C0805_H61,13658.30,12866.94,270.000,YES,,,
PC141_6,"Q_CAP_0402-0.1UF,25V,10%,X7R,CH4104K1B00",0.1UF,10%,C0402,4265.61,13389.19,270.000,NO,,,
PC144_6,"Q_CAP_C0805-22UF,16V,20%,X6S,CH6223MEA01",22UF,20%,C0805_H57,4127.99,13386.11,90.000,YES,,,
PC144_IOP0_2,"Q_CAP_C0402-2.2UF,10V,10%,X6S,CH5222KEB01",2.2UF,10%,C0402,11351.39,13650.18,270.000,NO,,,
PC145_6,"Q_CAP_C0805-22UF,16V,20%,X6S,CH6223MEA01",22UF,20%,C0805_H57,4211.77,13386.11,90.000,YES,,,
PC145_7,"Q_CAP_0402-0.1UF,25V,10%,X7R,CH4104K1B00",0.1UF,10%,C0402,11719.33,13841.49,90.000,NO,,,
PC146_8,"Q_CAP_0402-0.1UF,25V,10%,X7R,CH4104K1B00",0.1UF,10%,C0402,11390.33,13841.49,90.000,NO,,,
PC147_6,"Q_CAP_C0805-22UF,16V,20%,X6S,CH6223MEA01",22UF,20%,C0805_H57,4127.99,13538.54,270.000,YES,,,
PC147_IOP0_1,"Q_CAP_C0402-2.2UF,10V,10%,X6S,CH5222KEB01",2.2UF,10%,C0402,11680.39,13650.18,270.000,NO,,,
PC148_1,"Q_CAP_0402-0.1UF,25V,10%,X7R,CH4104K1B00",0.1UF,10%,C0402,11662.55,13822.86,0.000,NO,,,
PC148_6,"Q_CAP_C0805-22UF,4V,20%,X6S,CH622KMEA03",22UF,20%,C0805_H61,4243.73,13043.68,270.000,YES,,,
PC149_2,"Q_CAP_0402-0.1UF,25V,10%,X7R,CH4104K1B00",0.1UF,10%,C0402,11333.55,13822.86,0.000,NO,,,
PC149_6,"Q_CAP_C0805-22UF,4V,20%,X6S,CH622KMEA03",22UF,20%,C0805_H61,3961.76,13042.51,270.000,YES,,,
PC150_1,"Q_CAP_C0402-1UF,25V,10%,X6S,CH5104KEB02",1UF,10%,C0402,11968.48,13656.16,270.000,NO,,,
PC150_6,"Q_CAP_0402-0.1UF,25V,10%,X7R,CH4104K1B00",0.1UF,10%,C0402,13796.13,6152.83,270.000,NO,,,
PC151_2,"Q_CAP_C0402-1UF,25V,10%,X6S,CH5104KEB02",1UF,10%,C0402,11639.48,13656.16,270.000,NO,,,
PC152_1,"Q_CAP_C0805-22UF,16V,20%,X6S,CH6223MEA01",22UF,20%,C0805_H57,11869.55,13652.92,90.000,YES,,,
PC152_C0P0_6,"Q_CAP_C0402-2.2UF,10V,10%,X6S,CH5222KEB01",2.2UF,10%,C0402,13835.07,6344.14,90.000,NO,,,
PC153_2,"Q_CAP_C0805-22UF,16V,20%,X6S,CH6223MEA01",22UF,20%,C0805_H57,11540.55,13652.92,90.000,YES,,,
PC153_6,"Q_CAP_0402-0.1UF,25V,10%,X7R,CH4104K1B00",0.1UF,10%,C0402,13502.61,6340.81,90.000,NO,,,
PC154_1,"Q_CAP_C0805-22UF,16V,20%,X6S,CH6223MEA01",22UF,20%,C0805_H57,11869.55,13805.35,270.000,YES,,,
PC154_6,"Q_CAP_C0402-1UF,25V,10%,X6S,CH5104KEB02",1UF,10%,C0402,13545.97,6340.81,90.000,NO,,,
PC157_2,"Q_CAP_C0805-22UF,16V,20%,X6S,CH6223MEA01",22UF,20%,C0805_H57,11540.55,13805.35,270.000,YES,,,
PC157_6,"Q_CAP_C0805-22UF,16V,20%,X6S,CH6223MEA01",22UF,20%,C0805_H57,13640.34,6195.90,90.000,YES,,,
PC158_1,"Q_CAP_C0805-22UF,16V,20%,X6S,CH6223MEA01",22UF,20%,C0805_H57,11953.33,13652.92,90.000,YES,,,
PC158_6,"Q_CAP_C0805-22UF,16V,20%,X6S,CH6223MEA01",22UF,20%,C0805_H57,13649.64,6348.94,270.000,YES,,,
PC159_2,"Q_CAP_C0805-22UF,16V,20%,X6S,CH6223MEA01",22UF,20%,C0805_H57,11624.33,13652.92,90.000,YES,,,
PC159_6,"Q_CAP_C0805-22UF,16V,20%,X6S,CH6223MEA01",22UF,20%,C0805_H57,13569.64,6348.94,270.000,YES,,,
PC163_6,"Q_CAP_C0805-22UF,4V,20%,X6S,CH622KMEA03",22UF,20%,C0805_H61,13519.30,6684.53,90.000,YES,,,
PC166_1,"Q_CAP_C0805-22UF,4V,20%,X6S,CH622KMEA03",22UF,20%,C0805_H61,11662.32,13306.32,270.000,YES,,,
PC166_6,"Q_CAP_C0805-22UF,4V,20%,X6S,CH622KMEA03",22UF,20%,C0805_H61,13602.78,6684.53,90.000,YES,,,
PC168_2,"Q_CAP_C0805-22UF,4V,20%,X6S,CH622KMEA03",22UF,20%,C0805_H61,11490.12,13306.49,270.000,YES,,,
PC169_1,"Q_CAP_C0805-22UF,4V,20%,X6S,CH622KMEA03",22UF,20%,C0805_H61,11567.20,13306.49,270.000,YES,,,
PC170_2,"Q_CAP_C0805-22UF,4V,20%,X6S,CH622KMEA03",22UF,20%,C0805_H61,11413.04,13306.49,270.000,YES,,,
PC173_IOP0_4,"Q_CAP_C0402-2.2UF,10V,10%,X6S,CH5222KEB01",2.2UF,10%,C0402,10698.39,13650.18,270.000,NO,,,
PC174_IOP0_3,"Q_CAP_C0402-2.2UF,10V,10%,X6S,CH5222KEB01",2.2UF,10%,C0402,11024.39,13650.18,270.000,NO,,,
PC175_9,"Q_CAP_0402-0.1UF,25V,10%,X7R,CH4104K1B00",0.1UF,10%,C0402,11063.33,13841.49,90.000,NO,,,
PC176_10,"Q_CAP_0402-0.1UF,25V,10%,X7R,CH4104K1B00",0.1UF,10%,C0402,10737.33,13841.49,90.000,NO,,,
PC177_3,"Q_CAP_0402-0.1UF,25V,10%,X7R,CH4104K1B00",0.1UF,10%,C0402,11006.55,13822.86,0.000,NO,,,
PC178_4,"Q_CAP_0402-0.1UF,25V,10%,X7R,CH4104K1B00",0.1UF,10%,C0402,11991.15,13820.88,0.000,NO,,,
PC179_3,"Q_CAP_C0402-1UF,25V,10%,X6S,CH5104KEB02",1UF,10%,C0402,11312.48,13656.16,270.000,NO,,,
PC180_4,"Q_CAP_C0402-1UF,25V,10%,X6S,CH5104KEB02",1UF,10%,C0402,10986.48,13656.16,270.000,NO,,,
PC181_3,"Q_CAP_C0805-22UF,16V,20%,X6S,CH6223MEA01",22UF,20%,C0805_H57,11213.55,13652.92,90.000,YES,,,
PC182_4,"Q_CAP_C0805-22UF,16V,20%,X6S,CH6223MEA01",22UF,20%,C0805_H57,10887.55,13652.92,90.000,YES,,,
PC184_3,"Q_CAP_C0805-22UF,16V,20%,X6S,CH6223MEA01",22UF,20%,C0805_H57,11297.33,13652.92,90.000,YES,,,
PC185_4,"Q_CAP_C0805-22UF,16V,20%,X6S,CH6223MEA01",22UF,20%,C0805_H57,10971.33,13652.92,90.000,YES,,,
PC187_3,"Q_CAP_C0805-22UF,16V,20%,X6S,CH6223MEA01",22UF,20%,C0805_H57,11213.55,13805.35,270.000,YES,,,
PC188_4,"Q_CAP_C0805-22UF,16V,20%,X6S,CH6223MEA01",22UF,20%,C0805_H57,10887.55,13805.35,270.000,YES,,,
PC189_4,"Q_CAP_C0805-22UF,4V,20%,X6S,CH622KMEA03",22UF,20%,C0805_H61,10972.96,13306.49,270.000,YES,,,
PC190_3,"Q_CAP_C0805-22UF,4V,20%,X6S,CH622KMEA03",22UF,20%,C0805_H61,11335.96,13306.49,270.000,YES,,,
PC191_4,"Q_CAP_C0805-22UF,4V,20%,X6S,CH622KMEA03",22UF,20%,C0805_H61,10697.32,13306.32,270.000,YES,,,
PC192_3,"Q_CAP_C0805-22UF,4V,20%,X6S,CH622KMEA03",22UF,20%,C0805_H61,11057.32,13307.32,270.000,YES,,,
PC201_1,"Q_CAP_0402-0.1UF,25V,10%,X7R,CH4104K1B00",0.1UF,10%,C0402,16572.84,14014.66,90.000,NO,,,
PC202_2,"Q_CAP_0402-0.1UF,25V,10%,X7R,CH4104K1B00",0.1UF,10%,C0402,16536.67,14417.41,90.000,NO,,,
PC205_11P0_1,"Q_CAP_C0402-2.2UF,10V,10%,X6S,CH5222KEB01",2.2UF,10%,C0402,16533.90,13823.35,270.000,NO,,,
PC206_11P0_2,"Q_CAP_C0402-2.2UF,10V,10%,X6S,CH5222KEB01",2.2UF,10%,C0402,16861.72,13824.35,270.000,NO,,,
PC207_1,"Q_CAP_0402-0.1UF,25V,10%,X7R,CH4104K1B00",0.1UF,10%,C0402,16843.88,13997.03,0.000,NO,,,
PC208_2,"Q_CAP_0402-0.1UF,25V,10%,X7R,CH4104K1B00",0.1UF,10%,C0402,17189.49,13827.90,270.000,NO,,,
PC209_1,"Q_CAP_C0402-1UF,25V,10%,X6S,CH5104KEB02",1UF,10%,C0402,16822.90,13826.90,270.000,NO,,,
PC210_2,"Q_CAP_C0402-1UF,25V,10%,X6S,CH5104KEB02",1UF,10%,C0402,17150.72,13827.90,270.000,NO,,,
PC211_1,"Q_CAP_C0805-22UF,16V,20%,X6S,CH6223MEA01",22UF,20%,C0805_H57,16799.31,13820.19,90.000,YES,,,
PC212_2,"Q_CAP_C0805-22UF,16V,20%,X6S,CH6223MEA01",22UF,20%,C0805_H57,17127.13,13821.19,90.000,YES,,,
PC213_1,"Q_CAP_C0805-22UF,16V,20%,X6S,CH6223MEA01",22UF,20%,C0805_H57,16719.31,13820.19,90.000,YES,,,
PC214_2,"Q_CAP_C0805-22UF,16V,20%,X6S,CH6223MEA01",22UF,20%,C0805_H57,17047.13,13821.19,90.000,YES,,,
PC215_1,"Q_CAP_C0805-22UF,16V,20%,X6S,CH6223MEA01",22UF,20%,C0805_H57,16726.33,13971.35,270.000,YES,,,
PC216_2,"Q_CAP_C0805-22UF,16V,20%,X6S,CH6223MEA01",22UF,20%,C0805_H57,17056.52,13972.35,270.000,YES,,,
PC218_2,"Q_CAP_C0805-22UF,16V,20%,X6S,CH6223MEA01",22UF,20%,C0805_H57,17198.41,13822.67,90.000,YES,,,
PC219_1,"Q_CAP_C0805-22UF,16V,20%,X6S,CH6223MEA01",22UF,20%,C0805_H57,16767.58,14116.94,180.000,NO,,,
PC221_2,"Q_CAP_C0805-22UF,4V,20%,X6S,CH622KMEA03",22UF,20%,C0805_H61,16541.77,13464.88,270.000,YES,,,
PC224_1,"Q_CAP_C0805-22UF,4V,20%,X6S,CH622KMEA03",22UF,20%,C0805_H61,16831.77,13464.88,270.000,YES,,,
PC225_2,"Q_CAP_C0805-22UF,4V,20%,X6S,CH622KMEA03",22UF,20%,C0805_H61,16461.77,13464.88,270.000,YES,,,
PC227_1,"Q_CAP_C0805-22UF,4V,20%,X6S,CH622KMEA03",22UF,20%,C0805_H61,17141.98,13461.49,270.000,YES,,,
PC254_1,"Q_CAP_0402-0.1UF,25V,10%,X7R,CH4104K1B00",0.1UF,10%,C0402,3345.61,7003.40,270.000,NO,,,
PC255_2,"Q_CAP_0402-0.1UF,25V,10%,X7R,CH4104K1B00",0.1UF,10%,C0402,3676.21,7000.72,270.000,NO,,,
PC258_C0P1_1,"Q_CAP_C0402-2.2UF,10V,10%,X6S,CH5222KEB01",2.2UF,10%,C0402,3384.55,7194.71,90.000,NO,,,
PC259_C0P1_2,"Q_CAP_C0402-2.2UF,10V,10%,X6S,CH5222KEB01",2.2UF,10%,C0402,3715.15,7192.03,90.000,NO,,,
PC260_1,"Q_CAP_0402-0.1UF,25V,10%,X7R,CH4104K1B00",0.1UF,10%,C0402,3156.43,6945.25,0.000,NO,,,
PC261_2,"Q_CAP_0402-0.1UF,25V,10%,X7R,CH4104K1B00",0.1UF,10%,C0402,3402.39,7022.03,180.000,NO,,,
PC262_1,"Q_CAP_C0402-1UF,25V,10%,X6S,CH5104KEB02",1UF,10%,C0402,3096.55,7188.39,90.000,NO,,,
PC263_2,"Q_CAP_C0402-1UF,25V,10%,X6S,CH5104KEB02",1UF,10%,C0402,3427.10,7188.12,90.000,NO,,,
PC264_1,"Q_CAP_C0805-22UF,16V,20%,X6S,CH6223MEA01",22UF,20%,C0805_H57,3186.51,7045.78,90.000,YES,,,
PC265_2,"Q_CAP_C0805-22UF,16V,20%,X6S,CH6223MEA01",22UF,20%,C0805_H57,3525.99,7189.29,270.000,YES,,,
PC266_1,"Q_CAP_C0805-22UF,16V,20%,X6S,CH6223MEA01",22UF,20%,C0805_H57,3199.12,7191.21,270.000,YES,,,
PC267_2,"Q_CAP_C0805-22UF,16V,20%,X6S,CH6223MEA01",22UF,20%,C0805_H57,3525.99,7036.86,90.000,YES,,,
PC268_1,"Q_CAP_C0805-22UF,16V,20%,X6S,CH6223MEA01",22UF,20%,C0805_H57,3119.12,7191.21,270.000,YES,,,
PC269_2,"Q_CAP_C0805-22UF,16V,20%,X6S,CH6223MEA01",22UF,20%,C0805_H57,3442.21,7189.29,270.000,YES,,,
PC280_2,"Q_CAP_C0805-22UF,4V,20%,X6S,CH622KMEA03",22UF,20%,C0805_H61,3021.81,7335.28,90.000,YES,,,
PC281_1,"Q_CAP_C0805-22UF,4V,20%,X6S,CH622KMEA03",22UF,20%,C0805_H61,2746.21,7299.08,90.000,YES,,,
PC282_2,"Q_CAP_C0805-22UF,4V,20%,X6S,CH622KMEA03",22UF,20%,C0805_H61,3715.51,7533.78,90.000,YES,,,
PC283_1,"Q_CAP_C0805-22UF,4V,20%,X6S,CH622KMEA03",22UF,20%,C0805_H61,3411.51,7533.78,90.000,YES,,,
PC284_3,"Q_CAP_0402-0.1UF,25V,10%,X7R,CH4104K1B00",0.1UF,10%,C0402,4006.61,7001.40,270.000,NO,,,
PC285_4,"Q_CAP_0402-0.1UF,25V,10%,X7R,CH4104K1B00",0.1UF,10%,C0402,4336.61,6823.40,270.000,NO,,,
PC288_C0P1_3,"Q_CAP_C0402-2.2UF,10V,10%,X6S,CH5222KEB01",2.2UF,10%,C0402,4045.55,7192.71,90.000,NO,,,
PC289_C0P1_4,"Q_CAP_C0402-2.2UF,10V,10%,X6S,CH5222KEB01",2.2UF,10%,C0402,4375.55,7014.71,90.000,NO,,,
PC290_3,"Q_CAP_0402-0.1UF,25V,10%,X7R,CH4104K1B00",0.1UF,10%,C0402,3732.99,7019.35,180.000,NO,,,
PC291_4,"Q_CAP_C0402-1UF,25V,10%,X6S,CH5104KEB02",1UF,10%,C0402,4087.39,7010.94,90.000,NO,,,
PC292_3,"Q_CAP_C0402-1UF,25V,10%,X6S,CH5104KEB02",1UF,10%,C0402,3757.04,7189.63,90.000,NO,,,
PC293_4,"Q_CAP_0402-0.1UF,25V,10%,X7R,CH4104K1B00",0.1UF,10%,C0402,4047.71,6946.38,90.000,NO,,,
PC294_3,"Q_CAP_C0805-22UF,16V,20%,X6S,CH6223MEA01",22UF,20%,C0805_H57,3852.51,7042.78,90.000,YES,,,
PC295_4,"Q_CAP_C0805-22UF,16V,20%,X6S,CH6223MEA01",22UF,20%,C0805_H57,4180.51,6863.78,90.000,YES,,,
PC296_3,"Q_CAP_C0805-22UF,16V,20%,X6S,CH6223MEA01",22UF,20%,C0805_H57,3858.12,7187.21,270.000,YES,,,
PC297_4,"Q_CAP_C0805-22UF,16V,20%,X6S,CH6223MEA01",22UF,20%,C0805_H57,4107.12,7012.21,270.000,YES,,,
PC298_3,"Q_CAP_C0805-22UF,16V,20%,X6S,CH6223MEA01",22UF,20%,C0805_H57,3778.12,7187.21,270.000,YES,,,
PC299_4,"Q_CAP_C0805-22UF,16V,20%,X6S,CH6223MEA01",22UF,20%,C0805_H57,4187.12,7012.21,270.000,YES,,,
PC302_3,"Q_CAP_C0805-22UF,4V,20%,X6S,CH622KMEA03",22UF,20%,C0805_H61,3120.51,7533.78,90.000,YES,,,
PC303_4,"Q_CAP_C0805-22UF,4V,20%,X6S,CH622KMEA03",22UF,20%,C0805_H61,4091.51,7354.78,90.000,YES,,,
PC304_3,"Q_CAP_C0805-22UF,4V,20%,X6S,CH622KMEA03",22UF,20%,C0805_H61,4012.80,7530.63,90.000,YES,,,
PC305_4,"Q_CAP_C0805-22UF,4V,20%,X6S,CH622KMEA03",22UF,20%,C0805_H61,4378.51,7514.58,90.000,YES,,,
PC306_5,"Q_CAP_0402-0.1UF,25V,10%,X7R,CH4104K1B00",0.1UF,10%,C0402,3017.91,6801.90,270.000,NO,,,
PC308_C0P1_5,"Q_CAP_C0402-2.2UF,10V,10%,X6S,CH5222KEB01",2.2UF,10%,C0402,3056.85,6993.21,90.000,NO,,,
PC309_5,"Q_CAP_0402-0.1UF,25V,10%,X7R,CH4104K1B00",0.1UF,10%,C0402,2838.57,6741.50,0.000,NO,,,
PC310_5,"Q_CAP_C0402-1UF,25V,10%,X6S,CH5104KEB02",1UF,10%,C0402,2768.55,6989.79,90.000,NO,,,
PC311_5,"Q_CAP_C0805-22UF,16V,20%,X6S,CH6223MEA01",22UF,20%,C0805_H57,2870.42,6988.71,270.000,YES,,,
PC312_5,"Q_CAP_C0805-22UF,16V,20%,X6S,CH6223MEA01",22UF,20%,C0805_H57,2790.42,6988.71,270.000,YES,,,
PC313_5,"Q_CAP_C0805-22UF,16V,20%,X6S,CH6223MEA01",22UF,20%,C0805_H57,2861.81,6845.28,90.000,YES,,,
PC315_5,"Q_CAP_C0805-22UF,4V,20%,X6S,CH622KMEA03",22UF,20%,C0805_H61,2682.81,6982.28,90.000,YES,,,
PC316_5,"Q_CAP_C0805-22UF,4V,20%,X6S,CH622KMEA03",22UF,20%,C0805_H61,2495.51,6982.28,90.000,YES,,,
PC317_7,"Q_CAP_0402-0.1UF,25V,10%,X7R,CH4104K1B00",0.1UF,10%,C0402,4660.61,6577.40,270.000,NO,,,
PC318_8,"Q_CAP_0402-0.1UF,25V,10%,X7R,CH4104K1B00",0.1UF,10%,C0402,4986.61,6312.40,270.000,NO,,,
PC321_SOP1_1,"Q_CAP_C0402-2.2UF,10V,10%,X6S,CH5222KEB01",2.2UF,10%,C0402,4699.55,6768.71,90.000,NO,,,
PC322_SOP1_2,"Q_CAP_C0402-2.2UF,10V,10%,X6S,CH5222KEB01",2.2UF,10%,C0402,5025.55,6503.71,90.000,NO,,,
PC323_1,"Q_CAP_C0402-1UF,25V,10%,X6S,CH5104KEB02",1UF,10%,C0402,4411.37,6764.13,90.000,NO,,,
PC324_2,"Q_CAP_C0402-1UF,25V,10%,X6S,CH5104KEB02",1UF,10%,C0402,4737.32,6500.39,90.000,NO,,,
PC325_1,"Q_CAP_0402-0.1UF,25V,10%,X7R,CH4104K1B00",0.1UF,10%,C0402,4373.09,6764.27,90.000,NO,,,
PC326_2,"Q_CAP_0402-0.1UF,25V,10%,X7R,CH4104K1B00",0.1UF,10%,C0402,4698.81,6500.37,90.000,NO,,,
PC327_1,"Q_CAP_C0805-22UF,16V,20%,X6S,CH6223MEA01",22UF,20%,C0805_H57,4505.51,6619.78,90.000,YES,,,
PC328_2,"Q_CAP_C0805-22UF,16V,20%,X6S,CH6223MEA01",22UF,20%,C0805_H57,4832.51,6354.78,90.000,YES,,,
PC329_1,"Q_CAP_C0805-22UF,16V,20%,X6S,CH6223MEA01",22UF,20%,C0805_H57,4512.12,6763.21,270.000,YES,,,
PC330_2,"Q_CAP_C0805-22UF,16V,20%,X6S,CH6223MEA01",22UF,20%,C0805_H57,4838.12,6499.21,270.000,YES,,,
PC331_1,"Q_CAP_C0805-22UF,16V,20%,X6S,CH6223MEA01",22UF,20%,C0805_H57,4431.12,6763.21,270.000,YES,,,
PC332_2,"Q_CAP_C0805-22UF,16V,20%,X6S,CH6223MEA01",22UF,20%,C0805_H57,4758.12,6499.21,270.000,YES,,,
PC334_1,"Q_CAP_C0805-22UF,16V,20%,X6S,CH6223MEA01",22UF,20%,C0805_H57,4362.52,6762.81,270.000,YES,,,
PC335_2,"Q_CAP_C0805-22UF,16V,20%,X6S,CH6223MEA01",22UF,20%,C0805_H57,4689.12,6499.21,270.000,YES,,,
PC339_2,"Q_CAP_C0805-22UF,4V,20%,X6S,CH622KMEA03",22UF,20%,C0805_H61,5179.31,6503.58,90.000,YES,,,
PC341_1,"Q_CAP_C0805-22UF,4V,20%,X6S,CH622KMEA03",22UF,20%,C0805_H61,4433.51,7094.49,90.000,YES,,,
PC342_2,"Q_CAP_C0805-22UF,4V,20%,X6S,CH622KMEA03",22UF,20%,C0805_H61,5249.31,6503.58,90.000,YES,,,
PC344_1,"Q_CAP_C0805-22UF,4V,20%,X6S,CH622KMEA03",22UF,20%,C0805_H61,4709.51,6968.78,90.000,YES,,,
PC345_9,"Q_CAP_0402-0.1UF,25V,10%,X7R,CH4104K1B00",0.1UF,10%,C0402,5319.61,5971.40,270.000,NO,,,
PC347_SOP1_3,"Q_CAP_C0402-2.2UF,10V,10%,X6S,CH5222KEB01",2.2UF,10%,C0402,5358.55,6162.71,90.000,NO,,,
PC348_3,"Q_CAP_0402-0.1UF,25V,10%,X7R,CH4104K1B00",0.1UF,10%,C0402,5029.98,6159.13,90.000,NO,,,
PC349_3,"Q_CAP_C0402-1UF,25V,10%,X6S,CH5104KEB02",1UF,10%,C0402,5069.64,6159.21,90.000,NO,,,
PC350_3,"Q_CAP_C0805-22UF,16V,20%,X6S,CH6223MEA01",22UF,20%,C0805_H57,5170.12,6157.21,270.000,YES,,,
PC351_3,"Q_CAP_C0805-22UF,16V,20%,X6S,CH6223MEA01",22UF,20%,C0805_H57,5090.12,6157.21,270.000,YES,,,
PC352_3,"Q_CAP_C0805-22UF,16V,20%,X6S,CH6223MEA01",22UF,20%,C0805_H57,5163.51,6012.78,90.000,YES,,,
PC353_3,"Q_CAP_C0805-22UF,16V,20%,X6S,CH6223MEA01",22UF,20%,C0805_H57,5021.12,6157.21,270.000,YES,,,
PC354_3,"Q_CAP_C0805-22UF,4V,20%,X6S,CH622KMEA03",22UF,20%,C0805_H61,5388.51,6501.78,90.000,YES,,,
PC355_3,"Q_CAP_C0805-22UF,4V,20%,X6S,CH622KMEA03",22UF,20%,C0805_H61,5319.51,6501.78,90.000,YES,,,
PC371_C1P1_1,"Q_CAP_C0402-2.2UF,10V,10%,X6S,CH5222KEB01",2.2UF,10%,C0402,3285.01,13188.06,270.000,NO,,,
PC372_C1P1_2,"Q_CAP_C0402-2.2UF,10V,10%,X6S,CH5222KEB01",2.2UF,10%,C0402,2955.97,13188.63,270.000,NO,,,
PC373_2,"Q_CAP_0402-0.1UF,25V,10%,X7R,CH4104K1B00",0.1UF,10%,C0402,2994.91,13379.94,90.000,NO,,,
PC374_1,"Q_CAP_0402-0.1UF,25V,10%,X7R,CH4104K1B00",0.1UF,10%,C0402,3323.95,13379.37,90.000,NO,,,
PC375_1,"Q_CAP_0402-0.1UF,25V,10%,X7R,CH4104K1B00",0.1UF,10%,C0402,3267.17,13360.74,0.000,NO,,,
PC376_2,"Q_CAP_0402-0.1UF,25V,10%,X7R,CH4104K1B00",0.1UF,10%,C0402,2938.13,13361.31,0.000,NO,,,
PC377_1,"Q_CAP_C0402-1UF,25V,10%,X6S,CH5104KEB02",1UF,10%,C0402,3573.10,13194.04,270.000,NO,,,
PC378_2,"Q_CAP_C0402-1UF,25V,10%,X6S,CH5104KEB02",1UF,10%,C0402,3245.57,13194.27,270.000,NO,,,
PC379_1,"Q_CAP_C0805-22UF,16V,20%,X6S,CH6223MEA01",22UF,20%,C0805_H57,3474.17,13343.23,270.000,YES,,,
PC380_2,"Q_CAP_C0805-22UF,16V,20%,X6S,CH6223MEA01",22UF,20%,C0805_H57,3228.91,13191.37,90.000,YES,,,
PC381_1,"Q_CAP_C0805-22UF,16V,20%,X6S,CH6223MEA01",22UF,20%,C0805_H57,3474.17,13190.80,90.000,YES,,,
PC382_2,"Q_CAP_C0805-22UF,16V,20%,X6S,CH6223MEA01",22UF,20%,C0805_H57,3145.13,13191.37,90.000,YES,,,
PC384_1,"Q_CAP_C0805-22UF,16V,20%,X6S,CH6223MEA01",22UF,20%,C0805_H57,3557.95,13190.80,90.000,YES,,,
PC385_2,"Q_CAP_C0805-22UF,16V,20%,X6S,CH6223MEA01",22UF,20%,C0805_H57,3145.13,13343.80,270.000,YES,,,
PC394_2,"Q_CAP_C0805-22UF,4V,20%,X6S,CH622KMEA03",22UF,20%,C0805_H61,3553.14,12848.27,270.000,YES,,,
PC395_1,"Q_CAP_C0805-22UF,4V,20%,X6S,CH622KMEA03",22UF,20%,C0805_H61,2932.21,12843.78,270.000,YES,,,
PC397_2,"Q_CAP_C0805-22UF,4V,20%,X6S,CH622KMEA03",22UF,20%,C0805_H61,3278.31,12847.08,270.000,YES,,,
PC398_1,"Q_CAP_C0805-22UF,4V,20%,X6S,CH622KMEA03",22UF,20%,C0805_H61,3209.54,12846.94,270.000,YES,,,
PC401_C1P1_4,"Q_CAP_C0402-2.2UF,10V,10%,X6S,CH5222KEB01",2.2UF,10%,C0402,2291.01,13650.37,270.000,NO,,,
PC402_C1P1_3,"Q_CAP_C0402-2.2UF,10V,10%,X6S,CH5222KEB01",2.2UF,10%,C0402,2627.01,13188.91,270.000,NO,,,
PC403_4,"Q_CAP_0402-0.1UF,25V,10%,X7R,CH4104K1B00",0.1UF,10%,C0402,2329.95,13841.68,90.000,NO,,,
PC404_3,"Q_CAP_0402-0.1UF,25V,10%,X7R,CH4104K1B00",0.1UF,10%,C0402,2665.95,13380.22,90.000,NO,,,
PC405_4,"Q_CAP_0402-0.1UF,25V,10%,X7R,CH4104K1B00",0.1UF,10%,C0402,2617.78,13656.25,270.000,NO,,,
PC406_3,"Q_CAP_C0402-1UF,25V,10%,X6S,CH5104KEB02",1UF,10%,C0402,2915.10,13192.89,270.000,NO,,,
PC407_4,"Q_CAP_C0402-1UF,25V,10%,X6S,CH5104KEB02",1UF,10%,C0402,2579.10,13656.35,270.000,NO,,,
PC408_3,"Q_CAP_0402-0.1UF,25V,10%,X7R,CH4104K1B00",0.1UF,10%,C0402,2859.67,13427.05,180.000,NO,,,
PC409_4,"Q_CAP_C0805-22UF,16V,20%,X6S,CH6223MEA01",22UF,20%,C0805_H57,2480.17,13653.11,90.000,YES,,,
PC410_3,"Q_CAP_C0805-22UF,16V,20%,X6S,CH6223MEA01",22UF,20%,C0805_H57,2816.17,13344.08,270.000,YES,,,
PC411_4,"Q_CAP_C0805-22UF,16V,20%,X6S,CH6223MEA01",22UF,20%,C0805_H57,2563.95,13653.11,90.000,YES,,,
PC412_3,"Q_CAP_C0805-22UF,16V,20%,X6S,CH6223MEA01",22UF,20%,C0805_H57,2899.95,13191.65,90.000,YES,,,
PC415_4,"Q_CAP_C0805-22UF,16V,20%,X6S,CH6223MEA01",22UF,20%,C0805_H57,2480.17,13805.54,270.000,YES,,,
PC416_3,"Q_CAP_C0805-22UF,16V,20%,X6S,CH6223MEA01",22UF,20%,C0805_H57,2816.17,13191.65,90.000,YES,,,
PC417_3,"Q_CAP_C0805-22UF,4V,20%,X6S,CH622KMEA03",22UF,20%,C0805_H61,2388.94,13310.51,270.000,YES,,,
PC418_4,"Q_CAP_C0805-22UF,4V,20%,X6S,CH622KMEA03",22UF,20%,C0805_H61,2555.58,13310.51,270.000,YES,,,
PC419_3,"Q_CAP_C0805-22UF,4V,20%,X6S,CH622KMEA03",22UF,20%,C0805_H61,2299.94,13310.51,270.000,YES,,,
PC420_4,"Q_CAP_C0805-22UF,4V,20%,X6S,CH622KMEA03",22UF,20%,C0805_H61,2470.58,13310.68,270.000,YES,,,
PC422_5,"Q_CAP_0402-0.1UF,25V,10%,X7R,CH4104K1B00",0.1UF,10%,C0402,3651.95,13381.37,90.000,NO,,,
PC423_C1P1_5,"Q_CAP_C0402-2.2UF,10V,10%,X6S,CH5222KEB01",2.2UF,10%,C0402,3613.01,13190.06,270.000,NO,,,
PC424_5,"Q_CAP_C0402-1UF,25V,10%,X6S,CH5104KEB02",1UF,10%,C0402,3901.10,13196.04,270.000,NO,,,
PC425_5,"Q_CAP_0402-0.1UF,25V,10%,X7R,CH4104K1B00",0.1UF,10%,C0402,3595.17,13362.74,0.000,NO,,,
PC426_5,"Q_CAP_C0805-22UF,16V,20%,X6S,CH6223MEA01",22UF,20%,C0805_H57,3885.95,13192.80,90.000,YES,,,
PC427_5,"Q_CAP_C0805-22UF,16V,20%,X6S,CH6223MEA01",22UF,20%,C0805_H57,3802.17,13192.80,90.000,YES,,,
PC429_5,"Q_CAP_C0805-22UF,16V,20%,X6S,CH6223MEA01",22UF,20%,C0805_H57,3802.17,13345.23,270.000,YES,,,
PC430_5,"Q_CAP_C0805-22UF,4V,20%,X6S,CH622KMEA03",22UF,20%,C0805_H61,3897.01,12867.13,270.000,YES,,,
PC431_5,"Q_CAP_C0805-22UF,4V,20%,X6S,CH622KMEA03",22UF,20%,C0805_H61,3622.01,12849.13,270.000,YES,,,
PC434_IOP1_2,"Q_CAP_C0402-2.2UF,10V,10%,X6S,CH5222KEB01",2.2UF,10%,C0402,1634.01,13650.37,270.000,NO,,,
PC435_7,"Q_CAP_0402-0.1UF,25V,10%,X7R,CH4104K1B00",0.1UF,10%,C0402,2001.95,13841.68,90.000,NO,,,
PC436_8,"Q_CAP_0402-0.1UF,25V,10%,X7R,CH4104K1B00",0.1UF,10%,C0402,1672.95,13841.68,90.000,NO,,,
PC437_IOP1_1,"Q_CAP_C0402-2.2UF,10V,10%,X6S,CH5222KEB01",2.2UF,10%,C0402,1963.01,13650.37,270.000,NO,,,
PC438_1,"Q_CAP_0402-0.1UF,25V,10%,X7R,CH4104K1B00",0.1UF,10%,C0402,1945.17,13823.05,0.000,NO,,,
PC439_2,"Q_CAP_0402-0.1UF,25V,10%,X7R,CH4104K1B00",0.1UF,10%,C0402,1616.17,13823.05,0.000,NO,,,
PC440_1,"Q_CAP_C0402-1UF,25V,10%,X6S,CH5104KEB02",1UF,10%,C0402,2251.10,13656.35,270.000,NO,,,
PC441_2,"Q_CAP_C0402-1UF,25V,10%,X6S,CH5104KEB02",1UF,10%,C0402,1922.10,13656.35,270.000,NO,,,
PC442_1,"Q_CAP_C0805-22UF,16V,20%,X6S,CH6223MEA01",22UF,20%,C0805_H57,2152.17,13805.54,270.000,YES,,,
PC443_2,"Q_CAP_C0805-22UF,16V,20%,X6S,CH6223MEA01",22UF,20%,C0805_H57,1823.17,13653.11,90.000,YES,,,
PC444_1,"Q_CAP_C0805-22UF,16V,20%,X6S,CH6223MEA01",22UF,20%,C0805_H57,2235.95,13653.11,90.000,YES,,,
PC446_2,"Q_CAP_C0805-22UF,16V,20%,X6S,CH6223MEA01",22UF,20%,C0805_H57,1823.17,13805.54,270.000,YES,,,
PC448_1,"Q_CAP_C0805-22UF,16V,20%,X6S,CH6223MEA01",22UF,20%,C0805_H57,2152.17,13653.11,90.000,YES,,,
PC449_2,"Q_CAP_C0805-22UF,16V,20%,X6S,CH6223MEA01",22UF,20%,C0805_H57,1906.95,13653.11,90.000,YES,,,
PC456_1,"Q_CAP_C0805-22UF,4V,20%,X6S,CH622KMEA03",22UF,20%,C0805_H61,1944.94,13306.51,270.000,YES,,,
PC458_2,"Q_CAP_C0805-22UF,4V,20%,X6S,CH622KMEA03",22UF,20%,C0805_H61,1702.66,13306.68,270.000,YES,,,
PC459_1,"Q_CAP_C0805-22UF,4V,20%,X6S,CH622KMEA03",22UF,20%,C0805_H61,1866.82,13306.68,270.000,YES,,,
PC460_2,"Q_CAP_C0805-22UF,4V,20%,X6S,CH622KMEA03",22UF,20%,C0805_H61,1784.74,13306.68,270.000,YES,,,
PC473_1,"Q_CAP_0402-0.1UF,25V,10%,X7R,CH4104K1B00",0.1UF,10%,C0402,14449.13,6807.63,270.000,NO,,,
PC474_2,"Q_CAP_0402-0.1UF,25V,10%,X7R,CH4104K1B00",0.1UF,10%,C0402,14778.31,7003.40,270.000,NO,,,
PC477_C0P0_1,"Q_CAP_C0402-2.2UF,10V,10%,X6S,CH5222KEB01",2.2UF,10%,C0402,14488.07,6998.94,90.000,NO,,,
PC478_C0P0_2,"Q_CAP_C0402-2.2UF,10V,10%,X6S,CH5222KEB01",2.2UF,10%,C0402,14817.25,7194.71,90.000,NO,,,
PC479_1,"Q_CAP_0402-0.1UF,25V,10%,X7R,CH4104K1B00",0.1UF,10%,C0402,14322.57,6757.65,0.000,NO,,,
PC480_2,"Q_CAP_C0402-1UF,25V,10%,X6S,CH5104KEB02",1UF,10%,C0402,14527.65,7189.07,90.000,NO,,,
PC481_1,"Q_CAP_C0402-1UF,25V,10%,X6S,CH5104KEB02",1UF,10%,C0402,14200.07,6992.31,90.000,NO,,,
PC482_2,"Q_CAP_0402-0.1UF,25V,10%,X7R,CH4104K1B00",0.1UF,10%,C0402,14637.57,6952.65,0.000,NO,,,
PC483_1,"Q_CAP_C0805-22UF,16V,20%,X6S,CH6223MEA01",22UF,20%,C0805_H57,14294.84,6851.10,90.000,YES,,,
PC484_2,"Q_CAP_C0805-22UF,16V,20%,X6S,CH6223MEA01",22UF,20%,C0805_H57,14631.89,7047.04,90.000,YES,,,
PC485_1,"Q_CAP_C0805-22UF,16V,20%,X6S,CH6223MEA01",22UF,20%,C0805_H57,14302.64,7003.74,270.000,YES,,,
PC486_2,"Q_CAP_C0805-22UF,16V,20%,X6S,CH6223MEA01",22UF,20%,C0805_H57,14544.31,7191.97,270.000,YES,,,
PC487_1,"Q_CAP_C0805-22UF,16V,20%,X6S,CH6223MEA01",22UF,20%,C0805_H57,14222.64,7003.74,270.000,YES,,,
PC488_2,"Q_CAP_C0805-22UF,16V,20%,X6S,CH6223MEA01",22UF,20%,C0805_H57,14628.09,7191.97,270.000,YES,,,
PC499_2,"Q_CAP_C0805-22UF,4V,20%,X6S,CH622KMEA03",22UF,20%,C0805_H61,14233.90,7331.73,90.000,YES,,,
PC500_1,"Q_CAP_C0805-22UF,4V,20%,X6S,CH622KMEA03",22UF,20%,C0805_H61,13686.02,6684.53,90.000,YES,,,
PC501_2,"Q_CAP_C0805-22UF,4V,20%,X6S,CH622KMEA03",22UF,20%,C0805_H61,14523.34,7532.45,90.000,YES,,,
PC502_1,"Q_CAP_C0805-22UF,4V,20%,X6S,CH622KMEA03",22UF,20%,C0805_H61,13796.44,6746.10,90.000,YES,,,
PC503_1,"Q_CAP_0402-0.1UF,25V,10%,X7R,CH4104K1B00",0.1UF,10%,C0402,7095.51,14021.77,90.000,NO,,,
PC504_2,"Q_CAP_0402-0.1UF,25V,10%,X7R,CH4104K1B00",0.1UF,10%,C0402,7423.33,14022.77,90.000,NO,,,
PC507_11P1_1,"Q_CAP_C0402-2.2UF,10V,10%,X6S,CH5222KEB01",2.2UF,10%,C0402,7056.57,13830.46,270.000,NO,,,
PC508_11P1_2,"Q_CAP_C0402-2.2UF,10V,10%,X6S,CH5222KEB01",2.2UF,10%,C0402,7384.39,13831.46,270.000,NO,,,
PC509_1,"Q_CAP_0402-0.1UF,25V,10%,X7R,CH4104K1B00",0.1UF,10%,C0402,7366.55,14004.14,0.000,NO,,,
PC510_2,"Q_CAP_0402-0.1UF,25V,10%,X7R,CH4104K1B00",0.1UF,10%,C0402,7712.16,13835.01,270.000,NO,,,
PC511_1,"Q_CAP_C0402-1UF,25V,10%,X6S,CH5104KEB02",1UF,10%,C0402,7345.57,13834.01,270.000,NO,,,
PC512_2,"Q_CAP_C0402-1UF,25V,10%,X6S,CH5104KEB02",1UF,10%,C0402,7673.39,13835.01,270.000,NO,,,
PC513_1,"Q_CAP_C0805-22UF,16V,20%,X6S,CH6223MEA01",22UF,20%,C0805_H57,7241.98,13827.30,90.000,YES,,,
PC514_2,"Q_CAP_C0805-22UF,16V,20%,X6S,CH6223MEA01",22UF,20%,C0805_H57,7650.95,13828.30,90.000,YES,,,
PC515_1,"Q_CAP_C0805-22UF,16V,20%,X6S,CH6223MEA01",22UF,20%,C0805_H57,7323.13,13827.30,90.000,YES,,,
PC516_2,"Q_CAP_C0805-22UF,16V,20%,X6S,CH6223MEA01",22UF,20%,C0805_H57,7569.80,13828.30,90.000,YES,,,
PC517_1,"Q_CAP_C0805-22UF,16V,20%,X6S,CH6223MEA01",22UF,20%,C0805_H57,7249.00,13978.46,270.000,YES,,,
PC518_2,"Q_CAP_C0805-22UF,16V,20%,X6S,CH6223MEA01",22UF,20%,C0805_H57,7579.19,13979.46,270.000,YES,,,
PC521_1,"Q_CAP_C0805-22UF,16V,20%,X6S,CH6223MEA01",22UF,20%,C0805_H57,7291.41,14081.38,0.000,YES,,,
PC523_2,"Q_CAP_C0805-22UF,4V,20%,X6S,CH622KMEA03",22UF,20%,C0805_H61,7664.55,13468.60,270.000,YES,,,
PC526_1,"Q_CAP_C0805-22UF,4V,20%,X6S,CH622KMEA03",22UF,20%,C0805_H61,7061.21,13474.88,270.000,YES,,,
PC527_2,"Q_CAP_C0805-22UF,4V,20%,X6S,CH622KMEA03",22UF,20%,C0805_H61,7352.71,13474.88,270.000,YES,,,
PC529_1,"Q_CAP_C0805-22UF,4V,20%,X6S,CH622KMEA03",22UF,20%,C0805_H61,6785.52,13474.88,270.000,YES,,,
PC544_3,"Q_CAP_0402-0.1UF,25V,10%,X7R,CH4104K1B00",0.1UF,10%,C0402,15109.13,7003.40,270.000,NO,,,
PC545_4,"Q_CAP_0402-0.1UF,25V,10%,X7R,CH4104K1B00",0.1UF,10%,C0402,15437.13,7003.40,270.000,NO,,,
PC548_C0P0_3,"Q_CAP_C0402-2.2UF,10V,10%,X6S,CH5222KEB01",2.2UF,10%,C0402,15148.07,7194.71,90.000,NO,,,
PC549_C0P0_4,"Q_CAP_C0402-2.2UF,10V,10%,X6S,CH5222KEB01",2.2UF,10%,C0402,15476.07,7194.71,90.000,NO,,,
PC550_3,"Q_CAP_C0402-1UF,25V,10%,X6S,CH5104KEB02",1UF,10%,C0402,14858.97,7191.38,90.000,NO,,,
PC551_4,"Q_CAP_0402-0.1UF,25V,10%,X7R,CH4104K1B00",0.1UF,10%,C0402,15165.91,7022.03,180.000,NO,,,
PC552_3,"Q_CAP_0402-0.1UF,25V,10%,X7R,CH4104K1B00",0.1UF,10%,C0402,14835.09,7022.03,180.000,NO,,,
PC553_4,"Q_CAP_C0402-1UF,25V,10%,X6S,CH5104KEB02",1UF,10%,C0402,15186.97,7191.38,90.000,NO,,,
PC554_3,"Q_CAP_C0805-22UF,16V,20%,X6S,CH6223MEA01",22UF,20%,C0805_H57,14956.24,7046.37,90.000,YES,,,
PC555_4,"Q_CAP_C0805-22UF,16V,20%,X6S,CH6223MEA01",22UF,20%,C0805_H57,15283.34,7045.87,90.000,YES,,,
PC556_3,"Q_CAP_C0805-22UF,16V,20%,X6S,CH6223MEA01",22UF,20%,C0805_H57,14882.64,7199.51,270.000,YES,,,
PC557_4,"Q_CAP_C0805-22UF,16V,20%,X6S,CH6223MEA01",22UF,20%,C0805_H57,15290.64,7199.51,270.000,YES,,,
PC558_3,"Q_CAP_C0805-22UF,16V,20%,X6S,CH6223MEA01",22UF,20%,C0805_H57,14962.64,7199.51,270.000,YES,,,
PC559_4,"Q_CAP_C0805-22UF,16V,20%,X6S,CH6223MEA01",22UF,20%,C0805_H57,15210.64,7199.51,270.000,YES,,,
PC562_3,"Q_CAP_C0805-22UF,4V,20%,X6S,CH622KMEA03",22UF,20%,C0805_H61,15104.54,7532.87,90.000,YES,,,
PC563_4,"Q_CAP_C0805-22UF,4V,20%,X6S,CH622KMEA03",22UF,20%,C0805_H61,15460.47,7709.88,90.000,YES,,,
PC564_3,"Q_CAP_C0805-22UF,4V,20%,X6S,CH622KMEA03",22UF,20%,C0805_H61,14829.00,7529.40,90.000,YES,,,
PC565_4,"Q_CAP_C0805-22UF,4V,20%,X6S,CH622KMEA03",22UF,20%,C0805_H61,15173.00,7532.70,90.000,YES,,,
PC566_5,"Q_CAP_0402-0.1UF,25V,10%,X7R,CH4104K1B00",0.1UF,10%,C0402,14123.13,6481.83,270.000,NO,,,
PC568_C0P0_5,"Q_CAP_C0402-2.2UF,10V,10%,X6S,CH5222KEB01",2.2UF,10%,C0402,14162.07,6673.14,90.000,NO,,,
PC569_5,"Q_CAP_C0402-1UF,25V,10%,X6S,CH5104KEB02",1UF,10%,C0402,13872.97,6669.81,90.000,NO,,,
PC570_5,"Q_CAP_0402-0.1UF,25V,10%,X7R,CH4104K1B00",0.1UF,10%,C0402,13982.57,6427.65,0.000,NO,,,
PC571_5,"Q_CAP_C0805-22UF,16V,20%,X6S,CH6223MEA01",22UF,20%,C0805_H57,13969.24,6524.80,90.000,YES,,,
PC572_5,"Q_CAP_C0805-22UF,16V,20%,X6S,CH6223MEA01",22UF,20%,C0805_H57,13896.64,6677.94,270.000,YES,,,
PC573_5,"Q_CAP_C0805-22UF,16V,20%,X6S,CH6223MEA01",22UF,20%,C0805_H57,13976.64,6677.94,270.000,YES,,,
PC575_5,"Q_CAP_C0805-22UF,4V,20%,X6S,CH622KMEA03",22UF,20%,C0805_H61,14150.44,7073.80,90.000,YES,,,
PC576_5,"Q_CAP_C0805-22UF,4V,20%,X6S,CH622KMEA03",22UF,20%,C0805_H61,13875.00,7004.43,90.000,YES,,,
PC577_7,"Q_CAP_0402-0.1UF,25V,10%,X7R,CH4104K1B00",0.1UF,10%,C0402,15768.43,6784.00,270.000,NO,,,
PC578_8,"Q_CAP_0402-0.1UF,25V,10%,X7R,CH4104K1B00",0.1UF,10%,C0402,16096.13,6446.31,270.000,NO,,,
PC581_SOP0_1,"Q_CAP_C0402-2.2UF,10V,10%,X6S,CH5222KEB01",2.2UF,10%,C0402,15807.37,6975.31,90.000,NO,,,
PC582_SOP0_2,"Q_CAP_C0402-2.2UF,10V,10%,X6S,CH5222KEB01",2.2UF,10%,C0402,16135.07,6637.62,90.000,NO,,,
PC583_1,"Q_CAP_0402-0.1UF,25V,10%,X7R,CH4104K1B00",0.1UF,10%,C0402,15478.27,6970.30,90.000,NO,,,
PC584_2,"Q_CAP_C0402-1UF,25V,10%,X6S,CH5104KEB02",1UF,10%,C0402,15845.97,6634.29,90.000,NO,,,
PC585_1,"Q_CAP_C0402-1UF,25V,10%,X6S,CH5104KEB02",1UF,10%,C0402,15518.27,6970.30,90.000,NO,,,
PC586_2,"Q_CAP_0402-0.1UF,25V,10%,X7R,CH4104K1B00",0.1UF,10%,C0402,15805.97,6634.29,90.000,NO,,,
PC587_1,"Q_CAP_C0805-22UF,16V,20%,X6S,CH6223MEA01",22UF,20%,C0805_H57,15614.64,6826.57,90.000,YES,,,
PC588_2,"Q_CAP_C0805-22UF,16V,20%,X6S,CH6223MEA01",22UF,20%,C0805_H57,15941.84,6488.38,90.000,YES,,,
PC589_1,"Q_CAP_C0805-22UF,16V,20%,X6S,CH6223MEA01",22UF,20%,C0805_H57,15621.94,6980.11,270.000,YES,,,
PC590_2,"Q_CAP_C0805-22UF,16V,20%,X6S,CH6223MEA01",22UF,20%,C0805_H57,15949.64,6642.42,270.000,YES,,,
PC591_1,"Q_CAP_C0805-22UF,16V,20%,X6S,CH6223MEA01",22UF,20%,C0805_H57,15541.94,6980.11,270.000,YES,,,
PC592_2,"Q_CAP_C0805-22UF,16V,20%,X6S,CH6223MEA01",22UF,20%,C0805_H57,15869.64,6642.42,270.000,YES,,,
PC593_1,"Q_CAP_C0805-22UF,16V,20%,X6S,CH6223MEA01",22UF,20%,C0805_H57,15585.87,6710.98,180.000,YES,,,
PC595_2,"Q_CAP_C0805-22UF,16V,20%,X6S,CH6223MEA01",22UF,20%,C0805_H57,15800.67,6642.58,270.000,YES,,,
PC600_2,"Q_CAP_C0805-22UF,4V,20%,X6S,CH622KMEA03",22UF,20%,C0805_H61,16148.04,6977.38,90.000,YES,,,
PC602_1,"Q_CAP_C0805-22UF,4V,20%,X6S,CH622KMEA03",22UF,20%,C0805_H61,15801.54,7308.40,90.000,YES,,,
PC603_2,"Q_CAP_C0805-22UF,4V,20%,X6S,CH622KMEA03",22UF,20%,C0805_H61,15873.20,7038.30,90.000,YES,,,
PC604_1,"Q_CAP_C0805-22UF,4V,20%,X6S,CH622KMEA03",22UF,20%,C0805_H61,15525.00,7308.40,90.000,YES,,,
PC605_9,"Q_CAP_0402-0.1UF,25V,10%,X7R,CH4104K1B00",0.1UF,10%,C0402,16441.88,6272.06,0.000,NO,,,
PC607_SOP0_3,"Q_CAP_C0402-2.2UF,10V,10%,X6S,CH5222KEB01",2.2UF,10%,C0402,16465.07,6447.62,90.000,NO,,,
PC608_3,"Q_CAP_C0402-1UF,25V,10%,X6S,CH5104KEB02",1UF,10%,C0402,16175.97,6444.29,90.000,NO,,,
PC609_3,"Q_CAP_0402-0.1UF,25V,10%,X7R,CH4104K1B00",0.1UF,10%,C0402,16135.97,6444.29,90.000,NO,,,
PC610_3,"Q_CAP_C0805-22UF,16V,20%,X6S,CH6223MEA01",22UF,20%,C0805_H57,16199.64,6452.42,270.000,YES,,,
PC611_3,"Q_CAP_C0805-22UF,16V,20%,X6S,CH6223MEA01",22UF,20%,C0805_H57,16271.84,6298.78,90.000,YES,,,
PC612_3,"Q_CAP_C0805-22UF,16V,20%,X6S,CH6223MEA01",22UF,20%,C0805_H57,16126.92,6397.97,270.000,YES,,,
PC613_3,"Q_CAP_C0805-22UF,16V,20%,X6S,CH6223MEA01",22UF,20%,C0805_H57,16279.64,6452.42,270.000,YES,,,
PC614_3,"Q_CAP_C0805-22UF,4V,20%,X6S,CH622KMEA03",22UF,20%,C0805_H61,16223.00,6787.68,90.000,YES,,,
PC615_3,"Q_CAP_C0805-22UF,4V,20%,X6S,CH622KMEA03",22UF,20%,C0805_H61,16498.54,6787.68,90.000,YES,,,
PC618_IOP1_4,"Q_CAP_C0402-2.2UF,10V,10%,X6S,CH5222KEB01",2.2UF,10%,C0402,981.01,13650.37,270.000,NO,,,
PC619_IOP1_3,"Q_CAP_C0402-2.2UF,10V,10%,X6S,CH5222KEB01",2.2UF,10%,C0402,1307.01,13650.37,270.000,NO,,,
PC620_9,"Q_CAP_0402-0.1UF,25V,10%,X7R,CH4104K1B00",0.1UF,10%,C0402,1345.95,13841.68,90.000,NO,,,
PC621_10,"Q_CAP_0402-0.1UF,25V,10%,X7R,CH4104K1B00",0.1UF,10%,C0402,1019.95,13841.68,90.000,NO,,,
PC622_3,"Q_CAP_0402-0.1UF,25V,10%,X7R,CH4104K1B00",0.1UF,10%,C0402,1289.17,13823.05,0.000,NO,,,
PC623_4,"Q_CAP_0402-0.1UF,25V,10%,X7R,CH4104K1B00",0.1UF,10%,C0402,2273.17,13823.05,0.000,NO,,,
PC624_3,"Q_CAP_C0402-1UF,25V,10%,X6S,CH5104KEB02",1UF,10%,C0402,1595.10,13654.08,270.000,NO,,,
PC625_4,"Q_CAP_C0402-1UF,25V,10%,X6S,CH5104KEB02",1UF,10%,C0402,1269.10,13656.35,270.000,NO,,,
PC626_3,"Q_CAP_C0805-22UF,16V,20%,X6S,CH6223MEA01",22UF,20%,C0805_H57,1496.17,13653.11,90.000,YES,,,
PC627_4,"Q_CAP_C0805-22UF,16V,20%,X6S,CH6223MEA01",22UF,20%,C0805_H57,1253.95,13653.11,90.000,YES,,,
PC628_3,"Q_CAP_C0805-22UF,16V,20%,X6S,CH6223MEA01",22UF,20%,C0805_H57,1496.17,13805.54,270.000,YES,,,
PC629_4,"Q_CAP_C0805-22UF,16V,20%,X6S,CH6223MEA01",22UF,20%,C0805_H57,1170.17,13805.54,270.000,YES,,,
PC632_3,"Q_CAP_C0805-22UF,16V,20%,X6S,CH6223MEA01",22UF,20%,C0805_H57,1579.95,13653.11,90.000,YES,,,
PC633_4,"Q_CAP_C0805-22UF,16V,20%,X6S,CH6223MEA01",22UF,20%,C0805_H57,1170.17,13653.11,90.000,YES,,,
PC634_4,"Q_CAP_C0805-22UF,4V,20%,X6S,CH622KMEA03",22UF,20%,C0805_H61,979.94,13306.51,270.000,YES,,,
PC635_3,"Q_CAP_C0805-22UF,4V,20%,X6S,CH622KMEA03",22UF,20%,C0805_H61,1339.94,13307.51,270.000,YES,,,
PC636_4,"Q_CAP_C0805-22UF,4V,20%,X6S,CH622KMEA03",22UF,20%,C0805_H61,1255.58,13306.68,270.000,YES,,,
PC637_3,"Q_CAP_C0805-22UF,4V,20%,X6S,CH622KMEA03",22UF,20%,C0805_H61,1620.58,13306.68,270.000,YES,,,
PC6550_09P0_1,"Q_CAP_C0402-2.2UF,10V,10%,X6S,CH5222KEB01",2.2UF,10%,C0402,17379.14,15647.07,270.000,NO,,,
PC6551_09P0_2,"Q_CAP_C0402-2.2UF,10V,10%,X6S,CH5222KEB01",2.2UF,10%,C0402,17736.57,15652.07,270.000,NO,,,
PC6553_1,"Q_CAP_C0402-100NF,50V,10%,X7R,CH4106K1B01",100NF,10%,C0402,17392.79,15859.78,90.000,NO,,,
PC6554_1,"Q_CAP_C0402-1UF,25V,10%,X6S,CH5104KEB02",1UF,10%,C0402,17666.06,15645.63,270.000,NO,,,
PC6555_1,"Q_CAP_0402-3300PF,50V,10%,X7R,TMP_QCH2336K1B12",3300PF,10%,C0402,17674.79,15824.05,0.000,NO,,,
PC6556_1,"Q_CAP_C0805-22UF,16V,20%,X6S,CH6223MEA01",22UF,20%,C0805_H57,17569.04,15632.05,90.000,YES,,,
PC6557_1,"Q_CAP_C0805-22UF,16V,20%,X6S,CH6223MEA01",22UF,20%,C0805_H57,17653.10,15632.05,90.000,YES,,,
PC6558_1,"Q_CAP_C0805-22UF,16V,20%,X6S,CH6223MEA01",22UF,20%,C0805_H57,17607.79,15975.50,180.000,NO,,,
PC6559_1,"Q_CAP_C0805-22UF,16V,20%,X6S,CH6223MEA01",22UF,20%,C0805_H57,17607.79,16049.50,180.000,NO,,,
PC6566_1,"Q_CAP_C0805-22UF,4V,20%,X6S,CH622KMEA03",22UF,20%,C0805_H61,18084.22,15320.16,270.000,YES,,,
PC6567_1,"Q_CAP_C0805-22UF,4V,20%,X6S,CH622KMEA03",22UF,20%,C0805_H61,18169.22,15320.16,270.000,YES,,,
PC6577_2,"Q_CAP_C0402-1UF,25V,10%,X6S,CH5104KEB02",1UF,10%,C0402,18023.49,15642.63,270.000,NO,,,
PC6578_2,"Q_CAP_0402-3300PF,50V,10%,X7R,TMP_QCH2336K1B12",3300PF,10%,C0402,17934.04,15871.05,180.000,NO,,,
PC6579_2,"Q_CAP_C0805-22UF,16V,20%,X6S,CH6223MEA01",22UF,20%,C0805_H57,17921.79,15632.05,90.000,YES,,,
PC6580_2,"Q_CAP_C0805-22UF,16V,20%,X6S,CH6223MEA01",22UF,20%,C0805_H57,18005.79,15632.05,90.000,YES,,,
PC6581_2,"Q_CAP_C0805-22UF,16V,20%,X6S,CH6223MEA01",22UF,20%,C0805_H57,18045.13,15983.16,0.000,NO,,,
PC6582_2,"Q_CAP_C0805-22UF,16V,20%,X6S,CH6223MEA01",22UF,20%,C0805_H57,18045.13,16058.16,0.000,NO,,,
PC6586_2,"Q_CAP_C0805-22UF,4V,20%,X6S,CH622KMEA03",22UF,20%,C0805_H61,17733.52,15338.61,270.000,YES,,,
PC6587_2,"Q_CAP_C0805-22UF,4V,20%,X6S,CH622KMEA03",22UF,20%,C0805_H61,17441.48,15320.80,270.000,YES,,,
PC6609_09P1_1,"Q_CAP_C0402-2.2UF,10V,10%,X6S,CH5222KEB01",2.2UF,10%,C0402,506.31,15316.71,270.000,NO,,,
PC6611_1,"Q_CAP_C0402-100NF,50V,10%,X7R,CH4106K1B01",100NF,10%,C0402,519.96,15529.42,90.000,NO,,,
PC6612_1,"Q_CAP_C0402-1UF,25V,10%,X6S,CH5104KEB02",1UF,10%,C0402,793.23,15315.27,270.000,NO,,,
PC6613_1,"Q_CAP_0402-3300PF,50V,10%,X7R,TMP_QCH2336K1B12",3300PF,10%,C0402,801.96,15493.69,0.000,NO,,,
PC6614_1,"Q_CAP_C0805-22UF,16V,20%,X6S,CH6223MEA01",22UF,20%,C0805_H57,784.05,15306.69,90.000,YES,,,
PC6615_1,"Q_CAP_C0805-22UF,16V,20%,X6S,CH6223MEA01",22UF,20%,C0805_H57,704.75,15306.69,90.000,YES,,,
PC6616_1,"Q_CAP_C0805-22UF,16V,20%,X6S,CH6223MEA01",22UF,20%,C0805_H57,710.22,15716.89,0.000,YES,,,
PC6617_1,"Q_CAP_C0805-22UF,16V,20%,X6S,CH6223MEA01",22UF,20%,C0805_H57,710.22,15647.89,0.000,YES,,,
PC6624_1,"Q_CAP_C0805-22UF,4V,20%,X6S,CH622KMEA03",22UF,20%,C0805_H61,361.47,15080.77,270.000,YES,,,
PC6625_1,"Q_CAP_C0805-22UF,4V,20%,X6S,CH622KMEA03",22UF,20%,C0805_H61,429.55,15080.77,270.000,YES,,,
PC6633_2,"Q_CAP_C0402-1UF,25V,10%,X6S,CH5104KEB02",1UF,10%,C0402,1061.21,15540.69,180.000,NO,,,
PC6634_2,"Q_CAP_0402-3300PF,50V,10%,X7R,TMP_QCH2336K1B12",3300PF,10%,C0402,1150.66,15312.27,270.000,NO,,,
PC6635_2,"Q_CAP_C0805-22UF,16V,20%,X6S,CH6223MEA01",22UF,20%,C0805_H57,1128.26,15301.34,90.000,YES,,,
PC6636_2,"Q_CAP_C0805-22UF,16V,20%,X6S,CH6223MEA01",22UF,20%,C0805_H57,1048.87,15300.68,90.000,YES,,,
PC6637_2,"Q_CAP_C0805-22UF,16V,20%,X6S,CH6223MEA01",22UF,20%,C0805_H57,1217.98,15645.53,0.000,NO,,,
PC6638_2,"Q_CAP_C0805-22UF,16V,20%,X6S,CH6223MEA01",22UF,20%,C0805_H57,711.68,15593.57,180.000,NO,,,
PC6642_2,"Q_CAP_C0805-22UF,4V,20%,X6S,CH622KMEA03",22UF,20%,C0805_H61,708.64,15079.87,270.000,YES,,,
PC6643_2,"Q_CAP_C0805-22UF,4V,20%,X6S,CH622KMEA03",22UF,20%,C0805_H61,777.49,15080.24,270.000,YES,,,
PC6644_09P1_2,"Q_CAP_C0402-2.2UF,10V,10%,X6S,CH5222KEB01",2.2UF,10%,C0402,863.74,15321.71,270.000,NO,,,
PC3,"Q_CAPP_THLF-270UF,16V,20%,OSCON,CC72703MD38",270UF,20%,EC2-5_6-8_9-2,17012.85,1986.12,180.000,NO,,,
PC4,"Q_CAP_0402-0.1UF,25V,10%,X7R,CH4104K1B00",0.1UF,10%,C0402,16662.90,14402.07,90.000,NO,,,
PC5,"Q_CAP_0402-0.1UF,25V,10%,X7R,CH4104K1B00",0.1UF,10%,C0402,16677.56,14322.15,0.000,NO,,,
PC6,"Q_CAP_0402-0.1UF,25V,10%,X7R,CH4104K1B00",0.1UF,10%,C0402,3991.57,5574.15,180.000,YES,,,
PC7,"Q_CAP_0402-0.1UF,25V,10%,X7R,CH4104K1B00",0.1UF,10%,C0402,15122.57,5479.77,180.000,YES,,,
PC8,"Q_CAP_0402-0.1UF,25V,10%,X7R,CH4104K1B00",0.1UF,10%,C0402,6571.68,13789.31,0.000,NO,,,
PC9,"Q_CAP_0402-0.1UF,25V,10%,X7R,CH4104K1B00",0.1UF,10%,C0402,16900.66,14015.66,90.000,NO,,,
PC10,"Q_CAP_0402-0.1UF,25V,10%,X7R,CH4104K1B00",0.1UF,10%,C0402,3956.57,5509.15,90.000,YES,,,
PC11,"Q_CAP_0402-0.1UF,25V,10%,X7R,CH4104K1B00",0.1UF,10%,C0402,3876.57,5509.15,90.000,YES,,,
PC12,"Q_CAP_0402-0.1UF,25V,10%,X7R,CH4104K1B00",0.1UF,10%,C0402,15087.57,5414.77,90.000,YES,,,
PC13,"Q_CAP_0402-0.1UF,25V,10%,X7R,CH4104K1B00",0.1UF,10%,C0402,15007.57,5414.77,90.000,YES,,,
PC14,"Q_CAP_0402-0.1UF,25V,10%,X7R,CH4104K1B00",0.1UF,10%,C0402,12450.00,14355.00,90.000,NO,,,
PC15,"Q_CAP_0402-0.1UF,25V,10%,X7R,CH4104K1B00",0.1UF,10%,C0402,12410.00,14425.00,90.000,NO,,,
PC19,"Q_CAP_0402-0.22UF,16V,10%,X7R,CH4223K1B00",0.22UF,10%,C0402,2623.43,5839.99,180.000,NO,,,
PC20,"Q_CAP_C0402-1UF,25V,10%,X6S,CH5104KEB02",1UF,10%,C0402,2694.19,6111.72,0.000,NO,,,
PC21,"Q_CAP_0402-0.1UF,25V,10%,X7R,CH4104K1B00",0.1UF,10%,C0402,2306.33,5711.29,0.000,NO,,,
PC22,"Q_CAP_C0402-1UF,25V,10%,X6S,CH5104KEB02",1UF,10%,C0402,2624.66,5966.53,270.000,NO,,,
PC27,"Q_CAP_C0805-22UF,16V,20%,X6S,CH6223MEA01",22UF,20%,C0805_H57,7719.08,13826.84,90.000,YES,,,
PC29,"Q_CAP_0402-0.1UF,25V,10%,X7R,CH4104K1B00",0.1UF,10%,C0402,1410.28,14506.12,90.000,NO,,,
PC60,"Q_CAP_C0805-22UF,16V,20%,X6S,CH6223MEA01",22UF,20%,C0805_H57,3030.39,6023.26,90.000,NO,,,
PC61,"Q_CAP_C0805-22UF,16V,20%,X6S,CH6223MEA01",22UF,20%,C0805_H57,2892.39,6023.26,90.000,NO,,,
PC62,"Q_CAP_0402-0.1UF,25V,10%,X7R,CH4104K1B00",0.1UF,10%,C0402,2784.01,5851.78,0.000,NO,,,
PC64,"Q_CAP_0402-220PF,50V,10%,X7R,TMP_QCH12206KB14",220PF,10%,C0402,2852.91,5776.98,180.000,NO,,,
PC65,"Q_CAP_C0805-22UF,4V,20%,X6S,CH622KMEA03",22UF,20%,C0805_H61,2309.33,6055.98,180.000,YES,,,
PC67,"Q_CAP_0402-0.1UF,25V,10%,X7R,CH4104K1B00",0.1UF,10%,C0402,12488.59,14215.00,270.000,NO,,,
PC68,"Q_CAP_0402-3300PF,50V,10%,X7R,TMP_QCH2336K1B12",3300PF,10%,C0402,12095.00,14010.00,0.000,NO,,,
PC71,"Q_CAP_0402-3300PF,50V,10%,X7R,TMP_QCH2336K1B12",3300PF,10%,C0402,12415.00,14065.00,180.000,NO,,,
PC73,"Q_CAP_0402-1UF,6.3V,10%,X7R,CH5101K1B01",1UF,10%,C0402,11985.00,14190.00,180.000,NO,,,
PC74,"Q_CAP_0402-0.1UF,25V,10%,X7R,CH4104K1B00",0.1UF,10%,C0402,12450.00,14285.00,90.000,NO,,,
PC75,"Q_CAP_C0402-1UF,16V,10%,X6S,CH5103KEB01",1UF,10%,C0402,12490.00,14355.00,90.000,NO,,,
PC76,"Q_CAP_C0402-10UF,6.3V,20%,X6S,CH6101MEB03",10UF,20%,C0402,12450.00,14425.00,90.000,NO,,,
PC77,"Q_CAP_0402-470PF,50V,10%,X7R,TMP_QCH14706KB18",470PF,10%,C0402,12433.17,14184.62,0.000,NO,,,
PC78,"Q_CAP_0402-470PF,50V,10%,X7R,TMP_QCH14706KB18",470PF,10%,C0402,12433.59,14223.62,0.000,NO,,,
PC79,"Q_CAP_C0402-2.2UF,10V,10%,X6S,CH5222KEB01",2.2UF,10%,C0402,13046.30,13292.87,90.000,NO,,,
PC80,"Q_CAP_C0402-2.2UF,10V,10%,X6S,CH5222KEB01",2.2UF,10%,C0402,12717.26,13293.44,90.000,NO,,,
PC81,"Q_CAP_C0805-22UF,16V,20%,X6S,CH6223MEA01",22UF,20%,C0805_H57,13235.14,5265.75,0.000,NO,,,
PC83,"Q_CAP_C0805-22UF,4V,20%,X6S,CH622KMEA03",22UF,20%,C0805_H61,2052.89,5992.45,180.000,NO,,,
PC84,"Q_CAP_C0805-22UF,4V,20%,X6S,CH622KMEA03",22UF,20%,C0805_H61,2309.15,5894.56,180.000,YES,,,
PC85,"Q_CAP_0402-0.1UF,25V,10%,X7R,CH4104K1B00",0.1UF,10%,C0402,13199.38,14082.82,180.000,NO,,,
PC87,"Q_CAP_C0805-22UF,4V,20%,EMPTY,CH622KMEA03",NA,20%,C0805_H61,2309.15,5975.56,180.000,YES,,,
PC88,"Q_CAP_C0805-22UF,4V,20%,EMPTY,CH622KMEA03",NA,20%,C0805_H61,2052.89,5911.45,180.000,NO,,,
PC89,"Q_CAPP_SMLF-390UF,2.5V,20%,ALUM,CC7390JMZ13",390UF,20%,EC56_197_229SXA,2126.41,6275.57,180.000,NO,,,
PC92,"Q_CAP_0402-0.22UF,16V,10%,X7R,CH4223K1B00",0.22UF,10%,C0402,13261.61,13371.08,270.000,NO,,,
PC93,"Q_CAP_0402-0.1UF,25V,10%,X7R,CH4104K1B00",0.1UF,10%,C0402,1331.20,14506.58,90.000,NO,,,
PC94,"Q_CAP_0402-0.22UF,16V,10%,X7R,CH4223K1B00",0.22UF,10%,C0402,12932.57,13371.65,270.000,NO,,,
PC95,"Q_CAP_0402-0.1UF,25V,10%,X7R,CH4104K1B00",0.1UF,10%,C0402,6557.02,13869.23,90.000,NO,,,
PC96,"Q_CAP_0402-0.1UF,25V,10%,X7R,CH4104K1B00",0.1UF,10%,C0402,6435.63,13883.97,90.000,NO,,,
PC97,"Q_CAPP_SMLF-220UF,4V,20%,SPCAP,CH122KM8801",220UF,20%,TAJ_SX,12536.90,12922.86,270.000,YES,,,
PC98,"Q_CAPP_SMLF-220UF,4V,20%,SPCAP,CH122KM8801",220UF,20%,TAJ_SX,13521.05,12921.76,270.000,YES,,,
PC99,"Q_CAP_0402-0.1UF,25V,10%,X7R,CH4104K1B00",0.1UF,10%,C0402,14036.90,12877.65,270.000,NO,,,
PC100,"Q_CAPP_SMLF-220UF,4V,20%,SPCAP,CH122KM8801",220UF,20%,TAJ_SX,13867.90,13115.00,270.000,YES,,,
PC101,"Q_CAPP_THLF-270UF,16V,20%,OSCON,CC72703MD38",270UF,20%,EC2-5_6-8_9-2,12911.46,13757.15,180.000,NO,,,
PC102,"Q_CAPP_SMLF-220UF,4V,20%,SPCAP,CH122KM8801",220UF,20%,TAJ_SX,12831.12,12922.86,270.000,YES,,,
PC103,"Q_CAPP_SMLF-220UF,4V,20%,SPCAP,CH122KM8801",220UF,20%,TAJ_SX,13177.05,12922.01,270.000,YES,,,
PC104,"Q_CAPP_THLF-270UF,16V,20%,OSCON,CC72703MD38",270UF,20%,EC2-5_6-8_9-2,13205.16,13757.15,180.000,NO,,,
PC105,"Q_CAPP_SMLF-220UF,4V,20%,SPCAP,CH122KM8801",220UF,20%,TAJ_SX,4229.51,7279.78,90.000,YES,,,
PC106,"Q_CAPP_SMLF-220UF,4V,20%,SPCAP,CH122KM8801",220UF,20%,TAJ_SX,4106.61,13115.19,270.000,YES,,,
PC107,"Q_CAP_0402-0.1UF,25V,10%,X7R,CH4104K1B00",0.1UF,10%,C0402,10649.15,13094.88,90.000,NO,,,
PC108,"Q_CAPP_SMLF-220UF,4V,20%,SPCAP,CH122KM8801",220UF,20%,TAJ_SX,14966.51,7459.12,90.000,YES,,,
PC109,"Q_CAP_C0402-2.2UF,10V,10%,X6S,CH5222KEB01",2.2UF,10%,C0402,12008.39,13755.18,90.000,NO,,,
PC110,"Q_CAP_C0402-2.2UF,10V,10%,X6S,CH5222KEB01",2.2UF,10%,C0402,12388.30,13293.72,90.000,NO,,,
PC111,"Q_CAP_C0805-22UF,16V,20%,X6S,CH6223MEA01",22UF,20%,C0805_H57,13235.14,5334.75,0.000,NO,,,
PC112,"Q_CAP_C0402-2.2UF,10V,10%,X6S,CH5222KEB01",2.2UF,10%,C0402,13700.12,13488.18,90.000,NO,,,
PC113,"Q_CAP_0402-0.1UF,25V,10%,X7R,CH4104K1B00",0.1UF,10%,C0402,13073.66,5512.13,270.000,NO,,,
PC114,"Q_CAP_C0805-22UF,4V,20%,X6S,CH622KMEA03",22UF,20%,C0805_H61,13239.36,6144.09,180.000,YES,,,
PC115,"Q_CAPP_SMLF-390UF,2.5V,20%,ALUM,CC7390JMZ13",390UF,20%,EC56_197_229SXA,13135.00,6335.00,90.000,NO,,,
PC117,"Q_CAP_0402-0.22UF,16V,10%,X7R,CH4223K1B00",0.22UF,10%,C0402,13915.43,13566.39,270.000,NO,,,
PC118,"Q_CAP_C0402-1UF,25V,10%,X6S,CH5104KEB02",1UF,10%,C0402,7794.47,13357.56,90.000,NO,,,
PC119,"Q_CAP_C0805-22UF,16V,20%,X6S,CH6223MEA01",22UF,20%,C0805_H57,7871.73,13622.96,180.000,NO,,,
PC120,"Q_CAP_C0805-22UF,16V,20%,X6S,CH6223MEA01",22UF,20%,C0805_H57,7871.73,13553.96,180.000,NO,,,
PC121,"Q_CAP_0402-0.22UF,16V,10%,X7R,CH4223K1B00",0.22UF,10%,C0402,12223.70,13833.39,270.000,NO,,,
PC122,"Q_CAP_0402-0.22UF,16V,10%,X7R,CH4223K1B00",0.22UF,10%,C0402,12603.61,13371.93,270.000,NO,,,
PC123,"Q_CAP_C0805-22UF,16V,20%,X6S,CH6223MEA01",22UF,20%,C0805_H57,8014.69,13579.80,0.000,NO,,,
PC125,"Q_CAP_C0402-2.2UF,10V,10%,X6S,CH5222KEB01",2.2UF,10%,C0402,2729.55,6545.80,270.000,NO,,,
PC126,"Q_CAP_C0402-1UF,25V,10%,X6S,CH5104KEB02",1UF,10%,C0402,7938.46,13286.62,0.000,NO,,,
PC127,"Q_CAP_0402-0.1UF,25V,10%,X7R,CH4104K1B00",0.1UF,10%,C0402,8058.64,13407.62,0.000,NO,,,
PC128,"Q_CAP_0402-0.1UF,25V,10%,X7R,CH4104K1B00",0.1UF,10%,C0402,8065.00,13285.00,270.000,NO,,,
PC129,"Q_CAP_C0805-22UF,16V,20%,X6S,CH6223MEA01",22UF,20%,C0805_H57,7872.80,13032.59,270.000,YES,,,
PC130,"Q_CAP_C0805-22UF,16V,20%,X6S,CH6223MEA01",22UF,20%,C0805_H57,8032.80,13032.59,270.000,YES,,,
PC131,"Q_CAP_C0402-2.2UF,10V,10%,X6S,CH5222KEB01",2.2UF,10%,C0402,13374.30,13294.87,90.000,NO,,,
PC132,"Q_CAP_0402-100PF,50V,5%,NPO,CH11006JB00",100PF,5%,C0402,8125.26,13467.53,270.000,NO,,,
PC133,"Q_CAP_0402-0.22UF,16V,10%,X7R,CH4223K1B00",0.22UF,10%,C0402,2514.24,6467.59,90.000,NO,,,
PC134,"Q_CAP_C0805-22UF,16V,20%,X6S,CH6223MEA01",22UF,20%,C0805_H57,7952.80,13032.59,270.000,YES,,,
PC135,"Q_CAP_C0805-22UF,16V,20%,X6S,CH6223MEA01",22UF,20%,C0805_H57,7792.80,13032.59,270.000,YES,,,
PC136,"Q_CAP_0402-0.1UF,25V,10%,X7R,CH4104K1B00",0.1UF,10%,C0402,8076.69,13032.16,90.000,NO,,,
PC137,"Q_CAP_0402-0.22UF,16V,10%,X7R,CH4223K1B00",0.22UF,10%,C0402,13589.61,13373.08,270.000,NO,,,
PC138,"Q_CAP_C0402-2.2UF,10V,10%,X6S,CH5222KEB01",2.2UF,10%,C0402,3938.83,13488.37,90.000,NO,,,
PC141,"Q_CAP_C0402-560PF,50V,10%,EMPTY,CH1566K1B09",NA,10%,C0402,4699.98,6886.92,0.000,NO,,,
PC142,"Q_CAP_C0402-2.2UF,10V,10%,X6S,CH5222KEB01",2.2UF,10%,C0402,11351.39,13755.18,90.000,NO,,,
PC143,"Q_CAP_C0402-2.2UF,10V,10%,X6S,CH5222KEB01",2.2UF,10%,C0402,11680.39,13755.18,90.000,NO,,,
PC146,"Q_CAP_0402-0.22UF,16V,10%,X7R,CH4223K1B00",0.22UF,10%,C0402,4154.14,13566.58,270.000,NO,,,
PC148,"Q_CAP_0402-0.1UF,25V,10%,X7R,CH4104K1B00",0.1UF,10%,C0402,11488.83,14365.79,0.000,NO,,,
PC149,"Q_CAP_C0402-560PF,50V,10%,EMPTY,CH1566K1B09",NA,10%,C0402,5025.98,6621.92,0.000,NO,,,
PC150,"Q_CAP_C0805-22UF,16V,20%,X6S,CH6223MEA01",22UF,20%,C0805_H57,2961.39,6023.26,90.000,NO,,,
PC151,"Q_CAP_C0402-2.2UF,10V,10%,X6S,CH5222KEB01",2.2UF,10%,C0402,13835.07,6239.14,270.000,NO,,,
PC152,"Q_CAP_C0805-22UF,16V,20%,X6S,CH6223MEA01",22UF,20%,C0805_H57,3099.39,6023.26,90.000,NO,,,
PC153,"Q_CAP_0402-0.022UF,25V,10%,X7R,CH3224K1B01",0.022UF,10%,C0402,2768.01,5800.78,270.000,NO,,,
PC154,"Q_CAP_C0402-560PF,50V,10%,EMPTY,CH1566K1B09",NA,10%,C0402,13699.69,13264.97,180.000,NO,,,
PC155,"Q_CAP_0402-0.22UF,16V,10%,X7R,CH4223K1B00",0.22UF,10%,C0402,11895.70,13833.39,270.000,NO,,,
PC156,"Q_CAP_0402-0.22UF,16V,10%,X7R,CH4223K1B00",0.22UF,10%,C0402,11566.70,13833.39,270.000,NO,,,
PC157,"Q_CAP_C0402-560PF,50V,10%,EMPTY,CH1566K1B09",NA,10%,C0402,13373.87,13071.66,180.000,NO,,,
PC158,"Q_CAP_C0402-560PF,50V,10%,EMPTY,CH1566K1B09",NA,10%,C0402,11679.96,13531.97,180.000,NO,,,
PC159,"Q_CAP_C0402-560PF,50V,10%,EMPTY,CH1566K1B09",NA,10%,C0402,11350.96,13531.97,180.000,NO,,,
PC160,"Q_CAPP_SMLF-470UF,2.5V,20%,EMPTY,CH747LM8825",470UF,20%,TAJ_SX,10835.32,13380.32,270.000,YES,,,
PC161,"Q_CAP_0402-0.22UF,16V,10%,X7R,CH4223K1B00",0.22UF,10%,C0402,13619.76,6160.93,90.000,NO,,,
PC162,"Q_CAPP_SMLF-470UF,2.5V,20%,SPCAP,CH747LM8825",470UF,20%,TAJ_SX,11807.32,13381.32,270.000,YES,,,
PC163,"Q_CAP_C0402-560PF,50V,10%,EMPTY,CH1566K1B09",NA,10%,C0402,10697.96,13531.97,180.000,NO,,,
PC164,"Q_CAPP_THLF-270UF,16V,20%,OSCON,CC72703MD38",270UF,20%,EC2-5_6-8_9-2,11665.35,14124.79,180.000,NO,,,
PC165,"Q_CAPP_SMLF-470UF,2.5V,20%,SPCAP,CH747LM8825",470UF,20%,TAJ_SX,11196.32,13382.32,270.000,YES,,,
PC166,"Q_CAP_C0402-560PF,50V,10%,EMPTY,CH1566K1B09",NA,10%,C0402,11023.96,13531.97,180.000,NO,,,
PC168,"Q_CAP_C0402-560PF,50V,10%,EMPTY,CH1566K1B09",NA,10%,C0402,16861.29,13706.14,180.000,NO,,,
PC169,"Q_CAP_C0402-560PF,50V,10%,EMPTY,CH1566K1B09",NA,10%,C0402,16533.47,13705.14,180.000,NO,,,
PC170,"Q_CAP_C0402-560PF,50V,10%,EMPTY,CH1566K1B09",NA,10%,C0402,3384.98,7312.92,0.000,NO,,,
PC171,"Q_CAP_C0402-2.2UF,10V,10%,X6S,CH5222KEB01",2.2UF,10%,C0402,10698.39,13755.18,90.000,NO,,,
PC172,"Q_CAP_C0402-2.2UF,10V,10%,X6S,CH5222KEB01",2.2UF,10%,C0402,11024.39,13755.18,90.000,NO,,,
PC173,"Q_CAP_C0402-560PF,50V,10%,EMPTY,CH1566K1B09",NA,10%,C0402,3715.58,7310.24,0.000,NO,,,
PC174,"Q_CAP_C0402-560PF,50V,10%,EMPTY,CH1566K1B09",NA,10%,C0402,1962.58,13532.16,180.000,NO,,,
PC175,"Q_CAP_C0402-560PF,50V,10%,EMPTY,CH1566K1B09",NA,10%,C0402,1633.58,13532.16,180.000,NO,,,
PC176,"Q_CAP_C0402-560PF,50V,10%,EMPTY,CH1566K1B09",NA,10%,C0402,980.58,13532.16,180.000,NO,,,
PC177,"Q_CAP_C0402-560PF,50V,10%,EMPTY,CH1566K1B09",NA,10%,C0402,1306.58,13532.16,180.000,NO,,,
PC178,"Q_CAP_C0402-560PF,50V,10%,EMPTY,CH1566K1B09",NA,10%,C0402,14488.50,7117.15,0.000,NO,,,
PC179,"Q_CAP_C0402-560PF,50V,10%,EMPTY,CH1566K1B09",NA,10%,C0402,14817.68,7312.92,0.000,NO,,,
PC180,"Q_CAP_C0402-560PF,50V,10%,EMPTY,CH1566K1B09",NA,10%,C0402,15148.50,7312.92,0.000,NO,,,
PC181,"Q_CAP_C0402-560PF,50V,10%,EMPTY,CH1566K1B09",NA,10%,C0402,15476.50,7312.92,0.000,NO,,,
PC182,"Q_CAP_C0402-560PF,50V,10%,EMPTY,CH1566K1B09",NA,10%,C0402,13835.50,6462.35,0.000,NO,,,
PC183,"Q_CAP_0402-0.22UF,16V,10%,X7R,CH4223K1B00",0.22UF,10%,C0402,10913.70,13833.39,270.000,NO,,,
PC184,"Q_CAP_C0402-560PF,50V,10%,EMPTY,CH1566K1B09",NA,10%,C0402,14162.50,6791.35,0.000,NO,,,
PC185,"Q_CAP_C0402-560PF,50V,10%,EMPTY,CH1566K1B09",NA,10%,C0402,15807.80,7093.52,0.000,NO,,,
PC186,"Q_CAP_0402-0.22UF,16V,10%,X7R,CH4223K1B00",0.22UF,10%,C0402,11239.70,13833.39,270.000,NO,,,
PC187,"Q_CAP_C0402-560PF,50V,10%,EMPTY,CH1566K1B09",NA,10%,C0402,16135.50,6755.83,0.000,NO,,,
PC188,"Q_CAP_C0402-560PF,50V,10%,EMPTY,CH1566K1B09",NA,10%,C0402,16465.50,6565.83,0.000,NO,,,
PC189,"Q_CAP_C0402-560PF,50V,10%,EMPTY,CH1566K1B09",NA,10%,C0402,13045.87,13069.66,180.000,NO,,,
PC190,"Q_CAP_C0402-560PF,50V,10%,EMPTY,CH1566K1B09",NA,10%,C0402,12716.83,13070.23,180.000,NO,,,
PC191,"Q_CAP_C0402-560PF,50V,10%,EMPTY,CH1566K1B09",NA,10%,C0402,12007.96,13531.97,180.000,NO,,,
PC192,"Q_CAP_C0402-560PF,50V,10%,EMPTY,CH1566K1B09",NA,10%,C0402,12387.87,13070.51,180.000,NO,,,
PC193,"Q_CAP_0402-0.1UF,25V,10%,X7R,CH4104K1B00",0.1UF,10%,C0402,16677.90,14283.45,0.000,NO,,,
PC194,"Q_CAP_0402-3300PF,50V,10%,X7R,TMP_QCH2336K1B12",3300PF,10%,C0402,16394.90,14103.98,0.000,NO,,,
PC195,"Q_CAP_C0402-560PF,50V,10%,EMPTY,CH1566K1B09",NA,10%,C0402,5358.98,6280.92,0.000,NO,,,
PC198,"Q_CAP_0402-470PF,50V,10%,X7R,TMP_QCH14706KB18",470PF,10%,C0402,16678.24,14244.83,0.000,NO,,,
PC199,"Q_CAP_C0402-10UF,6.3V,20%,X6S,CH6101MEB03",10UF,20%,C0402,16581.67,14417.41,90.000,NO,,,
PC200,"Q_CAP_C0402-1UF,16V,10%,X6S,CH5103KEB01",1UF,10%,C0402,16624.65,14401.74,90.000,NO,,,
PC201,"Q_CAP_C0402-560PF,50V,10%,EMPTY,CH1566K1B09",NA,10%,C0402,3284.58,13069.85,180.000,NO,,,
PC202,"Q_CAP_C0402-560PF,50V,10%,EMPTY,CH1566K1B09",NA,10%,C0402,2955.54,13070.42,180.000,NO,,,
PC203,"Q_CAP_C0402-2.2UF,10V,10%,X6S,CH5222KEB01",2.2UF,10%,C0402,16533.90,13928.35,90.000,NO,,,
PC204,"Q_CAP_C0402-2.2UF,10V,10%,X6S,CH5222KEB01",2.2UF,10%,C0402,16861.72,13929.35,90.000,NO,,,
PC205,"Q_CAP_C0402-560PF,50V,10%,EMPTY,CH1566K1B09",NA,10%,C0402,2290.58,13532.16,180.000,NO,,,
PC206,"Q_CAP_C0402-560PF,50V,10%,EMPTY,CH1566K1B09",NA,10%,C0402,2626.58,13070.70,180.000,NO,,,
PC207,"Q_CAP_C0402-560PF,50V,10%,EMPTY,CH1566K1B09",NA,10%,C0402,3612.58,13071.85,180.000,NO,,,
PC208,"Q_CAP_C0402-560PF,50V,10%,EMPTY,CH1566K1B09",NA,10%,C0402,3938.40,13265.16,180.000,NO,,,
PC209,"Q_CAP_0402-0.22UF,16V,10%,X7R,CH4223K1B00",0.22UF,10%,C0402,13051.87,5672.71,90.000,NO,,,
PC212,"Q_CAP_C0402-1UF,25V,10%,X6S,CH5104KEB02",1UF,10%,C0402,13323.60,5601.95,270.000,NO,,,
PC215,"Q_CAP_0402-0.1UF,25V,10%,X7R,CH4104K1B00",0.1UF,10%,C0402,12988.86,5950.55,270.000,NO,,,
PC217,"Q_CAP_0402-0.22UF,16V,10%,X7R,CH4223K1B00",0.22UF,10%,C0402,16749.21,14004.66,270.000,NO,,,
PC218,"Q_CAP_0402-0.22UF,16V,10%,X7R,CH4223K1B00",0.22UF,10%,C0402,17077.03,14005.66,270.000,NO,,,
PC220,"Q_CAPP_THLF-270UF,16V,20%,OSCON,CC72703MD38",270UF,20%,EC2-5_6-8_9-2,17008.40,14245.19,180.000,NO,,,
PC222,"Q_CAP_0402-0.1UF,25V,10%,X7R,CH4104K1B00",0.1UF,10%,C0402,16418.04,13095.61,270.000,NO,,,
PC223,"Q_CAPP_SMLF-470UF,2.5V,20%,SPCAP,CH747LM8825",470UF,20%,TAJ_SX,16679.87,13541.78,270.000,YES,,,
PC226,"Q_CAPP_SMLF-470UF,2.5V,20%,SPCAP,CH747LM8825",470UF,20%,TAJ_SX,17004.67,13543.58,270.000,YES,,,
PC227,"Q_CAP_C0805-22UF,16V,20%,X6S,CH6223MEA01",22UF,20%,C0805_H57,13235.14,5403.75,0.000,NO,,,
PC228,"Q_CAPP_SMLF-390UF,2.5V,20%,ALUM,CC7390JMZ13",390UF,20%,EC56_197_229SXA,16558.72,13095.90,270.000,NO,,,
PC229,"Q_CAPP_SMLF-390UF,2.5V,20%,ALUM,CC7390JMZ13",390UF,20%,EC56_197_229SXA,17038.72,13095.90,270.000,NO,,,
PC230,"Q_CAPP_SMLF-390UF,2.5V,20%,ALUM,CC7390JMZ13",390UF,20%,EC56_197_229SXA,16798.72,13095.90,270.000,NO,,,
PC237,"Q_CAP_C0402-1UF,25V,10%,X6S,CH5104KEB02",1UF,10%,C0402,13178.41,5671.48,180.000,NO,,,
PC243,"Q_CAP_0402-0.1UF,25V,10%,X7R,CH4104K1B00",0.1UF,10%,C0402,3991.57,5614.15,180.000,YES,,,
PC244,"Q_CAP_0402-3300PF,50V,10%,X7R,TMP_QCH2336K1B12",3300PF,10%,C0402,3635.83,5904.79,180.000,YES,,,
PC245,"Q_CAP_0402-3300PF,50V,10%,X7R,TMP_QCH2336K1B12",3300PF,10%,C0402,3976.57,5789.15,270.000,YES,,,
PC247,"Q_CAP_0402-1UF,6.3V,10%,X7R,CH5101K1B01",1UF,10%,C0402,3551.57,5704.15,0.000,YES,,,
PC250,"Q_CAP_0402-470PF,50V,10%,X7R,TMP_QCH14706KB18",470PF,10%,C0402,3991.57,5654.15,180.000,YES,,,
PC251,"Q_CAP_C0402-10UF,6.3V,20%,X6S,CH6101MEB03",10UF,20%,C0402,3916.57,5509.15,90.000,YES,,,
PC252,"Q_CAP_C0402-1UF,16V,10%,X6S,CH5103KEB01",1UF,10%,C0402,3996.57,5509.15,90.000,YES,,,
PC253,"Q_CAP_0402-470PF,50V,10%,X7R,TMP_QCH14706KB18",470PF,10%,C0402,3991.57,5694.15,180.000,YES,,,
PC254,"Q_CAP_C0805-22UF,16V,20%,X6S,CH6223MEA01",22UF,20%,C0805_H57,13102.66,5321.13,180.000,NO,,,
PC255,"Q_CAP_C0402-560PF,50V,10%,EMPTY,CH1566K1B09",NA,10%,C0402,7383.96,13713.25,180.000,NO,,,
PC256,"Q_CAP_C0402-2.2UF,10V,10%,X6S,CH5222KEB01",2.2UF,10%,C0402,3384.55,7089.71,270.000,NO,,,
PC257,"Q_CAP_C0402-2.2UF,10V,10%,X6S,CH5222KEB01",2.2UF,10%,C0402,3715.15,7087.03,270.000,NO,,,
PC258,"Q_CAP_0402-0.022UF,25V,10%,X7R,CH3224K1B01",0.022UF,10%,C0402,13022.66,5528.13,180.000,NO,,,
PC259,"Q_CAP_0402-220PF,50V,10%,X7R,TMP_QCH12206KB14",220PF,10%,C0402,12963.86,5468.23,90.000,NO,,,
PC260,"Q_CAP_C0805-22UF,4V,20%,EMPTY,CH622KMEA03",NA,20%,C0805_H61,13213.34,5947.61,90.000,YES,,,
PC261,"Q_CAP_C0805-22UF,4V,20%,EMPTY,CH622KMEA03",NA,20%,C0805_H61,13239.36,6073.09,180.000,YES,,,
PC270,"Q_CAP_0402-0.22UF,16V,10%,X7R,CH4223K1B00",0.22UF,10%,C0402,3169.24,7011.50,90.000,NO,,,
PC271,"Q_CAP_0402-0.22UF,16V,10%,X7R,CH4223K1B00",0.22UF,10%,C0402,3499.84,7008.82,90.000,NO,,,
PC272,"Q_CAPP_THLF-270UF,16V,20%,OSCON,CC72703MD38",270UF,20%,EC2-5_6-8_9-2,3267.31,6533.94,180.000,NO,,,
PC273,"Q_CAPP_THLF-270UF,16V,20%,OSCON,CC72703MD38",270UF,20%,EC2-5_6-8_9-2,3637.31,6533.94,180.000,NO,,,
PC275,"Q_CAPP_SMLF-220UF,4V,20%,SPCAP,CH122KM8801",220UF,20%,TAJ_SX,3871.51,7458.78,90.000,YES,,,
PC276,"Q_CAPP_SMLF-220UF,4V,20%,SPCAP,CH122KM8801",220UF,20%,TAJ_SX,3566.57,7459.12,90.000,YES,,,
PC277,"Q_CAPP_SMLF-220UF,4V,20%,SPCAP,CH122KM8801",220UF,20%,TAJ_SX,3269.51,7459.12,90.000,YES,,,
PC278,"Q_CAP_0402-0.1UF,25V,10%,X7R,CH4104K1B00",0.1UF,10%,C0402,2398.43,7137.48,270.000,NO,,,
PC279,"Q_CAPP_SMLF-220UF,4V,20%,SPCAP,CH122KM8801",220UF,20%,TAJ_SX,2883.81,7257.62,90.000,YES,,,
PC285,"Q_CAP_C0805-22UF,4V,20%,X6S,CH622KMEA03",22UF,20%,C0805_H61,13132.34,5947.61,90.000,YES,,,
PC286,"Q_CAP_C0402-2.2UF,10V,10%,X6S,CH5222KEB01",2.2UF,10%,C0402,4045.55,7087.71,270.000,NO,,,
PC287,"Q_CAP_C0402-2.2UF,10V,10%,X6S,CH5222KEB01",2.2UF,10%,C0402,4375.55,6909.71,270.000,NO,,,
PC288,"Q_CAP_C0805-22UF,4V,20%,X6S,CH622KMEA03",22UF,20%,C0805_H61,13293.76,5947.43,90.000,YES,,,
PC300,"Q_CAP_0402-0.22UF,16V,10%,X7R,CH4223K1B00",0.22UF,10%,C0402,3830.24,7009.50,90.000,NO,,,
PC301,"Q_CAP_0402-0.22UF,16V,10%,X7R,CH4223K1B00",0.22UF,10%,C0402,4160.24,6831.50,90.000,NO,,,
PC307,"Q_CAP_C0402-2.2UF,10V,10%,X6S,CH5222KEB01",2.2UF,10%,C0402,3056.85,6888.21,270.000,NO,,,
PC314,"Q_CAP_0402-0.22UF,16V,10%,X7R,CH4223K1B00",0.22UF,10%,C0402,2841.54,6810.00,90.000,NO,,,
PC315,"Q_CAP_C0402-560PF,50V,10%,EMPTY,CH1566K1B09",NA,10%,C0402,7056.14,13712.25,180.000,NO,,,
PC316,"Q_CAP_C0402-560PF,50V,10%,EMPTY,CH1566K1B09",NA,10%,C0402,4045.98,7310.92,0.000,NO,,,
PC317,"Q_CAP_C0402-560PF,50V,10%,EMPTY,CH1566K1B09",NA,10%,C0402,4375.98,7132.92,0.000,NO,,,
PC318,"Q_CAP_C0402-560PF,50V,10%,EMPTY,CH1566K1B09",NA,10%,C0402,3057.28,7111.42,0.000,NO,,,
PC319,"Q_CAP_C0402-2.2UF,10V,10%,X6S,CH5222KEB01",2.2UF,10%,C0402,4699.55,6663.71,270.000,NO,,,
PC320,"Q_CAP_C0402-2.2UF,10V,10%,X6S,CH5222KEB01",2.2UF,10%,C0402,5025.55,6398.71,270.000,NO,,,
PC321,"Q_CAP_C0402-560PF,50V,10%,EMPTY,CH1566K1B09",NA,10%,C0402,2729.98,6769.01,0.000,NO,,,
PC333,"Q_CAP_0402-0.22UF,16V,10%,X7R,CH4223K1B00",0.22UF,10%,C0402,4484.24,6585.50,90.000,NO,,,
PC334,"Q_CAP_0402-0.22UF,16V,10%,X7R,CH4223K1B00",0.22UF,10%,C0402,4810.24,6320.50,90.000,NO,,,
PC336,"Q_CAPP_THLF-270UF,16V,20%,OSCON,CC72703MD38",270UF,20%,EC2-5_6-8_9-2,4336.24,5942.59,90.000,NO,,,
PC337,"Q_CAPP_SMLF-470UF,2.5V,20%,SPCAP,CH747LM8825",470UF,20%,TAJ_SX,4847.51,6768.12,90.000,YES,,,
PC338,"Q_CAP_0402-0.1UF,25V,10%,X7R,CH4104K1B00",0.1UF,10%,C0402,5401.06,6613.00,270.000,NO,,,
PC340,"Q_CAPP_SMLF-470UF,2.5V,20%,EMPTY,CH747LM8825",470UF,20%,TAJ_SX,5046.11,6768.92,90.000,YES,,,
PC343,"Q_CAPP_SMLF-470UF,2.5V,20%,SPCAP,CH747LM8825",470UF,20%,TAJ_SX,4571.51,7033.78,90.000,YES,,,
PC346,"Q_CAP_C0402-2.2UF,10V,10%,X6S,CH5222KEB01",2.2UF,10%,C0402,5358.55,6057.71,270.000,NO,,,
PC353,"Q_CAP_0402-0.22UF,16V,10%,X7R,CH4223K1B00",0.22UF,10%,C0402,5143.24,5979.50,90.000,NO,,,
PC357,"Q_CAP_0402-0.1UF,25V,10%,X7R,CH4104K1B00",0.1UF,10%,C0402,1465.00,14375.00,0.000,NO,,,
PC358,"Q_CAP_0402-3300PF,50V,10%,X7R,TMP_QCH2336K1B12",3300PF,10%,C0402,1085.00,14145.00,0.000,NO,,,
PC361,"Q_CAP_0402-3300PF,50V,10%,X7R,TMP_QCH2336K1B12",3300PF,10%,C0402,1425.00,14175.00,180.000,NO,,,
PC363,"Q_CAP_0402-1UF,6.3V,10%,X7R,CH5101K1B01",1UF,10%,C0402,975.00,14305.00,180.000,NO,,,
PC364,"Q_CAP_0402-0.1UF,25V,10%,X7R,CH4104K1B00",0.1UF,10%,C0402,1435.00,14440.00,270.000,NO,,,
PC365,"Q_CAP_C0402-1UF,16V,10%,X6S,CH5103KEB01",1UF,10%,C0402,1450.28,14506.12,90.000,NO,,,
PC366,"Q_CAP_C0402-10UF,6.3V,20%,X6S,CH6101MEB03",10UF,20%,C0402,1371.20,14506.58,90.000,NO,,,
PC367,"Q_CAP_0402-470PF,50V,10%,X7R,TMP_QCH14706KB18",470PF,10%,C0402,1465.00,14295.00,0.000,NO,,,
PC368,"Q_CAP_0402-470PF,50V,10%,X7R,TMP_QCH14706KB18",470PF,10%,C0402,1465.00,14335.00,0.000,NO,,,
PC369,"Q_CAP_C0402-2.2UF,10V,10%,X6S,CH5222KEB01",2.2UF,10%,C0402,3285.01,13293.06,90.000,NO,,,
PC370,"Q_CAP_C0402-2.2UF,10V,10%,X6S,CH5222KEB01",2.2UF,10%,C0402,2955.97,13293.63,90.000,NO,,,
PC375,"Q_CAP_0402-0.1UF,25V,10%,X7R,CH4104K1B00",0.1UF,10%,C0402,3727.62,13876.97,0.000,NO,,,
PC383,"Q_CAP_0402-0.22UF,16V,10%,X7R,CH4223K1B00",0.22UF,10%,C0402,3500.32,13371.27,270.000,NO,,,
PC384,"Q_CAP_0402-3300PF,50V,10%,X7R,TMP_QCH2336K1B12",3300PF,10%,C0402,5688.00,2974.69,180.000,NO,,,
PC386,"Q_CAP_0402-0.22UF,16V,10%,X7R,CH4223K1B00",0.22UF,10%,C0402,3171.28,13371.84,270.000,NO,,,
PC387,"Q_CAPP_SMLF-220UF,4V,20%,SPCAP,CH122KM8801",220UF,20%,TAJ_SX,2775.61,12923.05,270.000,YES,,,
PC388,"Q_CAPP_SMLF-220UF,4V,20%,SPCAP,CH122KM8801",220UF,20%,TAJ_SX,3069.83,12923.05,270.000,YES,,,
PC389,"Q_CAPP_SMLF-220UF,4V,20%,SPCAP,CH122KM8801",220UF,20%,TAJ_SX,3759.76,12921.95,270.000,YES,,,
PC390,"Q_CAPP_SMLF-270UF,16V,20%,OSCON,CC72703MZ11",270UF,20%,EC75_248_304S,3289.94,13872.80,90.000,NO,,,
PC391,"Q_CAPP_SMLF-220UF,4V,20%,SPCAP,CH122KM8801",220UF,20%,TAJ_SX,3415.76,12922.20,270.000,YES,,,
PC392,"Q_CAP_0402-0.1UF,25V,10%,X7R,CH4104K1B00",0.1UF,10%,C0402,4272.51,12876.94,90.000,NO,,,
PC393,"Q_CAPP_SMLF-270UF,16V,20%,OSCON,CC72703MZ11",270UF,20%,EC75_248_304S,3000.44,13976.71,90.000,NO,,,
PC399,"Q_CAP_C0402-2.2UF,10V,10%,X6S,CH5222KEB01",2.2UF,10%,C0402,2291.01,13755.37,90.000,NO,,,
PC400,"Q_CAP_C0402-2.2UF,10V,10%,X6S,CH5222KEB01",2.2UF,10%,C0402,2627.01,13293.91,90.000,NO,,,
PC413,"Q_CAP_0402-0.22UF,16V,10%,X7R,CH4223K1B00",0.22UF,10%,C0402,2506.32,13833.58,270.000,NO,,,
PC414,"Q_CAP_0402-0.22UF,16V,10%,X7R,CH4223K1B00",0.22UF,10%,C0402,2842.32,13372.12,270.000,NO,,,
PC421,"Q_CAP_C0402-2.2UF,10V,10%,X6S,CH5222KEB01",2.2UF,10%,C0402,3613.01,13295.06,90.000,NO,,,
PC428,"Q_CAP_0402-0.22UF,16V,10%,X7R,CH4223K1B00",0.22UF,10%,C0402,3828.32,13373.27,270.000,NO,,,
PC432,"Q_CAP_C0402-2.2UF,10V,10%,X6S,CH5222KEB01",2.2UF,10%,C0402,1634.01,13755.37,90.000,NO,,,
PC433,"Q_CAP_C0402-2.2UF,10V,10%,X6S,CH5222KEB01",2.2UF,10%,C0402,1963.01,13755.37,90.000,NO,,,
PC438,"Q_CAP_0402-0.1UF,25V,10%,X7R,CH4104K1B00",0.1UF,10%,C0402,2120.73,14191.87,0.000,NO,,,
PC445,"Q_CAP_0402-0.22UF,16V,10%,X7R,CH4223K1B00",0.22UF,10%,C0402,1849.32,13833.58,270.000,NO,,,
PC447,"Q_CAP_0402-0.22UF,16V,10%,X7R,CH4223K1B00",0.22UF,10%,C0402,2178.32,13833.58,270.000,NO,,,
PC450,"Q_CAPP_SMLF-470UF,2.5V,20%,SPCAP,CH747LM8825",470UF,20%,TAJ_SX,2089.94,13381.51,270.000,YES,,,
PC451,"Q_CAP_C0402-100NF,50V,10%,X7R,CH4106K1B01",100NF,10%,C0402,941.58,13096.01,90.000,NO,,,
PC452,"Q_CAPP_SMLF-470UF,2.5V,20%,SPCAP,CH747LM8825",470UF,20%,TAJ_SX,1478.94,13382.51,270.000,YES,,,
PC454,"Q_CAPP_SMLF-270UF,16V,20%,OSCON,CC72703MZ11",270UF,20%,EC75_248_304S,1680.71,14220.98,90.000,NO,,,
PC455,"Q_CAPP_SMLF-470UF,2.5V,20%,EMPTY,CH747LM8825",470UF,20%,TAJ_SX,1117.94,13380.51,270.000,YES,,,
PC462,"Q_CAP_0402-0.1UF,25V,10%,X7R,CH4104K1B00",0.1UF,10%,C0402,15122.57,5519.77,180.000,YES,,,
PC463,"Q_CAP_0402-3300PF,50V,10%,X7R,TMP_QCH2336K1B12",3300PF,10%,C0402,14776.83,5816.58,180.000,YES,,,
PC464,"Q_CAP_0402-3300PF,50V,10%,X7R,TMP_QCH2336K1B12",3300PF,10%,C0402,15107.57,5694.77,270.000,YES,,,
PC466,"Q_CAP_0402-1UF,6.3V,10%,X7R,CH5101K1B01",1UF,10%,C0402,14682.57,5609.77,0.000,YES,,,
PC469,"Q_CAP_0402-470PF,50V,10%,X7R,TMP_QCH14706KB18",470PF,10%,C0402,15122.57,5559.77,180.000,YES,,,
PC470,"Q_CAP_C0402-10UF,6.3V,20%,X6S,CH6101MEB03",10UF,20%,C0402,15047.57,5414.77,90.000,YES,,,
PC471,"Q_CAP_C0402-1UF,16V,10%,X6S,CH5103KEB01",1UF,10%,C0402,15127.57,5414.77,90.000,YES,,,
PC472,"Q_CAP_0402-470PF,50V,10%,X7R,TMP_QCH14706KB18",470PF,10%,C0402,15122.57,5599.77,180.000,YES,,,
PC473,"Q_CAPP_SMLF-100UF,16V,20%,OSCON,CC71003MZ30",100UF,20%,EC56_197_229SXA,1249.07,15803.08,0.000,NO,,,
PC475,"Q_CAP_C0402-2.2UF,10V,10%,X6S,CH5222KEB01",2.2UF,10%,C0402,14488.07,6893.94,270.000,NO,,,
PC476,"Q_CAP_C0402-2.2UF,10V,10%,X6S,CH5222KEB01",2.2UF,10%,C0402,14817.25,7089.71,270.000,NO,,,
PC479,"Q_CAP_0402-0.1UF,25V,10%,X7R,CH4104K1B00",0.1UF,10%,C0402,14417.41,5978.66,270.000,NO,,,
PC489,"Q_CAP_0402-0.22UF,16V,10%,X7R,CH4223K1B00",0.22UF,10%,C0402,14272.76,6815.73,90.000,NO,,,
PC490,"Q_CAP_0402-0.22UF,16V,10%,X7R,CH4223K1B00",0.22UF,10%,C0402,14601.94,7011.50,90.000,NO,,,
PC491,"Q_CAPP_THLF-270UF,16V,20%,OSCON,CC72703MD38",270UF,20%,EC2-5_6-8_9-2,14876.77,6401.45,180.000,NO,,,
PC492,"Q_CAPP_THLF-270UF,16V,20%,OSCON,CC72703MD38",270UF,20%,EC2-5_6-8_9-2,14156.90,6012.30,90.000,NO,,,
PC494,"Q_CAPP_SMLF-220UF,4V,20%,SPCAP,CH122KM8801",220UF,20%,TAJ_SX,14372.61,7263.35,90.000,YES,,,
PC495,"Q_CAPP_SMLF-220UF,4V,20%,SPCAP,CH122KM8801",220UF,20%,TAJ_SX,14012.89,6938.76,90.000,YES,,,
PC496,"Q_CAPP_SMLF-220UF,4V,20%,SPCAP,CH122KM8801",220UF,20%,TAJ_SX,15310.30,7459.25,90.000,YES,,,
PC497,"Q_CAP_0402-0.1UF,25V,10%,X7R,CH4104K1B00",0.1UF,10%,C0402,13507.72,6761.68,270.000,NO,,,
PC498,"Q_CAPP_SMLF-220UF,4V,20%,SPCAP,CH122KM8801",220UF,20%,TAJ_SX,14677.89,7460.80,90.000,YES,,,
PC505,"Q_CAP_C0402-2.2UF,10V,10%,X6S,CH5222KEB01",2.2UF,10%,C0402,7056.57,13935.46,90.000,NO,,,
PC506,"Q_CAP_C0402-2.2UF,10V,10%,X6S,CH5222KEB01",2.2UF,10%,C0402,7384.39,13936.46,90.000,NO,,,
PC511,"Q_CAP_0402-0.1UF,25V,10%,X7R,CH4104K1B00",0.1UF,10%,C0402,7102.17,14372.38,90.000,NO,,,
PC514,"Q_CAP_0402-0.1UF,25V,10%,EMPTY,CH4104K1B00",NA,10%,C0402,396.33,16128.96,180.000,NO,,,
PC519,"Q_CAP_0402-0.22UF,16V,10%,X7R,CH4223K1B00",0.22UF,10%,C0402,7271.88,14011.77,270.000,NO,,,
PC520,"Q_CAP_0402-0.22UF,16V,10%,X7R,CH4223K1B00",0.22UF,10%,C0402,7599.70,14012.77,270.000,NO,,,
PC522,"Q_CAPP_THLF-270UF,16V,20%,OSCON,CC72703MD38",270UF,20%,EC2-5_6-8_9-2,7546.45,14268.92,180.000,NO,,,
PC523,"Q_CAP_0402-470PF,50V,10%,X7R,TMP_QCH14706KB18",470PF,10%,C0402,396.33,16173.96,180.000,NO,,,
PC524,"Q_CAP_C0402-100NF,50V,10%,X7R,CH4106K1B01",100NF,10%,C0402,6780.71,13101.89,270.000,NO,,,
PC525,"Q_CAPP_SMLF-470UF,2.5V,20%,SPCAP,CH747LM8825",470UF,20%,TAJ_SX,7202.71,13551.18,270.000,YES,,,
PC528,"Q_CAPP_SMLF-470UF,2.5V,20%,SPCAP,CH747LM8825",470UF,20%,TAJ_SX,7527.41,13550.28,270.000,YES,,,
PC530,"Q_CAPP_SMLF-390UF,2.5V,20%,ALUM,CC7390JMZ13",390UF,20%,EC56_197_229SXA,7646.39,13100.18,270.000,NO,,,
PC531,"Q_CAPP_SMLF-390UF,2.5V,20%,ALUM,CC7390JMZ13",390UF,20%,EC56_197_229SXA,7166.39,13100.18,270.000,NO,,,
PC532,"Q_CAPP_SMLF-390UF,2.5V,20%,ALUM,CC7390JMZ13",390UF,20%,EC56_197_229SXA,7406.39,13100.18,270.000,NO,,,
PC534,"Q_CAPP_SMLF-470UF,2.5V,20%,SPCAP,CH747LM8818",470UF,20%,TAJ_DXC,18193.88,14961.71,90.000,YES,,,
PC546,"Q_CAP_C0402-2.2UF,10V,10%,X6S,CH5222KEB01",2.2UF,10%,C0402,15148.07,7089.71,270.000,NO,,,
PC547,"Q_CAP_C0402-2.2UF,10V,10%,X6S,CH5222KEB01",2.2UF,10%,C0402,15476.07,7089.71,270.000,NO,,,
PC560,"Q_CAP_0402-0.22UF,16V,10%,X7R,CH4223K1B00",0.22UF,10%,C0402,14932.76,7011.50,90.000,NO,,,
PC561,"Q_CAP_0402-0.22UF,16V,10%,X7R,CH4223K1B00",0.22UF,10%,C0402,15260.76,7011.50,90.000,NO,,,
PC566,"Q_CAPP_THLF-270UF,16V,20%,OSCON,CC72703MD38",270UF,20%,EC2-5_6-8_9-2,17316.60,1986.12,180.000,NO,,,
PC567,"Q_CAP_C0402-2.2UF,10V,10%,X6S,CH5222KEB01",2.2UF,10%,C0402,14162.07,6568.14,270.000,NO,,,
PC568,"Q_CAP_C0402-0.22UF,25V,10%,X7R,CH4224K1B01",0.22UF,10%,C0402,17801.31,1978.99,180.000,NO,,,
PC569,"Q_CAP_0402-10PF,50V,1%,NPO,TMP_QCH0106F0B00",10PF,1%,C0402,17934.44,1821.44,270.000,NO,,,
PC570,"Q_CAP_C0805-22UF,16V,20%,X6S,CH6223MEA01",22UF,20%,C0805_H57,17778.48,2080.65,90.000,NO,,,
PC571,"Q_CAP_C0805-22UF,16V,20%,X6S,CH6223MEA01",22UF,20%,C0805_H57,17708.24,2080.59,270.000,YES,,,
PC574,"Q_CAP_0402-0.22UF,16V,10%,X7R,CH4223K1B00",0.22UF,10%,C0402,13946.76,6489.93,90.000,NO,,,
PC576,"Q_CAP_C0805-22UF,16V,20%,X6S,CH6223MEA01",22UF,20%,C0805_H57,17648.48,1870.33,270.000,NO,,,
PC577,"Q_CAP_0402-0.1UF,25V,10%,X7R,CH4104K1B00",0.1UF,10%,C0402,17834.48,2089.57,90.000,NO,,,
PC579,"Q_CAP_C0402-2.2UF,10V,10%,X6S,CH5222KEB01",2.2UF,10%,C0402,15807.37,6870.31,270.000,NO,,,
PC580,"Q_CAP_C0402-2.2UF,10V,10%,X6S,CH5222KEB01",2.2UF,10%,C0402,16135.07,6532.62,270.000,NO,,,
PC581,"Q_CAP_C0603-4.7UF,16V,10%,X6S,CH5473KE902",4.7UF,10%,C0603_H40,18118.27,2054.98,90.000,NO,,,
PC583,"Q_CAP_0402-0.1UF,25V,10%,X7R,CH4104K1B00",0.1UF,10%,C0402,14915.60,5960.37,270.000,NO,,,
PC591,"Q_CAP_C0603-2.2UF,16V,10%,X6S,CH5223KE901",2.2UF,10%,C0603,18176.74,1946.99,270.000,NO,,,
PC593,"Q_CAP_0402-0.22UF,16V,10%,X7R,CH4223K1B00",0.22UF,10%,C0402,15592.06,6792.10,90.000,NO,,,
PC594,"Q_CAP_0402-0.22UF,16V,10%,X7R,CH4223K1B00",0.22UF,10%,C0402,15919.76,6454.41,90.000,NO,,,
PC596,"Q_CAPP_THLF-270UF,16V,20%,OSCON,CC72703MD38",270UF,20%,EC2-5_6-8_9-2,15244.37,6403.65,180.000,NO,,,
PC597,"Q_CAPP_SMLF-470UF,2.5V,20%,EMPTY,CH747LM8825",470UF,20%,TAJ_SX,16361.01,6712.20,90.000,YES,,,
PC598,"Q_CAPP_SMLF-470UF,2.5V,20%,SPCAP,CH747LM8825",470UF,20%,TAJ_SX,16010.51,6903.50,90.000,YES,,,
PC599,"Q_CAP_0402-0.1UF,25V,10%,X7R,CH4104K1B00",0.1UF,10%,C0402,16519.59,6942.47,270.000,NO,,,
PC601,"Q_CAPP_SMLF-470UF,2.5V,20%,SPCAP,CH747LM8825",470UF,20%,TAJ_SX,15664.41,7239.72,90.000,YES,,,
PC606,"Q_CAP_C0402-2.2UF,10V,10%,X6S,CH5222KEB01",2.2UF,10%,C0402,16465.07,6342.62,270.000,NO,,,
PC612,"Q_CAP_0402-0.22UF,16V,10%,X7R,CH4223K1B00",0.22UF,10%,C0402,16249.76,6264.41,90.000,NO,,,
PC616,"Q_CAP_C0402-2.2UF,10V,10%,X6S,CH5222KEB01",2.2UF,10%,C0402,981.01,13755.37,90.000,NO,,,
PC617,"Q_CAP_C0402-2.2UF,10V,10%,X6S,CH5222KEB01",2.2UF,10%,C0402,1307.01,13755.37,90.000,NO,,,
PC630,"Q_CAP_0402-0.22UF,16V,10%,X7R,CH4223K1B00",0.22UF,10%,C0402,1196.32,13833.58,270.000,NO,,,
PC631,"Q_CAP_0402-0.22UF,16V,10%,X7R,CH4223K1B00",0.22UF,10%,C0402,1522.32,13833.58,270.000,NO,,,
PC638,"Q_CAP_0402-0.1UF,25V,10%,X7R,CH4104K1B00",0.1UF,10%,C0402,6572.02,13750.61,0.000,NO,,,
PC639,"Q_CAP_0402-3300PF,50V,10%,X7R,TMP_QCH2336K1B12",3300PF,10%,C0402,6289.02,13571.14,0.000,NO,,,
PC641,"Q_CAP_C0402-0.22UF,25V,10%,X7R,CH4224K1B01",0.22UF,10%,C0402,5755.38,3092.03,90.000,NO,,,
PC643,"Q_CAP_0402-470PF,50V,10%,X7R,TMP_QCH14706KB18",470PF,10%,C0402,6572.36,13711.99,0.000,NO,,,
PC644,"Q_CAP_C0402-10UF,6.3V,20%,X6S,CH6101MEB03",10UF,20%,C0402,6474.45,13884.21,90.000,NO,,,
PC645,"Q_CAP_C0402-1UF,16V,10%,X6S,CH5103KEB01",1UF,10%,C0402,6595.59,13868.65,90.000,NO,,,
PC800,"Q_CAPP_SMLF-470UF,2.5V,20%,SPCAP,CH747LM8825",470UF,20%,TAJ_SX,17279.67,13529.78,270.000,YES,,,
PC801,"Q_CAPP_SMLF-390UF,2.5V,20%,ALUM,CC7390JMZ13",390UF,20%,EC56_197_229SXA,17276.67,13095.90,270.000,NO,,,
PC802,"Q_CAPP_SMLF-470UF,2.5V,20%,SPCAP,CH747LM8825",470UF,20%,TAJ_SX,6922.71,13534.88,270.000,YES,,,
PC803,"Q_CAPP_SMLF-390UF,2.5V,20%,ALUM,CC7390JMZ13",390UF,20%,EC56_197_229SXA,6927.61,13099.78,270.000,NO,,,
PC819,"Q_CAP_0402-0.1UF,25V,10%,X7R,CH4104K1B00",0.1UF,10%,C0402,396.33,16078.96,180.000,NO,,,
PC850,"Q_CAP_C0805-22UF,4V,20%,X6S,CH622KMEA03",22UF,20%,C0805_H61,5992.23,3020.60,0.000,YES,,,
PC852,"Q_CAP_0402-330PF,50V,10%,X7R,CH1336K1B02",330PF,10%,C0402,4749.28,2847.38,0.000,NO,,,
PC865,"Q_CAP_C0805-22UF,4V,20%,X6S,CH622KMEA03",22UF,20%,C0805_H61,5992.23,3101.15,0.000,YES,,,
PC866,"Q_CAP_C0805-22UF,4V,20%,X6S,CH622KMEA03",22UF,20%,C0805_H61,5992.23,2940.10,0.000,YES,,,
PC867,"Q_CAP_C0805-22UF,4V,20%,X6S,CH622KMEA03",22UF,20%,C0805_H61,5992.23,3181.70,0.000,YES,,,
PC1320,"Q_CAP_C0603-2.2UF,16V,20%,X7R,CH5223M1900",2.2UF,20%,C0603_H40,2543.87,976.33,180.000,NO,,,
PC1321,"Q_CAP_0402-0.068UF,16V,10%,X7R,CH3683K1B09",0.068UF,10%,C0402,3825.88,2943.70,0.000,NO,,,
PC1322,"Q_CAP_0402-100PF,50V,5%,X7R,CH11006JB18",100PF,5%,C0402,3825.88,2803.70,0.000,NO,,,
PC1525,"Q_CAP_C0402-1UF,25V,10%,X6S,CH5104KEB02",1UF,10%,C0402,7704.50,15825.33,90.000,NO,,,
PC1599,"Q_CAP_C0805-22UF,10V,20%,X6S,CH6222MEA01",22UF,20%,C0805_H61,17917.76,2589.33,90.000,YES,,,
PC1600,"Q_CAP_C0805-22UF,10V,20%,X6S,CH6222MEA01",22UF,20%,C0805_H61,17997.96,2589.33,90.000,YES,,,
PC1648,"Q_CAP_C0402-0.1UF,25V,10%,X6S,CH4104KEB00",0.1UF,10%,C0402,16173.09,5307.39,0.000,NO,,,
PC1649,"Q_CAP_C0402-0.1UF,25V,10%,X6S,CH4104KEB00",0.1UF,10%,C0402,17303.64,1729.51,90.000,NO,,,
PC1750,"Q_CAP_C0402-33NF,25V,10%,EMPTY,CH3334K1B00",NA,10%,C0402,9555.23,15057.77,180.000,YES,,,
PC1751,"Q_CAP_0402-1NF,50V,10%,EMPTY,CH21006KB16",NA,10%,C0402,9610.23,15076.23,90.000,YES,,,
PC1789,"Q_CAP_0402-0.1UF,25V,10%,X7R,CH4104K1B00",0.1UF,10%,C0402,7892.77,15258.29,90.000,NO,,,
PC1845,"Q_CAPP_SMLF-220UF,6.3V,20%,ALUM,CC72201MZ28",220UF,20%,EC56_197_229SXA,16643.55,6047.03,0.000,NO,,,
PC1846,"Q_CAP_C0402-1UF,16V,10%,X6S,CH5103KEB01",1UF,10%,C0402,16239.66,5668.03,180.000,NO,,,
PC1847,"Q_CAP_C0402-0.22UF,25V,10%,X7R,CH4224K1B01",0.22UF,10%,C0402,16175.06,5664.26,90.000,NO,,,
PC1848,"Q_CAP_C0402-1UF,25V,10%,X6S,CH5104KEB02",1UF,10%,C0402,16383.34,5597.87,270.000,NO,,,
PC1849,"Q_CAP_C0805-22UF,16V,20%,X6S,CH6223MEA01",22UF,20%,C0805_H57,16296.39,5331.30,0.000,NO,,,
PC1850,"Q_CAP_C0805-22UF,16V,20%,X6S,CH6223MEA01",22UF,20%,C0805_H57,16296.39,5262.30,0.000,NO,,,
PC1852,"Q_CAP_0402-0.1UF,25V,10%,X7R,CH4104K1B00",0.1UF,10%,C0402,16091.41,5969.06,90.000,YES,,,
PC1853,"Q_CAP_0402-0.1UF,25V,10%,X7R,CH4104K1B00",0.1UF,10%,C0402,16119.48,5546.64,180.000,NO,,,
PC1855,"Q_CAP_C0805-22UF,10V,20%,X6S,CH6222MEA01",22UF,20%,C0805_H61,16302.59,5958.15,90.000,YES,,,
PC1856,"Q_CAP_C0805-22UF,10V,20%,X6S,CH6222MEA01",22UF,20%,C0805_H61,16230.59,5958.54,90.000,YES,,,
PC1866,"Q_CAPP_THLF-560UF,6.3V,20%,OSCON,CC75601MD16",560UF,20%,EC2-5_6-8_9-5,18000.02,2849.34,180.000,NO,,,
PC1867,"Q_CAPP_THLF-560UF,6.3V,20%,OSCON,CC75601MD16",560UF,20%,EC2-5_6-8_9-5,17704.42,2849.34,180.000,NO,,,
PC1868,"Q_CAP_C0805-22UF,10V,20%,X6S,CH6222MEA01",22UF,20%,C0805_H61,17832.96,2589.33,90.000,YES,,,
PC1869,"Q_CAP_0402-0.1UF,25V,10%,X7R,CH4104K1B00",0.1UF,10%,C0402,18072.96,2590.33,90.000,YES,,,
PC1870,"Q_CAP_0402-0.1UF,25V,10%,EMPTY,CH4104K1B00",NA,10%,C0402,17800.75,1869.11,180.000,NO,,,
PC1877,"Q_CAP_0402-47PF,50V,5%,NPO,TMP_QCH04706JB01",47PF,5%,C0402,16052.86,5486.73,270.000,NO,,,
PC1898,"Q_CAP_C0805-22UF,16V,20%,X6S,CH6223MEA01",22UF,20%,C0805_H57,16296.39,5400.30,0.000,NO,,,
PC2079,"Q_CAP_C0402-1UF,25V,10%,X6S,CH5104KEB02",1UF,10%,C0402,17678.91,988.20,270.000,NO,,,
PC2080,"Q_CAP_C0805-22UF,16V,20%,X6S,CH6223MEA01",22UF,20%,C0805_H57,17328.89,863.48,0.000,YES,,,
PC2081,"Q_CAP_C0805-10UF,16V,10%,X6S,CH6103KEA01",10UF,10%,C0805_H57,16798.50,4316.72,90.000,NO,,,
PC2082,"Q_CAP_C0805-10UF,16V,10%,X6S,CH6103KEA01",10UF,10%,C0805_H57,17541.42,930.75,0.000,NO,,,
PC2085,"Q_CAP_C0402-1UF,25V,10%,X6S,CH5104KEB02",1UF,10%,C0402,17702.78,928.91,180.000,NO,,,
PC2086,"Q_CAP_C0402-1UF,25V,10%,X6S,CH5104KEB02",1UF,10%,C0402,17104.08,4219.45,90.000,NO,,,
PC2087,"Q_CAP_C0402-1UF,25V,10%,X6S,CH5104KEB02",1UF,10%,C0402,17620.68,767.97,0.000,NO,,,
PC2088,"Q_CAP_C0402-0.01UF,50V,10%,EMPTY,CH31006KB18",NA,10%,C0402,17836.78,969.27,180.000,NO,,,
PC2089,"Q_CAP_C0402-6800PF,50V,10%,X7R,CH2686K1B01",6800PF,10%,C0402,17104.26,4091.63,270.000,NO,,,
PC2091,"Q_CAP_0402-0.1UF,25V,10%,X7R,CH4104K1B00",0.1UF,10%,C0402,16738.72,4296.45,90.000,NO,,,
PC2092,"Q_CAP_0402-0.1UF,25V,10%,X7R,CH4104K1B00",0.1UF,10%,C0402,17549.36,854.07,0.000,NO,,,
PC2093,"Q_CAP_C0402-1UF,25V,10%,X6S,CH5104KEB02",1UF,10%,C0402,16943.14,4301.55,270.000,NO,,,
PC2098,"Q_CAP_C0402-1UF,25V,10%,X6S,CH5104KEB02",1UF,10%,C0402,3036.57,917.67,180.000,NO,,,
PC2103,"Q_CAP_C0402-1UF,25V,10%,X6S,CH5104KEB02",1UF,10%,C0402,7036.10,15765.23,180.000,NO,,,
PC2137,"Q_CAP_0402-0.1UF,25V,10%,X7R,CH4104K1B00",0.1UF,10%,C0402,3714.12,2735.77,90.000,NO,,,
PC2139,"Q_CAP_C0402-1UF,25V,10%,X6S,CH5104KEB02",1UF,10%,C0402,3013.15,972.99,270.000,NO,,,
PC2140,"Q_CAP_C0402-1UF,25V,10%,X6S,CH5104KEB02",1UF,10%,C0402,3673.15,2113.61,0.000,NO,,,
PC2141,"Q_CAP_C0805-22UF,16V,20%,X6S,CH6223MEA01",22UF,20%,C0805_H57,2554.69,789.30,0.000,YES,,,
PC2142,"Q_CAP_C0805-10UF,16V,10%,X6S,CH6103KEA01",10UF,10%,C0805_H57,3526.18,2678.10,90.000,NO,,,
PC2143,"Q_CAP_C0805-10UF,16V,10%,X6S,CH6103KEA01",10UF,10%,C0805_H57,2554.69,789.30,180.000,NO,,,
PC2144,"Q_CAP_C0402-0.01UF,50V,10%,EMPTY,CH31006KB18",NA,10%,C0402,17150.44,4085.45,90.000,NO,,,
PC2146,"Q_CAP_C0402-1UF,25V,10%,X6S,CH5104KEB02",1UF,10%,C0402,2969.47,756.73,0.000,NO,,,
PC2147,"Q_CAP_C0402-1UF,25V,10%,X6S,CH5104KEB02",1UF,10%,C0402,3755.25,2354.55,180.000,NO,,,
PC2149,"Q_CAP_C0402-0.01UF,50V,10%,EMPTY,CH31006KB18",NA,10%,C0402,3539.15,2153.25,0.000,NO,,,
PC2150,"Q_CAP_C0402-3900PF,50V,10%,X7R,CH23906KB14",3900PF,10%,C0402,3185.57,918.03,0.000,NO,,,
PC2151,"Q_CAP_C0402-6800PF,50V,10%,X7R,CH2686K1B01",6800PF,10%,C0402,3539.33,2193.43,180.000,NO,,,
PC2152,"Q_CAP_0402-0.1UF,25V,10%,X7R,CH4104K1B00",0.1UF,10%,C0402,2563.00,734.00,180.000,NO,,,
PC2153,"Q_CAP_0402-0.22UF,16V,10%,X7R,CH4223K1B00",0.22UF,10%,C0402,17469.18,1266.67,90.000,NO,,,
PC2154,"Q_CAP_C0402-1UF,25V,10%,X6S,CH5104KEB02",1UF,10%,C0402,17644.78,1186.27,90.000,NO,,,
PC2155,"Q_CAP_C0402-0.047UF,25V,10%,X7R,CH3474K1B04",0.047UF,10%,C0402,17364.18,1266.67,90.000,NO,,,
PC2156,"Q_CAP_C0402-100NF,50V,10%,X7R,CH4106K1B01",100NF,10%,C0402,17294.18,1266.67,90.000,NO,,,
PC2157,"Q_CAP_0402-39PF,50V,5%,NPO,CH03906JB06",39PF,5%,C0402,16596.10,3987.02,270.000,NO,,,
PC2158,"Q_CAP_C0603-2.2UF,16V,20%,X7R,CH5223M1900",2.2UF,20%,C0603_H40,17295.08,997.27,180.000,NO,,,
PC2159,"Q_CAP_C0402-1UF,25V,10%,X6S,CH5104KEB02",1UF,10%,C0402,16461.10,4142.02,180.000,NO,,,
PC2160,"Q_CAP_0402-0.1UF,25V,10%,X7R,CH4104K1B00",0.1UF,10%,C0402,17503.88,1003.07,0.000,NO,,,
PC2161,"Q_CAP_0402-0.068UF,16V,10%,X7R,CH3683K1B09",0.068UF,10%,C0402,16465.10,4300.44,90.000,NO,,,
PC2162,"Q_CAP_0402-100PF,50V,5%,X7R,CH11006JB18",100PF,5%,C0402,16611.10,4302.02,90.000,NO,,,
PC2163,"Q_CAP_C0805-10UF,16V,10%,X6S,CH6103KEA01",10UF,10%,C0805_H57,16675.70,4178.32,90.000,NO,,,
PC2164,"Q_CAP_0402-0.22UF,16V,10%,X7R,CH4223K1B00",0.22UF,10%,C0402,2717.97,1255.43,90.000,NO,,,
PC2165,"Q_CAP_C0402-1UF,25V,10%,X6S,CH5104KEB02",1UF,10%,C0402,2893.57,1175.03,90.000,NO,,,
PC2166,"Q_CAP_C0402-0.047UF,25V,10%,X7R,CH3474K1B04",0.047UF,10%,C0402,2612.97,1255.43,90.000,NO,,,
PC2167,"Q_CAP_0402-100PF,50V,5%,NPO,CH11006JB00",100PF,5%,C0402,2542.97,1255.43,90.000,NO,,,
PC2168,"Q_CAP_0402-39PF,50V,5%,NPO,CH03906JB06",39PF,5%,C0402,3526.28,2852.90,90.000,NO,,,
PC2169,"Q_CAP_C0402-1UF,25V,10%,X6S,CH5104KEB02",1UF,10%,C0402,3644.08,2940.30,180.000,NO,,,
PC2173,"Q_CAP_C0805-10UF,16V,10%,X6S,CH6103KEA01",10UF,10%,C0805_H57,3629.08,2749.70,180.000,NO,,,
PC2174,"Q_CAP_0402-0.1UF,25V,10%,X7R,CH4104K1B00",0.1UF,10%,C0402,2752.67,991.83,0.000,NO,,,
PC2181,"Q_CAP_C0402-1UF,25V,10%,X6S,CH5104KEB02",1UF,10%,C0402,8127.50,15834.33,90.000,NO,,,
PC2182,"Q_CAP_0402-220PF,50V,10%,X7R,TMP_QCH12206KB14",220PF,10%,C0402,8061.50,15906.33,0.000,NO,,,
PC2183,"Q_CAP_0402-220PF,50V,10%,EMPTY,TMP_QCH12206KB14",NA,10%,C0402,8481.50,15906.33,0.000,NO,,,
PC2184,"Q_CAP_0402-0.068UF,16V,10%,X7R,CH3683K1B09",0.068UF,10%,C0402,7646.50,15877.33,180.000,NO,,,
PC2185,"Q_CAP_0402-0.068UF,16V,10%,X7R,CH3683K1B09",0.068UF,10%,C0402,8061.50,15946.33,180.000,NO,,,
PC2186,"Q_CAP_C0402-1UF,25V,10%,X6S,CH5104KEB02",1UF,10%,C0402,7219.50,15823.58,270.000,YES,,,
PC2187,"Q_CAP_C0402-1UF,25V,10%,X6S,CH5104KEB02",1UF,10%,C0402,7036.10,15845.23,180.000,NO,,,
PC2188,"Q_CAP_C0402-1UF,25V,10%,X6S,CH5104KEB02",1UF,10%,C0402,7268.61,16107.43,180.000,NO,,,
PC2189,"Q_CAP_C0402-0.01UF,50V,10%,X7R,CH31006KB18",0.01UF,10%,C0402,7230.50,16009.33,90.000,NO,,,
PC2190,"Q_CAP_C0402-0.01UF,50V,10%,X7R,CH31006KB18",0.01UF,10%,C0402,7187.50,15663.33,180.000,NO,,,
PC2191,"Q_CAP_0402-0.068UF,16V,10%,X7R,CH3683K1B09",0.068UF,10%,C0402,6985.00,15925.00,90.000,NO,,,
PC2192,"Q_CAP_C0402-0.001UF,50V,10%,X7R,CH30106KB19",0.001UF,10%,C0402,7035.00,15965.00,180.000,NO,,,
PC2193,"Q_CAP_C0402-0.047UF,25V,10%,X7R,CH3474K1B04",0.047UF,10%,C0402,7036.10,15645.23,180.000,NO,,,
PC2196,"Q_CAP_0402-0.22UF,16V,10%,X7R,CH4223K1B00",0.22UF,10%,C0402,10152.20,1989.99,0.000,NO,,,
PC2197,"Q_CAP_0402-39PF,50V,5%,NPO,CH03906JB06",39PF,5%,C0402,7582.66,2693.22,180.000,NO,,,
PC2198,"Q_CAP_C0402-1UF,25V,10%,X6S,CH5104KEB02",1UF,10%,C0402,10232.20,1875.99,90.000,NO,,,
PC2200,"Q_CAP_C0402-1UF,25V,10%,X6S,CH5104KEB02",1UF,10%,C0402,7737.66,2828.22,90.000,NO,,,
PC2201,"Q_CAP_0402-0.068UF,16V,10%,X7R,CH3683K1B09",0.068UF,10%,C0402,7897.66,2818.22,0.000,NO,,,
PC2202,"Q_CAP_C0402-100NF,50V,10%,X7R,CH4106K1B01",100NF,10%,C0402,10151.95,2144.23,0.000,NO,,,
PC2203,"Q_CAP_0402-100PF,50V,5%,X7R,CH11006JB18",100PF,5%,C0402,7897.66,2678.22,0.000,NO,,,
PC2204,"Q_CAP_C0805-10UF,16V,10%,X6S,CH6103KEA01",10UF,10%,C0805_H57,7734.56,2567.92,270.000,NO,,,
PC2205,"Q_CAP_C0603-2.2UF,16V,20%,X7R,CH5223M1900",2.2UF,20%,C0603_H40,9882.28,2143.33,90.000,NO,,,
PC2206,"Q_CAP_0402-0.1UF,25V,10%,X7R,CH4104K1B00",0.1UF,10%,C0402,9888.35,1934.53,270.000,NO,,,
PC2207,"Q_CAP_C0402-1UF,25V,10%,X6S,CH5104KEB02",1UF,10%,C0402,10113.76,1752.78,180.000,NO,,,
PC2208,"Q_CAP_C0402-1UF,25V,10%,X6S,CH5104KEB02",1UF,10%,C0402,8635.71,2953.85,270.000,NO,,,
PC2209,"Q_CAP_C0402-1UF,25V,10%,X6S,CH5104KEB02",1UF,10%,C0402,10056.99,1728.43,90.000,NO,,,
PC2210,"Q_CAP_C0402-1UF,25V,10%,X6S,CH5104KEB02",1UF,10%,C0402,8660.43,2893.11,180.000,NO,,,
PC2211,"Q_CAP_C0402-1UF,25V,10%,X6S,CH5104KEB02",1UF,10%,C0402,9896.05,1810.53,270.000,NO,,,
PC2212,"Q_CAP_C0402-1UF,25V,10%,X6S,CH5104KEB02",1UF,10%,C0402,8578.33,2732.17,0.000,NO,,,
PC2213,"Q_CAP_C0402-0.01UF,50V,10%,EMPTY,CH31006KB18",NA,10%,C0402,8794.43,2933.47,180.000,NO,,,
PC2214,"Q_CAP_C0402-0.01UF,50V,10%,EMPTY,CH31006KB18",NA,10%,C0402,10097.35,1594.43,90.000,NO,,,
PC2215,"Q_CAP_C0402-3900PF,50V,10%,X7R,CH23906KB14",3900PF,10%,C0402,10057.35,1594.43,270.000,NO,,,
PC2216,"Q_CAP_C0402-6800PF,50V,10%,X7R,CH2686K1B01",6800PF,10%,C0402,8794.15,2894.39,0.000,NO,,,
PC2217,"Q_CAP_0402-0.1UF,25V,10%,X7R,CH4104K1B00",0.1UF,10%,C0402,9831.24,1893.47,0.000,NO,,,
PC2218,"Q_CAP_0402-0.1UF,25V,10%,X7R,CH4104K1B00",0.1UF,10%,C0402,8595.92,2404.41,180.000,NO,,,
PC2219,"Q_CAP_C0805-10UF,16V,10%,X6S,CH6103KEA01",10UF,10%,C0805_H57,9693.90,2125.89,90.000,NO,,,
PC2220,"Q_CAP_C0805-10UF,16V,10%,X6S,CH6103KEA01",10UF,10%,C0805_H57,8590.76,2340.68,180.000,NO,,,
PC2223,"Q_CAP_C0402-1UF,25V,10%,X6S,CH5104KEB02",1UF,10%,C0402,8967.50,15834.33,90.000,NO,,,
PC2224,"Q_CAP_0402-220PF,50V,10%,EMPTY,TMP_QCH12206KB14",NA,10%,C0402,8901.50,15906.33,0.000,NO,,,
PC2225,"Q_CAP_0402-220PF,50V,10%,EMPTY,TMP_QCH12206KB14",NA,10%,C0402,9321.50,15822.33,0.000,NO,,,
PC2226,"Q_CAP_0402-0.068UF,16V,10%,X7R,CH3683K1B09",0.068UF,10%,C0402,8481.50,15946.33,180.000,NO,,,
PC2227,"Q_CAP_0402-0.068UF,16V,10%,X7R,CH3683K1B09",0.068UF,10%,C0402,8901.50,15946.33,180.000,NO,,,
PC2229,"Q_CAP_0402-0.22UF,16V,10%,X7R,CH4223K1B00",0.22UF,10%,C0402,7049.53,1296.68,90.000,NO,,,
PC2230,"Q_CAP_C0402-1UF,25V,10%,X6S,CH5104KEB02",1UF,10%,C0402,7373.40,1172.35,270.000,NO,,,
PC2231,"Q_CAP_C0402-1UF,25V,10%,X6S,CH5104KEB02",1UF,10%,C0402,7239.33,1369.88,90.000,NO,,,
PC2232,"Q_CAP_C0402-0.047UF,25V,10%,X7R,CH3474K1B04",0.047UF,10%,C0402,6944.53,1296.68,90.000,NO,,,
PC2233,"Q_CAP_C0402-1UF,25V,10%,X6S,CH5104KEB02",1UF,10%,C0402,7397.33,1112.52,180.000,NO,,,
PC2234,"Q_CAP_C0402-1UF,25V,10%,X6S,CH5104KEB02",1UF,10%,C0402,7315.23,951.58,0.000,NO,,,
PC2235,"Q_CAP_C0402-100NF,50V,10%,X7R,CH4106K1B01",100NF,10%,C0402,6874.53,1296.68,90.000,NO,,,
PC2236,"Q_CAP_C0402-0.01UF,50V,10%,EMPTY,CH31006KB18",NA,10%,C0402,7531.33,1152.88,180.000,NO,,,
PC2237,"Q_CAP_C0402-3900PF,50V,10%,X7R,CH23906KB14",3900PF,10%,C0402,7531.33,1112.88,0.000,NO,,,
PC2238,"Q_CAP_0402-0.1UF,25V,10%,X7R,CH4104K1B00",0.1UF,10%,C0402,6922.20,769.62,180.000,NO,,,
PC2239,"Q_CAP_C0603-2.2UF,16V,20%,X7R,CH5223M1900",2.2UF,20%,C0603_H40,6875.43,1017.58,180.000,NO,,,
PC2240,"Q_CAP_C0805-10UF,16V,10%,X6S,CH6103KEA01",10UF,10%,C0805_H57,6889.20,970.62,0.000,YES,,,
PC2241,"Q_CAP_0402-0.1UF,25V,10%,X7R,CH4104K1B00",0.1UF,10%,C0402,7084.23,1033.08,0.000,NO,,,
PC2242,"Q_CAP_C0805-22UF,16V,20%,X6S,CH6223MEA01",22UF,20%,C0805_H57,6892.20,833.62,180.000,NO,,,
PC2260,"Q_CAP_C0805-22UF,16V,20%,X6S,CH6223MEA01",22UF,20%,C0805_H57,17578.48,1870.33,270.000,NO,,,
PC2261,"Q_CAP_C0805-22UF,16V,20%,X6S,CH6223MEA01",22UF,20%,C0805_H57,17569.23,2094.02,90.000,NO,,,
PC2262,"Q_CAP_C0805-22UF,16V,20%,X6S,CH6223MEA01",22UF,20%,C0805_H57,17507.88,1870.96,270.000,NO,,,
PC2263,"Q_CAP_C0805-22UF,16V,20%,X6S,CH6223MEA01",22UF,20%,C0805_H57,17498.33,2094.02,90.000,NO,,,
PC2280,"Q_CAP_C0805-10UF,16V,10%,X6S,CH6103KEA01",10UF,10%,C0805_H57,9685.80,2122.99,270.000,YES,,,
PC2281,"Q_CAP_C0402-0.047UF,25V,10%,X7R,CH3474K1B04",0.047UF,10%,C0402,10151.95,2074.23,0.000,NO,,,
PC2340,"Q_CAP_C0402-560PF,50V,10%,X7R,CH1566K1B09",560PF,10%,C0402,7078.49,1286.93,90.000,YES,,,
PC2341,"Q_CAP_C0402-560PF,50V,10%,X7R,CH1566K1B09",560PF,10%,C0402,10219.11,2016.28,270.000,YES,,,
PC2342,"Q_CAP_C0805-22UF,16V,20%,X6S,CH6223MEA01",22UF,20%,C0805_H57,17639.83,2094.65,90.000,NO,,,
PC2343,"Q_CAP_C0805-22UF,16V,20%,X6S,CH6223MEA01",22UF,20%,C0805_H57,17718.48,1870.33,270.000,NO,,,
PC2344,"Q_CAP_C0805-22UF,16V,20%,X6S,CH6223MEA01",22UF,20%,C0805_H57,17723.54,1870.29,90.000,YES,,,
PC2347,"Q_CAP_0402-1NF,50V,10%,EMPTY,CH21006KB16",NA,10%,C0402,7646.37,15706.33,180.000,NO,,,
PC2348,"Q_CAP_0402-1NF,50V,10%,EMPTY,CH21006KB16",NA,10%,C0402,8061.50,15706.33,180.000,NO,,,
PC2349,"Q_CAP_0402-1NF,50V,10%,EMPTY,CH21006KB16",NA,10%,C0402,8901.50,15706.33,180.000,NO,,,
PC2350,"Q_CAP_0402-1NF,50V,10%,EMPTY,CH21006KB16",NA,10%,C0402,8481.50,15706.33,180.000,NO,,,
PC3272,"Q_CAP_C0402-1UF,25V,10%,X6S,CH5104KEB02",1UF,10%,C0402,8547.50,15834.33,90.000,NO,,,
PC4056,"Q_CAP_C0402-3900PF,50V,10%,X7R,CH23906KB14",3900PF,10%,C0402,17836.78,929.27,0.000,NO,,,
PC5328,"Q_CAP_C0402-1UF,25V,10%,X6S,CH5104KEB02",1UF,10%,C0402,17165.27,4243.40,180.000,NO,,,
PC6000,"Q_CAP_C0402-0.1UF,25V,10%,X6S,CH4104KEB00",0.1UF,10%,C0402,8094.11,13641.93,0.000,NO,,,
PC6001,"Q_CAP_C0402-0.1UF,25V,10%,X6S,CH4104KEB00",0.1UF,10%,C0402,13006.51,5274.18,180.000,NO,,,
PC6002,"Q_CAP_0402-0.1UF,25V,10%,X7R,CH4104K1B00",0.1UF,10%,C0402,3339.88,5953.04,270.000,NO,,,
PC6003,"Q_CAP_0402-0.1UF,25V,10%,X7R,CH4104K1B00",0.1UF,10%,C0402,17414.97,14350.05,0.000,NO,,,
PC6004,"Q_CAP_0402-0.1UF,25V,10%,X7R,CH4104K1B00",0.1UF,10%,C0402,3661.32,6174.38,0.000,NO,,,
PC6005,"Q_CAP_C0402-0.01UF,25V,10%,EMPTY,CH3104K1B11",NA,10%,C0402,12947.56,5521.47,0.000,NO,,,
PC6006,"Q_CAP_C0402-0.01UF,25V,10%,EMPTY,CH3104K1B11",NA,10%,C0402,2821.41,5740.22,180.000,NO,,,
PC6007,"Q_CAP_0402-0.1UF,25V,10%,X7R,CH4104K1B00",0.1UF,10%,C0402,4834.65,5785.72,0.000,NO,,,
PC6008,"Q_CAP_C0402-1UF,25V,10%,X6S,CH5104KEB02",1UF,10%,C0402,5648.05,3188.09,180.000,NO,,,
PC6009,"Q_CAP_C0402-1UF,25V,10%,X6S,CH5104KEB02",1UF,10%,C0402,4778.05,3098.09,180.000,NO,,,
PC6010,"Q_CAP_C0402-1UF,25V,10%,X6S,CH5104KEB02",1UF,10%,C0402,5560.38,3111.38,90.000,NO,,,
PC6011,"Q_CAP_C0402-1UF,25V,10%,X6S,CH5104KEB02",1UF,10%,C0402,4690.38,3021.38,90.000,NO,,,
PC6012,"Q_CAP_C0805-22UF,16V,20%,X6S,CH6223MEA01",22UF,20%,C0805_H57,5438.71,3121.61,90.000,NO,,,
PC6013,"Q_CAP_C0805-22UF,16V,20%,X6S,CH6223MEA01",22UF,20%,C0805_H57,4637.51,3031.01,90.000,NO,,,
PC6014,"Q_CAP_C0805-22UF,16V,20%,X6S,CH6223MEA01",22UF,20%,C0805_H57,5507.51,3121.01,90.000,NO,,,
PC6015,"Q_CAP_C0805-22UF,16V,20%,X6S,CH6223MEA01",22UF,20%,C0805_H57,4568.71,3031.61,90.000,NO,,,
PC6016,"Q_CAP_0402-3300PF,50V,10%,X7R,TMP_QCH2336K1B12",3300PF,10%,C0402,4818.00,2884.69,180.000,NO,,,
PC6017,"Q_CAP_C0402-0.22UF,25V,10%,X7R,CH4224K1B01",0.22UF,10%,C0402,4885.38,3002.03,90.000,NO,,,
PC6018,"Q_CAP_C0805-22UF,4V,20%,X6S,CH622KMEA03",22UF,20%,C0805_H61,5122.23,2930.60,0.000,YES,,,
PC6019,"Q_CAP_0402-330PF,50V,10%,X7R,CH1336K1B02",330PF,10%,C0402,5619.28,2937.38,0.000,NO,,,
PC6020,"Q_CAP_C0402-100NF,50V,10%,X7R,CH4106K1B01",100NF,10%,C0402,5401.42,2922.68,180.000,NO,,,
PC6021,"Q_CAP_C0402-100NF,50V,10%,X7R,CH4106K1B01",100NF,10%,C0402,5997.23,2897.21,180.000,NO,,,
PC6022,"Q_CAP_C0402-100NF,50V,10%,X7R,CH4106K1B01",100NF,10%,C0402,5127.23,2807.21,180.000,NO,,,
PC6023,"Q_CAP_C0402-100NF,50V,10%,X7R,CH4106K1B01",100NF,10%,C0402,4528.52,2833.18,180.000,NO,,,
PC6024,"Q_CAP_C0805-22UF,4V,20%,X6S,CH622KMEA03",22UF,20%,C0805_H61,5122.23,3011.15,0.000,YES,,,
PC6025,"Q_CAP_C0805-22UF,4V,20%,X6S,CH622KMEA03",22UF,20%,C0805_H61,5122.23,3091.70,0.000,YES,,,
PC6026,"Q_CAP_C0805-22UF,4V,20%,X6S,CH622KMEA03",22UF,20%,C0805_H61,5122.23,2850.10,0.000,YES,,,
PC6500,"Q_CAP_C0402-0.1UF,25V,10%,X6S,CH4104KEB00",0.1UF,10%,C0402,9787.25,10554.84,180.000,NO,,,
PC6501,"Q_CAP_C0805-22UF,16V,20%,X6S,CH6223MEA01",22UF,20%,C0805_H57,9619.19,11245.34,0.000,NO,,,
PC6502,"Q_CAP_C0805-22UF,16V,20%,X6S,CH6223MEA01",22UF,20%,C0805_H57,9619.19,11175.34,0.000,NO,,,
PC6503,"Q_CAP_C0805-22UF,16V,20%,X6S,CH6223MEA01",22UF,20%,C0805_H57,9480.00,11162.00,180.000,NO,,,
PC6504,"Q_CAP_C0805-22UF,16V,20%,X6S,CH6223MEA01",22UF,20%,C0805_H57,9480.00,11092.00,180.000,NO,,,
PC6505,"Q_CAP_C0402-1UF,25V,10%,X6S,CH5104KEB02",1UF,10%,C0402,9550.73,11611.69,180.000,NO,,,
PC6506,"Q_CAP_C0402-1UF,25V,10%,X6S,CH5104KEB02",1UF,10%,C0402,9694.72,11540.75,270.000,NO,,,
PC6507,"Q_CAP_0402-0.22UF,16V,10%,X7R,CH4223K1B00",0.22UF,10%,C0402,9424.19,11613.31,90.000,NO,,,
PC6508,"Q_CAP_C0805-22UF,4V,20%,X6S,CH622KMEA03",22UF,20%,C0805_H61,9599.07,12439.20,270.000,YES,,,
PC6509,"Q_CAP_C0805-22UF,4V,20%,X6S,CH622KMEA03",22UF,20%,C0805_H61,9750.07,12439.20,270.000,YES,,,
PC6510,"Q_CAP_C0805-22UF,4V,20%,X6S,CH622KMEA03",22UF,20%,C0805_H61,9448.07,12439.20,270.000,YES,,,
PC6511,"Q_CAP_C0805-22UF,4V,20%,X6S,CH622KMEA03",22UF,20%,C0805_H61,9518.07,12439.20,270.000,YES,,,
PC6512,"Q_CAP_C0805-22UF,4V,20%,X6S,CH622KMEA03",22UF,20%,C0805_H61,9680.07,12439.20,270.000,YES,,,
PC6513,"Q_CAPP_SMLF-390UF,2.5V,20%,ALUM,CC7390JMZ13",390UF,20%,EC56_197_229SXA,9504.07,12434.20,90.000,NO,,,
PC6514,"Q_CAP_0402-0.1UF,25V,10%,X7R,CH4104K1B00",0.1UF,10%,C0402,9359.07,12439.20,90.000,NO,,,
PC6515,"Q_CAP_0402-150PF,50V,5%,NPO,TMP_QCH11506JB08",150PF,5%,C0402,9363.93,11430.78,90.000,NO,,,
PC6518,"Q_CAP_0402-0.1UF,25V,10%,X7R,CH4104K1B00",0.1UF,10%,C0402,9430.55,11490.69,180.000,NO,,,
PC6519,"Q_CAP_C0402-0.1UF,25V,10%,X6S,CH4104KEB00",0.1UF,10%,C0402,8874.82,10560.33,0.000,NO,,,
PC6520,"Q_CAP_C0805-22UF,16V,20%,X6S,CH6223MEA01",22UF,20%,C0805_H57,9050.00,11177.87,180.000,NO,,,
PC6521,"Q_CAP_C0805-22UF,16V,20%,X6S,CH6223MEA01",22UF,20%,C0805_H57,9182.00,11162.00,0.000,NO,,,
PC6522,"Q_CAP_C0805-22UF,16V,20%,X6S,CH6223MEA01",22UF,20%,C0805_H57,9182.00,11232.00,0.000,NO,,,
PC6523,"Q_CAP_C0805-22UF,16V,20%,X6S,CH6223MEA01",22UF,20%,C0805_H57,9050.00,11109.79,180.000,NO,,,
PC6524,"Q_CAP_C0402-1UF,25V,10%,X6S,CH5104KEB02",1UF,10%,C0402,9080.48,11611.69,180.000,NO,,,
PC6525,"Q_CAP_C0402-1UF,25V,10%,X6S,CH5104KEB02",1UF,10%,C0402,9224.47,11540.75,270.000,NO,,,
PC6526,"Q_CAP_0402-0.22UF,16V,10%,X7R,CH4223K1B00",0.22UF,10%,C0402,8953.94,11613.31,90.000,NO,,,
PC6527,"Q_CAP_C0805-22UF,4V,20%,X6S,CH622KMEA03",22UF,20%,C0805_H61,9009.23,12439.20,270.000,YES,,,
PC6528,"Q_CAP_C0805-22UF,4V,20%,X6S,CH622KMEA03",22UF,20%,C0805_H61,8928.23,12439.20,270.000,YES,,,
PC6529,"Q_CAP_C0805-22UF,4V,20%,X6S,CH622KMEA03",22UF,20%,C0805_H61,9090.23,12439.20,270.000,YES,,,
PC6530,"Q_CAP_C0805-22UF,4V,20%,X6S,CH622KMEA03",22UF,20%,C0805_H61,9160.23,12439.20,270.000,YES,,,
PC6531,"Q_CAP_C0805-22UF,4V,20%,X6S,CH622KMEA03",22UF,20%,C0805_H61,8858.23,12439.20,270.000,YES,,,
PC6532,"Q_CAPP_SMLF-390UF,2.5V,20%,ALUM,CC7390JMZ13",390UF,20%,EC56_197_229SXA,9154.23,12434.20,90.000,NO,,,
PC6533,"Q_CAP_0402-0.1UF,25V,10%,X7R,CH4104K1B00",0.1UF,10%,C0402,8769.23,12439.20,90.000,NO,,,
PC6534,"Q_CAP_0402-150PF,50V,5%,NPO,TMP_QCH11506JB08",150PF,5%,C0402,8893.68,11430.78,90.000,NO,,,
PC6537,"Q_CAP_0402-0.1UF,25V,10%,X7R,CH4104K1B00",0.1UF,10%,C0402,8960.30,11490.69,180.000,NO,,,
PC6540,"Q_CAP_0402-3300PF,50V,10%,X7R,TMP_QCH2336K1B12",3300PF,10%,C0402,17404.63,16539.65,0.000,NO,,,
PC6543,"Q_CAP_C0402-100NF,50V,10%,X7R,CH4106K1B01",100NF,10%,C0402,396.33,16033.96,180.000,NO,,,
PC6544,"Q_CAP_C0402-1UF,16V,10%,X6S,CH5103KEB01",1UF,10%,C0402,396.33,15988.96,180.000,NO,,,
PC6545,"Q_CAP_C0402-1UF,16V,10%,X6S,CH5103KEB01",1UF,10%,C0402,456.33,15968.96,270.000,NO,,,
PC6546,"Q_CAP_C0402-10UF,6.3V,20%,X6S,CH6101MEB03",10UF,20%,C0402,501.33,15968.96,270.000,NO,,,
PC6552,"Q_CAP_C0402-2.2UF,10V,10%,X6S,CH5222KEB01",2.2UF,10%,C0402,17379.14,15717.07,90.000,NO,,,
PC6560,"Q_CAP_C0805-22UF,16V,20%,X6S,CH6223MEA01",22UF,20%,C0805_H57,17607.79,15975.50,0.000,YES,,,
PC6561,"Q_CAPP_SMLF-100UF,16V,20%,OSCON,CC71003MZ30",100UF,20%,EC56_197_229SXA,17538.11,16216.50,180.000,NO,,,
PC6562,"Q_CAP_0402-0.1UF,25V,10%,X7R,CH4104K1B00",0.1UF,10%,C0402,17664.23,16356.86,180.000,NO,,,
PC6563,"Q_CAP_C0402-100NF,50V,10%,X7R,CH4106K1B01",100NF,10%,C0402,17600.51,15818.32,270.000,NO,,,
PC6564,"Q_CAP_C0402-560PF,50V,10%,EMPTY,CH1566K1B09",NA,10%,C0402,17374.45,15523.71,180.000,NO,,,
PC6565,"Q_CAP_C0402-100NF,50V,10%,X7R,CH4106K1B01",100NF,10%,C0402,17406.88,15326.04,90.000,NO,,,
PC6568,"Q_CAPP_SMLF-470UF,2.5V,20%,SPCAP,CH747LM8818",470UF,20%,TAJ_DXC,17486.88,14961.71,90.000,YES,,,
PC6569,"Q_CAPP_SMLF-470UF,2.5V,20%,SPCAP,CH747LM8818",470UF,20%,TAJ_DXC,17953.88,14961.71,90.000,YES,,,
PC6570,"Q_CAPP_SMLF-470UF,2.5V,20%,SPCAP,CH747LM8818",470UF,20%,TAJ_DXC,17713.88,14961.71,90.000,YES,,,
PC6571,"Q_CAPP_SMLF-390UF,2.5V,20%,ALUM,CC7390JMZ13",390UF,20%,EC56_197_229SXA,17474.79,14966.05,270.000,NO,,,
PC6572,"Q_CAPP_SMLF-390UF,2.5V,20%,ALUM,CC7390JMZ13",390UF,20%,EC56_197_229SXA,18194.79,14966.05,270.000,NO,,,
PC6573,"Q_CAPP_SMLF-390UF,2.5V,20%,ALUM,CC7390JMZ13",390UF,20%,EC56_197_229SXA,17954.79,14966.05,270.000,NO,,,
PC6574,"Q_CAPP_SMLF-390UF,2.5V,20%,ALUM,CC7390JMZ13",390UF,20%,EC56_197_229SXA,17714.79,14966.05,270.000,NO,,,
PC6575,"Q_CAP_C0402-2.2UF,10V,10%,X6S,CH5222KEB01",2.2UF,10%,C0402,17736.57,15722.07,90.000,NO,,,
PC6576,"Q_CAP_C0402-100NF,50V,10%,X7R,CH4106K1B01",100NF,10%,C0402,17744.79,15824.05,180.000,NO,,,
PC6583,"Q_CAP_C0805-22UF,16V,20%,X6S,CH6223MEA01",22UF,20%,C0805_H57,18045.13,16058.16,180.000,YES,,,
PC6584,"Q_CAP_C0402-100NF,50V,10%,X7R,CH4106K1B01",100NF,10%,C0402,17957.94,15815.32,270.000,NO,,,
PC6585,"Q_CAP_C0402-560PF,50V,10%,EMPTY,CH1566K1B09",NA,10%,C0402,17731.88,15523.71,180.000,NO,,,
PC6600,"Q_CAP_0402-3300PF,50V,10%,X7R,TMP_QCH2336K1B12",3300PF,10%,C0402,686.33,16303.96,180.000,NO,,,
PC6601,"Q_CAP_0402-0.1UF,25V,10%,EMPTY,CH4104K1B00",NA,10%,C0402,17698.08,16740.57,0.000,NO,,,
PC6602,"Q_CAP_0402-0.1UF,25V,10%,X7R,CH4104K1B00",0.1UF,10%,C0402,17694.63,16781.72,0.000,NO,,,
PC6603,"Q_CAP_C0402-100NF,50V,10%,X7R,CH4106K1B01",100NF,10%,C0402,17694.63,16817.02,0.000,NO,,,
PC6604,"Q_CAP_C0402-1UF,16V,10%,X6S,CH5103KEB01",1UF,10%,C0402,17694.63,16854.65,0.000,NO,,,
PC6605,"Q_CAP_C0402-1UF,16V,10%,X6S,CH5103KEB01",1UF,10%,C0402,17634.63,16874.65,90.000,NO,,,
PC6606,"Q_CAP_C0402-10UF,6.3V,20%,X6S,CH6101MEB03",10UF,20%,C0402,17589.63,16874.65,90.000,NO,,,
PC6607,"Q_CAP_0402-470PF,50V,10%,X7R,TMP_QCH14706KB18",470PF,10%,C0402,17699.28,16669.84,0.000,NO,,,
PC6610,"Q_CAP_C0402-2.2UF,10V,10%,X6S,CH5222KEB01",2.2UF,10%,C0402,506.31,15386.71,90.000,NO,,,
PC6618,"Q_CAP_C0805-22UF,16V,20%,X6S,CH6223MEA01",22UF,20%,C0805_H57,710.22,15578.89,0.000,YES,,,
PC6619,"Q_CAPP_SMLF-100UF,16V,20%,OSCON,CC71003MZ30",100UF,20%,EC56_197_229SXA,714.92,15751.94,180.000,NO,,,
PC6620,"Q_CAP_0402-0.1UF,25V,10%,X7R,CH4104K1B00",0.1UF,10%,C0402,1060.93,15977.97,0.000,NO,,,
PC6621,"Q_CAP_C0402-100NF,50V,10%,X7R,CH4106K1B01",100NF,10%,C0402,727.68,15487.96,270.000,NO,,,
PC6622,"Q_CAP_C0402-560PF,50V,10%,EMPTY,CH1566K1B09",NA,10%,C0402,501.62,15193.35,180.000,NO,,,
PC6623,"Q_CAP_C0402-100NF,50V,10%,X7R,CH4106K1B01",100NF,10%,C0402,520.40,15007.97,90.000,NO,,,
PC6626,"Q_CAPP_SMLF-470UF,2.5V,20%,SPCAP,CH747LM8818",470UF,20%,TAJ_DXC,500.81,14698.41,90.000,YES,,,
PC6627,"Q_CAPP_SMLF-470UF,2.5V,20%,SPCAP,CH747LM8818",470UF,20%,TAJ_DXC,741.81,14698.41,90.000,YES,,,
PC6628,"Q_CAPP_SMLF-470UF,2.5V,20%,SPCAP,CH747LM8818",470UF,20%,TAJ_DXC,261.81,14698.41,90.000,YES,,,
PC6629,"Q_CAPP_SMLF-390UF,2.5V,20%,ALUM,CC7390JMZ13",390UF,20%,EC56_197_229SXA,502.72,14702.75,270.000,NO,,,
PC6630,"Q_CAPP_SMLF-390UF,2.5V,20%,ALUM,CC7390JMZ13",390UF,20%,EC56_197_229SXA,742.72,14702.75,270.000,NO,,,
PC6631,"Q_CAPP_SMLF-390UF,2.5V,20%,ALUM,CC7390JMZ13",390UF,20%,EC56_197_229SXA,982.72,14702.75,270.000,NO,,,
PC6632,"Q_CAPP_SMLF-390UF,2.5V,20%,ALUM,CC7390JMZ13",390UF,20%,EC56_197_229SXA,262.72,14702.75,270.000,NO,,,
PC6639,"Q_CAP_C0805-22UF,16V,20%,X6S,CH6223MEA01",22UF,20%,C0805_H57,1218.48,15576.44,0.000,NO,,,
PC6640,"Q_CAP_C0402-100NF,50V,10%,X7R,CH4106K1B01",100NF,10%,C0402,1085.11,15484.96,270.000,NO,,,
PC6641,"Q_CAP_C0402-560PF,50V,10%,EMPTY,CH1566K1B09",NA,10%,C0402,859.05,15193.35,180.000,NO,,,
PC6645,"Q_CAP_C0402-2.2UF,10V,10%,X6S,CH5222KEB01",2.2UF,10%,C0402,863.74,15391.71,90.000,NO,,,
PC6646,"Q_CAP_C0402-100NF,50V,10%,X7R,CH4106K1B01",100NF,10%,C0402,871.96,15493.69,180.000,NO,,,
PC6800,"Q_CAPP_SMLF-270UF,16V,20%,OSCON,CC72703MZ11",270UF,20%,EC75_248_304S,9772.07,10922.58,0.000,NO,,,
PC6801,"Q_CAPP_SMLF-270UF,16V,20%,OSCON,CC72703MZ11",270UF,20%,EC75_248_304S,8867.28,10928.07,180.000,NO,,,
PC6802,"Q_CAP_C0805-22UF,16V,20%,X6S,CH6223MEA01",22UF,20%,C0805_H57,9619.19,11105.34,0.000,NO,,,
PC6803,"Q_CAP_C0805-22UF,16V,20%,X6S,CH6223MEA01",22UF,20%,C0805_H57,9182.00,11092.00,0.000,NO,,,
PC6804,"Q_CAPP_SMLF-390UF,2.5V,20%,ALUM,CC7390JMZ13",390UF,20%,EC56_197_229SXA,8914.23,12434.20,90.000,NO,,,
PC6805,"Q_CAPP_SMLF-390UF,2.5V,20%,ALUM,CC7390JMZ13",390UF,20%,EC56_197_229SXA,9744.07,12434.20,90.000,NO,,,
PC6806,"Q_CAP_C0402-100NF,50V,10%,X7R,CH4106K1B01",100NF,10%,C0402,18019.79,15324.05,270.000,YES,,,
PC6807,"Q_CAP_C0402-100NF,50V,10%,X7R,CH4106K1B01",100NF,10%,C0402,1031.77,15073.78,270.000,YES,,,
PC6810,"Q_CAPP_SMLF-100UF,16V,20%,OSCON,CC71003MZ30",100UF,20%,EC56_197_229SXA,18057.52,16215.50,0.000,NO,,,
PC6811,"Q_CAPP_SMLF-470UF,2.5V,20%,SPCAP,CH747LM8818",470UF,20%,TAJ_DXC,17581.88,15370.31,270.000,YES,,,
PC6812,"Q_CAPP_SMLF-470UF,2.5V,20%,SPCAP,CH747LM8818",470UF,20%,TAJ_DXC,17870.93,15370.77,270.000,YES,,,
PC6813,"Q_CAPP_SMLF-470UF,2.5V,20%,SPCAP,CH747LM8818",470UF,20%,TAJ_DXC,564.58,15099.95,270.000,YES,,,
PC6814,"Q_CAPP_SMLF-470UF,2.5V,20%,SPCAP,CH747LM8818",470UF,20%,TAJ_DXC,960.81,14698.41,90.000,YES,,,
PC6815,"Q_CAPP_SMLF-470UF,2.5V,20%,SPCAP,CH747LM8818",470UF,20%,TAJ_DXC,914.77,15099.95,270.000,YES,,,
PC6816,"Q_CAP_C0805-22UF,16V,20%,X6S,CH6223MEA01",22UF,20%,C0805_H57,17607.79,16049.50,0.000,YES,,,
PC6817,"Q_CAP_C0805-22UF,16V,20%,X6S,CH6223MEA01",22UF,20%,C0805_H57,18045.13,15983.16,180.000,YES,,,
PC6818,"Q_CAP_C0805-22UF,16V,20%,X6S,CH6223MEA01",22UF,20%,C0805_H57,1122.20,15848.06,270.000,YES,,,
PC6819,"Q_CAP_C0805-22UF,16V,20%,X6S,CH6223MEA01",22UF,20%,C0805_H57,709.35,15785.58,0.000,YES,,,
PC6900,"Q_CAP_C0805-22UF,16V,20%,X6S,CH6223MEA01",22UF,20%,C0805_H57,9480.00,11232.00,180.000,NO,,,
PC6901,"Q_CAP_C0805-22UF,16V,20%,X6S,CH6223MEA01",22UF,20%,C0805_H57,9618.00,11314.03,0.000,NO,,,
PC6902,"Q_CAP_C0805-22UF,16V,20%,X6S,CH6223MEA01",22UF,20%,C0805_H57,9480.00,11302.00,180.000,NO,,,
PC6903,"Q_CAP_C0805-22UF,16V,20%,X6S,CH6223MEA01",22UF,20%,C0805_H57,9050.00,11245.95,180.000,NO,,,
PC6904,"Q_CAP_C0805-22UF,16V,20%,X6S,CH6223MEA01",22UF,20%,C0805_H57,9050.00,11314.03,180.000,NO,,,
PC6905,"Q_CAP_C0805-22UF,16V,20%,X6S,CH6223MEA01",22UF,20%,C0805_H57,9182.00,11302.00,0.000,NO,,,
PC7000,"Q_CAP_C0805-22UF,16V,20%,X6S,CH6223MEA01",22UF,20%,C0805_H57,11444.20,13895.80,90.000,YES,,,
PC7001,"Q_CAP_C0805-22UF,16V,20%,X6S,CH6223MEA01",22UF,20%,C0805_H57,1206.90,13902.10,0.000,YES,,,
PC7002,"Q_CAP_C0805-22UF,16V,20%,X6S,CH6223MEA01",22UF,20%,C0805_H57,17231.10,14282.30,270.000,YES,,,
PC7003,"Q_CAP_C0805-22UF,16V,20%,X6S,CH6223MEA01",22UF,20%,C0805_H57,7290.00,14301.50,0.000,YES,,,
PC8000,"Q_CAP_C0805-22UF,16V,20%,X6S,CH6223MEA01",22UF,20%,C0805_H57,7871.73,13622.96,0.000,YES,,,
PC8001,"Q_CAP_C0805-22UF,16V,20%,X6S,CH6223MEA01",22UF,20%,C0805_H57,7871.73,13553.96,0.000,YES,,,
PC8002,"Q_CAP_C0805-22UF,16V,20%,X6S,CH6223MEA01",22UF,20%,C0805_H57,13235.14,5196.75,0.000,NO,,,
PC8003,"Q_CAP_C0805-22UF,16V,20%,X6S,CH6223MEA01",22UF,20%,C0805_H57,3179.61,6023.61,90.000,NO,,,
PC8004,"Q_CAP_C0805-22UF,16V,20%,X6S,CH6223MEA01",22UF,20%,C0805_H57,17300.00,14025.00,180.000,YES,,,
PC8005,"Q_CAP_C0805-22UF,16V,20%,X6S,CH6223MEA01",22UF,20%,C0805_H57,16767.58,14116.94,0.000,YES,,,
PC8006,"Q_CAP_C0805-22UF,16V,20%,X6S,CH6223MEA01",22UF,20%,C0805_H57,7290.00,14155.00,0.000,YES,,,
PC8007,"Q_CAP_C0805-22UF,16V,20%,X6S,CH6223MEA01",22UF,20%,C0805_H57,7779.94,14095.57,0.000,NO,,,
PC8008,"Q_CAP_0603-1UF,16V,10%,X7R,TMP_QCH5103K1900",1UF,10%,C0603,18121.74,1886.99,270.000,NO,,,
PC8009,"Q_CAP_C0805-22UF,16V,20%,X6S,CH6223MEA01",22UF,20%,C0805_H57,15703.94,6673.05,270.000,YES,,,
PC8010,"Q_CAP_C0805-22UF,16V,20%,X6S,CH6223MEA01",22UF,20%,C0805_H57,16045.01,6387.32,270.000,YES,,,
PC8011,"Q_CAP_C0805-22UF,16V,20%,X6S,CH6223MEA01",22UF,20%,C0805_H57,4952.79,6156.62,270.000,YES,,,
PC8012,"Q_CAP_C0805-22UF,16V,20%,X6S,CH6223MEA01",22UF,20%,C0805_H57,4620.13,6497.64,270.000,YES,,,
PC8013,"Q_CAP_C0805-22UF,16V,20%,X6S,CH6223MEA01",22UF,20%,C0805_H57,17639.83,2094.65,270.000,YES,,,
PC8014,"Q_CAP_C0805-22UF,16V,20%,X6S,CH6223MEA01",22UF,20%,C0805_H57,17569.23,2094.02,270.000,YES,,,
PC8071,"Q_CAP_C0805-22UF,16V,20%,X6S,CH6223MEA01",22UF,20%,C0805_H57,17778.64,2080.69,270.000,YES,,,
PC8567,"Q_CAP_C0805-22UF,16V,20%,X6S,CH6223MEA01",22UF,20%,C0805_H57,17708.48,2080.65,90.000,NO,,,
PD13,"ZENER_AC-5.0SMDJ14A,SMLF,IC,BC0MDJ14000",,,D2723_SMCXC,9963.14,16461.05,270.000,NO,,,
PD15,"ZENER_AC-5.0SMDJ14A,SMLF,IC,BC0MDJ14000",,,D2723_SMCXC,9686.90,16461.36,270.000,NO,,,
PD17,"SS15P3SM386A-SS15P3S-M3/86A,SMLF,IC,BC015P3SZ00",,,TO277A_4-3X6-1,9492.71,14756.35,90.000,NO,,,
PD101,"DIODE_TVS-SMF14A,SMLF,IC,BCSMF14AZ01",,,SOD123F,17768.78,1196.77,270.000,NO,,,
PD102,"SCHOTTKY_AC-B340A-13-F,SMLF,IC,BC000340Z30",,,D2010XF,17922.38,610.37,180.000,NO,,,
PD103,"SCHOTTKY_AC-B340A-13-F,SMLF,IC,BC000340Z30",,,D2010XF,16638.73,3855.98,0.000,NO,,,
PD107,"DIODE_TVS-SMF14A,SMLF,IC,BCSMF14AZ01",,,SOD123F,3067.53,1185.53,270.000,NO,,,
PD108,"SCHOTTKY_AC-B340A-13-F,SMLF,IC,BC000340Z30",,,D2010XF,3205.67,597.53,180.000,NO,,,
PD109,"SCHOTTKY_AC-B340A-13-F,SMLF,IC,BC000340Z30",,,D2010XF,3854.43,2639.33,270.000,NO,,,
PD111,"SS15P3SM386A-SS15P3S-M3/86A,SMLF,IC,BC015P3SZ00",,,TO277A_4-3X6-1,8493.85,15369.21,90.000,NO,,,
PD112,"SCHOTTKY_AC-B340A-13-F,SMLF,IC,BC000340Z30",,,D2010XF,9744.08,1610.36,90.000,NO,,,
PD113,"SCHOTTKY_AC-B340A-13-F,SMLF,IC,BC000340Z30",,,D2010XF,8463.52,2646.46,270.000,NO,,,
PD114,"DIODE_TVS-SMF14A,SMLF,IC,BCSMF14AZ01",,,SOD123F,10219.24,1565.14,90.000,NO,,,
PD115,"DIODE_TVS-SMF14A,SMLF,IC,BCSMF14AZ01",,,SOD123F,7522.26,1264.19,180.000,NO,,,
PD116,"SCHOTTKY_AC-B340A-13-F,SMLF,IC,BC000340Z30",,,D2010XF,7551.43,792.38,180.000,NO,,,
PJ09_P0_N,"Q_SHORT_SM-EMPTY,SHORT16",,,SHORT_10X12_M_FOR_INNER_LAYER,11985.67,16124.41,90.000,GEOMETRY,BODY_DOWN,DIRECT_ATTACH,IN4
PJ09_P0_P,"Q_SHORT_SM-EMPTY,SHORT16",,,SHORT_10X12_M_FOR_INNER_LAYER,11970.67,16124.41,90.000,GEOMETRY,BODY_DOWN,DIRECT_ATTACH,IN4
PJ09_P1_N,"Q_SHORT_SM-EMPTY,SHORT16",,,SHORT_10X12_M_FOR_INNER_LAYER,5442.60,15331.90,0.000,GEOMETRY,BODY_DOWN,DIRECT_ATTACH,IN6
PJ09_P1_P,"Q_SHORT_SM-EMPTY,SHORT16",,,SHORT_10X12_M_FOR_INNER_LAYER,5442.60,15346.90,0.000,GEOMETRY,BODY_DOWN,DIRECT_ATTACH,IN6
PJ38_NUT,"TP_TP-EMPTY,TP30",,,TP30,1693.39,-765.54,270.000,NO,,,
PJ1,"CONN3_210HP1030BR1-CONN3_210-HP1-030BR1,THLF,IO,DFA",,,HEADER1X3XG,15503.77,5813.53,270.000,NO,,,
PJ38,"SCONN21_9193031121LF-SCONN21_91930-31121LF,SMLF,IOA",,,CON_F21S2H2D2S_P1W4-22_LDH,7712.20,15085.06,180.000,NO,,,
PL7,"Q_INDUCTOR4P_14-150NH,SMLF,IND,CV+15^0TZ04",,,L_TLM117513Q-151QL_11X7-5XA,13849.76,13016.43,0.000,NO,,,
PL8,"Q_INDUCTOR4P_14-150NH,SMLF,IND,CV+15^0TZ04",,,L_TLM117513Q-151QL_11X7-5XA,2579.91,7017.55,180.000,NO,,,
PL9,"Q_INDUCTOR_SMLF-120NH/69A,IND,CV+12^0EZ03",120NH/69A,,L_VLBU6565100T-R12L-1_6-5X6-5,14145.59,13093.74,90.000,NO,,,
PL10,"Q_INDUCTOR4P_14-150NH,SMLF,IND,CV+15^0TZ04",,,L_TLM117513Q-151QL_11X7-5XA,13195.94,12821.12,0.000,NO,,,
PL11,"Q_INDUCTOR4P_14-150NH,SMLF,IND,CV+15^0TZ04",,,L_TLM117513Q-151QL_11X7-5XA,12866.90,12821.12,0.000,NO,,,
PL12,"Q_INDUCTOR_SMLF-50NH/86A,IND,CVA50^0MZ09",50NH/86A,,L_MSI-600607_6-1X6,13450.73,14017.85,90.000,NO,,,
PL13,"Q_INDUCTOR4P_14-150NH,SMLF,IND,CV+15^0TZ04",,,L_TLM117513Q-151QL_11X7-5XA,12158.03,13283.43,0.000,NO,,,
PL14,"Q_INDUCTOR4P_14-150NH,SMLF,IND,CV+15^0TZ04",,,L_TLM117513Q-151QL_11X7-5XA,12537.94,12821.97,0.000,NO,,,
PL15,"Q_INDUCTOR4P_14-150NH,SMLF,IND,CV+15^0TZ04",,,L_TLM117513Q-151QL_11X7-5XA,13520.90,12821.69,0.000,NO,,,
PL16,"Q_INDUCTOR_SMLF-0.22UH/33A,IND,CV+22Y0EZ00",0.22UH/33A,,L_VLBU6565100T-R12L-1_6-5X6-5,10547.12,13355.07,90.000,NO,,,
PL17,"Q_INDUCTOR4P_14-150NH,SMLF,IND,CV+15^0TZ04",,,L_TLM117513Q-151QL_11X7-5XA,11830.03,13283.43,0.000,NO,,,
PL18,"Q_INDUCTOR4P_14-150NH,SMLF,IND,CV+15^0TZ04",,,L_TLM117513Q-151QL_11X7-5XA,11501.03,13283.43,0.000,NO,,,
PL19,"Q_INDUCTOR_SMLF-50NH/86A,IND,CVA50^0MZ09",50NH/86A,,L_MSI-600607_6-1X6,11335.65,14189.77,90.000,NO,,,
PL20,"Q_INDUCTOR4P_14-150NH,SMLF,IND,CV+15^0TZ04",,,L_TLM117513Q-151QL_11X7-5XA,10848.03,13283.43,0.000,NO,,,
PL21,"Q_INDUCTOR4P_14-150NH,SMLF,IND,CV+15^0TZ04",,,L_TLM117513Q-151QL_11X7-5XA,11174.03,13283.43,0.000,NO,,,
PL22,"Q_INDUCTOR_SMLF-90NH/155A,IND,CVA90^0KZ13",90NH/155A,,L_HCME107512Q-900QL_10X7-7,17006.72,13476.66,270.000,NO,,,
PL23,"Q_INDUCTOR_SMLF-90NH/155A,IND,CVA90^0KZ13",90NH/155A,,L_HCME107512Q-900QL_10X7-7,16678.90,13475.66,270.000,NO,,,
PL24,"Q_INDUCTOR_SMLF-100NH/16A,IND,CV+10G0MZ04",100NH/16A,,L_HCBS4545_4-5X4-5,17283.31,14197.12,0.000,NO,,,
PL26,"Q_INDUCTOR_SMLF-BLM18SN220TN1D/8000MA,IND,CX220TN1A",BLM18SN220TN1D/8000MA,,L0603,3269.86,5987.94,180.000,NO,,,
PL27,"Q_INDUCTOR_SMLF-120NH/69A,IND,CV+12^0EZ03",120NH/69A,,L_VLBU6565100T-R12L-1_6-5X6-5,2279.57,6922.19,90.000,NO,,,
PL28,"Q_INDUCTOR4P_14-150NH,SMLF,IND,CV+15^0TZ04",,,L_TLM117513Q-151QL_11X7-5XA,3234.91,7561.46,180.000,NO,,,
PL29,"Q_INDUCTOR4P_14-150NH,SMLF,IND,CV+15^0TZ04",,,L_TLM117513Q-151QL_11X7-5XA,3565.51,7560.58,180.000,NO,,,
PL30,"Q_INDUCTOR_SMLF-50NH/86A,IND,CVA50^0MZ09",50NH/86A,,L_MSI-600607_6-1X6,3473.80,6261.02,270.000,NO,,,
PL31,"Q_INDUCTOR4P_14-150NH,SMLF,IND,CV+15^0TZ04",,,L_TLM117513Q-151QL_11X7-5XA,3895.91,7559.46,180.000,NO,,,
PL32,"Q_INDUCTOR4P_14-150NH,SMLF,IND,CV+15^0TZ04",,,L_TLM117513Q-151QL_11X7-5XA,4255.62,7381.61,180.000,NO,,,
PL33,"Q_INDUCTOR4P_14-150NH,SMLF,IND,CV+15^0TZ04",,,L_TLM117513Q-151QL_11X7-5XA,2907.21,7359.96,180.000,NO,,,
PL34,"Q_INDUCTOR_SMLF-0.22UH/33A,IND,CV+22Y0EZ00",0.22UH/33A,,L_VLBU6565100T-R12L-1_6-5X6-5,5537.87,6315.11,90.000,NO,,,
PL35,"Q_INDUCTOR4P_14-150NH,SMLF,IND,CV+15^0TZ04",,,L_TLM117513Q-151QL_11X7-5XA,4570.90,7135.46,180.000,NO,,,
PL36,"Q_INDUCTOR4P_14-150NH,SMLF,IND,CV+15^0TZ04",,,L_TLM117513Q-151QL_11X7-5XA,4894.62,6870.46,180.000,NO,,,
PL37,"Q_INDUCTOR_SMLF-50NH/86A,IND,CVA50^0MZ09",50NH/86A,,L_MSI-600607_6-1X6,4665.81,5838.23,270.000,NO,,,
PL38,"Q_INDUCTOR4P_14-150NH,SMLF,IND,CV+15^0TZ04",,,L_TLM117513Q-151QL_11X7-5XA,5220.62,6529.46,180.000,NO,,,
PL39,"Q_INDUCTOR_SMLF-120NH/69A,IND,CV+12^0EZ03",120NH/69A,,L_VLBU6565100T-R12L-1_6-5X6-5,4387.00,13099.73,90.000,NO,,,
PL40,"Q_INDUCTOR4P_14-150NH,SMLF,IND,CV+15^0TZ04",,,L_TLM117513Q-151QL_11X7-5XA,3434.65,12821.31,0.000,NO,,,
PL41,"Q_INDUCTOR4P_14-150NH,SMLF,IND,CV+15^0TZ04",,,L_TLM117513Q-151QL_11X7-5XA,3105.61,12821.31,0.000,NO,,,
PL42,"Q_INDUCTOR_SMLF-50NH/86A,IND,CVA50^0MZ09",50NH/86A,,L_MSI-600607_6-1X6,3562.51,13799.11,90.000,NO,,,
PL43,"Q_INDUCTOR4P_14-150NH,SMLF,IND,CV+15^0TZ04",,,L_TLM117513Q-151QL_11X7-5XA,2433.65,13283.62,0.000,NO,,,
PL44,"Q_INDUCTOR4P_14-150NH,SMLF,IND,CV+15^0TZ04",,,L_TLM117513Q-151QL_11X7-5XA,2776.65,12822.16,0.000,NO,,,
PL45,"Q_INDUCTOR4P_14-150NH,SMLF,IND,CV+15^0TZ04",,,L_TLM117513Q-151QL_11X7-5XA,3759.61,12821.88,0.000,NO,,,
PL46,"Q_INDUCTOR_SMLF-0.22UH/33A,IND,CV+22Y0EZ00",0.22UH/33A,,L_VLBU6565100T-R12L-1_6-5X6-5,829.74,13355.26,90.000,NO,,,
PL47,"Q_INDUCTOR4P_14-150NH,SMLF,IND,CV+15^0TZ04",,,L_TLM117513Q-151QL_11X7-5XA,2107.65,13283.62,0.000,NO,,,
PL48,"Q_INDUCTOR4P_14-150NH,SMLF,IND,CV+15^0TZ04",,,L_TLM117513Q-151QL_11X7-5XA,1781.65,13283.62,0.000,NO,,,
PL49,"Q_INDUCTOR_SMLF-50NH/86A,IND,CVA50^0MZ09",50NH/86A,,L_MSI-600607_6-1X6,1953.45,14174.24,90.000,NO,,,
PL50,"Q_INDUCTOR_SMLF-120NH/69A,IND,CV+12^0EZ03",120NH/69A,,L_VLBU6565100T-R12L-1_6-5X6-5,13392.22,6527.71,90.000,NO,,,
PL51,"Q_INDUCTOR4P_14-150NH,SMLF,IND,CV+15^0TZ04",,,L_TLM117513Q-151QL_11X7-5XA,14338.43,7365.69,180.000,NO,,,
PL52,"Q_INDUCTOR4P_14-150NH,SMLF,IND,CV+15^0TZ04",,,L_TLM117513Q-151QL_11X7-5XA,14667.61,7561.46,180.000,NO,,,
PL53,"Q_INDUCTOR_SMLF-50NH/86A,IND,CVA50^0MZ09",50NH/86A,,L_MSI-600607_6-1X6,14540.57,6295.58,270.000,NO,,,
PL54,"Q_INDUCTOR_SMLF-90NH/155A,IND,CVA90^0KZ13",90NH/155A,,L_HCME107512Q-900QL_10X7-7,7201.57,13482.77,270.000,NO,,,
PL55,"Q_INDUCTOR_SMLF-90NH/155A,IND,CVA90^0KZ13",90NH/155A,,L_HCME107512Q-900QL_10X7-7,7529.39,13483.77,270.000,NO,,,
PL56,"Q_INDUCTOR_SMLF-100NH/16A,IND,CV+10G0MZ04",100NH/16A,,L_HCBS4545_4-5X4-5,7215.34,14236.23,180.000,NO,,,
PL57,"Q_INDUCTOR_SMLF-1.0UH/18A,IND,CV-10I0MZ01",1.0UH/18A,,L_PCMC104T,2362.71,5944.08,180.000,NO,,,
PL59,"Q_INDUCTOR4P_14-150NH,SMLF,IND,CV+15^0TZ04",,,L_TLM117513Q-151QL_11X7-5XA,14998.43,7561.46,180.000,NO,,,
PL60,"Q_INDUCTOR4P_14-150NH,SMLF,IND,CV+15^0TZ04",,,L_TLM117513Q-151QL_11X7-5XA,15326.43,7561.46,180.000,NO,,,
PL61,"Q_INDUCTOR4P_14-150NH,SMLF,IND,CV+15^0TZ04",,,L_TLM117513Q-151QL_11X7-5XA,14012.43,7039.89,180.000,NO,,,
PL62,"Q_INDUCTOR_SMLF-0.22UH/33A,IND,CV+22Y0EZ00",0.22UH/33A,,L_VLBU6565100T-R12L-1_6-5X6-5,16641.27,6741.39,90.000,NO,,,
PL63,"Q_INDUCTOR4P_14-150NH,SMLF,IND,CV+15^0TZ04",,,L_TLM117513Q-151QL_11X7-5XA,15671.14,7342.06,180.000,NO,,,
PL64,"Q_INDUCTOR4P_14-150NH,SMLF,IND,CV+15^0TZ04",,,L_TLM117513Q-151QL_11X7-5XA,16002.44,7004.37,180.000,NO,,,
PL65,"Q_INDUCTOR_SMLF-50NH/86A,IND,CVA50^0MZ09",50NH/86A,,L_MSI-600607_6-1X6,15100.67,6093.38,180.000,NO,,,
PL66,"Q_INDUCTOR4P_14-150NH,SMLF,IND,CV+15^0TZ04",,,L_TLM117513Q-151QL_11X7-5XA,16330.43,6814.37,180.000,NO,,,
PL67,"Q_INDUCTOR4P_14-150NH,SMLF,IND,CV+15^0TZ04",,,L_TLM117513Q-151QL_11X7-5XA,1130.65,13283.62,0.000,NO,,,
PL68,"Q_INDUCTOR4P_14-150NH,SMLF,IND,CV+15^0TZ04",,,L_TLM117513Q-151QL_11X7-5XA,1456.65,13283.62,0.000,NO,,,
PL69,"Q_INDUCTOR4P_14-150NH,SMLF,IND,CV+15^0TZ04",,,L_TLM117513Q-151QL_11X7-5XA,4088.47,13016.62,0.000,NO,,,
PL70,"Q_INDUCTOR4P_14-150NH,SMLF,IND,CV+15^0TZ04",,,L_TLM117513Q-151QL_11X7-5XA,13688.61,6710.91,180.000,NO,,,
PL71,"Q_INDUCTOR_SMLF-BLM18SN220TN1D/8000MA,IND,CX220TN1A",BLM18SN220TN1D/8000MA,,L0603,8004.36,13641.93,180.000,NO,,,
PL72,"Q_INDUCTOR_SMLF-1.5UH,IND,CV-15I0MZ28",1.5UH,,L_PCMC063T,7912.80,13094.97,270.000,NO,,,
PL77,"Q_INDUCTOR_SMLF-BLM18SN220TN1D/8000MA,IND,CX220TN1A",BLM18SN220TN1D/8000MA,,L0603,13106.00,5187.23,0.000,NO,,,
PL78,"Q_INDUCTOR_SMLF-1.0UH/18A,IND,CV-10I0MZ01",1.0UH/18A,,L_PCMC104T,13221.65,5932.53,90.000,NO,,,
PL6000,"Q_INDUCTOR_SMLF-3.3UH/6A,IND,CV-3360MZ07",3.3UH/6A,,L_PCMC063T,5952.08,3061.14,0.000,NO,,,
PL6001,"Q_INDUCTOR_SMLF-2.2UH,IND,CV-2280MZ15",2.2UH,,L_PCMC063T,5082.08,2971.14,0.000,NO,,,
PL6002,"Q_INDUCTOR_SMLF-BLM18SN220TN1D/8000MA,IND,CX220TN1A",BLM18SN220TN1D/8000MA,,L0603,5432.08,3001.68,90.000,NO,,,
PL6003,"Q_INDUCTOR_SMLF-BLM18SN220TN1D/8000MA,IND,CX220TN1A",BLM18SN220TN1D/8000MA,,L0603,4559.68,2911.58,90.000,NO,,,
PL6500,"Q_INDUCTOR_SMLF-100NH/16A,IND,CV+10G0MZ04",100NH/16A,,L_HCBS4545_4-5X4-5,9782.25,10679.84,180.000,NO,,,
PL6501,"Q_INDUCTOR_SMLF-1UH,IND,CV-10U0MZ01",1UH,,L_PCMC135T,9565.04,11974.89,90.000,NO,,,
PL6502,"Q_INDUCTOR_SMLF-1UH,IND,CV-10U0MZ01",1UH,,L_PCMC135T,9016.50,11974.89,90.000,NO,,,
PL6503,"Q_INDUCTOR_SMLF-100NH/16A,IND,CV+10G0MZ04",100NH/16A,,L_HCBS4545_4-5X4-5,8874.82,10685.33,0.000,NO,,,
PL6504,"Q_INDUCTOR_SMLF-100NH/16A,IND,CV+10G0MZ04",100NH/16A,,L_HCBS4545_4-5X4-5,17799.81,16260.50,90.000,NO,,,
PL6505,"Q_INDUCTOR_SMLF-120NH/69A,IND,CV+12^0EZ03",120NH/69A,,L_VLBU6565100T-R12L-1_6-5X6-5,17584.04,15357.36,270.000,NO,,,
PL6506,"Q_INDUCTOR_SMLF-120NH/69A,IND,CV+12^0EZ03",120NH/69A,,L_VLBU6565100T-R12L-1_6-5X6-5,17869.79,15357.36,270.000,NO,,,
PL6510,"Q_INDUCTOR_SMLF-100NH/16A,IND,CV+10G0MZ04",100NH/16A,,L_HCBS4545_4-5X4-5,974.77,15850.39,90.000,NO,,,
PL6511,"Q_INDUCTOR_SMLF-120NH/69A,IND,CV+12^0EZ03",120NH/69A,,L_VLBU6565100T-R12L-1_6-5X6-5,711.21,15027.00,270.000,NO,,,
PL6512,"Q_INDUCTOR_SMLF-120NH/69A,IND,CV+12^0EZ03",120NH/69A,,L_VLBU6565100T-R12L-1_6-5X6-5,996.96,15027.00,270.000,NO,,,
PL8045,"Q_INDUCTOR_SMLF-100NH/16A,IND,CV+10G0MZ04",100NH/16A,,L_HCBS4545_4-5X4-5,17157.80,1772.64,90.000,NO,,,
PL8064,"Q_INDUCTOR_SMLF-BLM18SN220TN1D/8000MA,IND,CX220TN1A",BLM18SN220TN1D/8000MA,,L0603,16178.59,5259.62,0.000,NO,,,
PL8065,"Q_INDUCTOR_SMLF-4.7UH,IND,CV-47A0MZ10",4.7UH,,L_PCMB104EXB,16271.79,5939.33,90.000,NO,,,
PL8066,"Q_INDUCTOR_SMLF-1.5UH/53A,IND,CV-15^0MZ02",1.5UH/53A,,L_EM-15AM17VG1-QS_14-3X12-9,17957.96,2443.87,90.000,NO,,,
PPQ1,"MOSFET_NCH_1D3S-PSMNR58-30YLH,SMLF,IC,BAMNR580000",,,SOT1023,9514.02,15168.40,90.000,NO,,,
PPQ2,"MOSFET_NCH_1D3S-PSMNR58-30YLH,SMLF,IC,BAMNR580000",,,SOT1023,9747.68,15168.40,90.000,NO,,,
PPQ5,"MOSFET_NCH_1D3S-PSMNR58-30YLH,SMLF,IC,BAMNR580000",,,SOT1023,9981.34,15168.40,90.000,NO,,,
PPQ6,"MOSFET_NCH_1D3S-PSMNR58-30YLH,SMLF,IC,BAMNR580000",,,SOT1023,10215.00,15168.40,90.000,NO,,,
PPQ7,"MOSFET_NCH_1D3S-PSMNR58-30YLH,SMLF,IC,BAMNR580000",,,SOT1023,10448.66,15168.40,90.000,NO,,,
PPQ8,"MOSFET_NCH_1D3S-PSMNR58-30YLH,SMLF,IC,BAMNR580000",,,SOT1023,10682.32,15168.40,90.000,NO,,,
PPQ9,"MOSFET_NCH_1D3S-PSMNR58-30YLH,SMLF,IC,BAMNR580000",,,SOT1023,10915.98,15168.40,90.000,NO,,,
PQ10,"MOSFET_PCH_GDS_ESD_PROTECTED-PJA3415AE,SMLF,IC,BAMA",,,SOT23_GDSXC,11641.00,14450.00,0.000,NO,,,
PQ11,"MOSFET_PCH_GDS_ESD_PROTECTED-PJA3415AE,SMLF,IC,BAMA",,,SOT23_GDSXC,4222.71,5366.38,90.000,NO,,,
PQ12,"MOSFET_PCH_GDS_ESD_PROTECTED-PJA3415AE,SMLF,IC,BAMA",,,SOT23_GDSXC,770.00,14435.00,90.000,NO,,,
PQ13,"MOSFET_PCH_GDS_ESD_PROTECTED-PJA3415AE,SMLF,IC,BAMA",,,SOT23_GDSXC,14472.27,5728.18,270.000,YES,,,
PQ14,"MOSFET_N_SMLF-BSS138K,BSS138K,IC,BAM138K0000",,,SOT23_GDSXD,11484.49,14497.27,0.000,NO,,,
PQ15,"MOSFET_N_SMLF-BSS138K,BSS138K,IC,BAM138K0000",,,SOT23_GDSXD,3917.71,5361.38,0.000,NO,,,
PQ16,"MOSFET_N_SMLF-BSS138K,BSS138K,IC,BAM138K0000",,,SOT23_GDSXD,760.00,14230.00,90.000,NO,,,
PQ17,"MOSFET_N_SMLF-BSS138K,BSS138K,IC,BAM138K0000",,,SOT23_GDSXD,14472.27,5503.18,270.000,YES,,,
PR3,"Q_RES_0402LF-10K,1%,1/16W,CHIP,CS31002FB08",10K,1%,R0402,16593.94,14269.45,0.000,YES,,,
PR4,"Q_RES_0402LF-10K,1%,1/16W,CHIP,CS31002FB08",10K,1%,R0402,3891.57,5659.15,180.000,NO,,,
PR5,"Q_RES_0402LF-10K,1%,1/16W,CHIP,CS31002FB08",10K,1%,R0402,15022.57,5564.77,180.000,NO,,,
PR6,"Q_RES_0402LF-10K,1%,1/16W,CHIP,CS31002FB08",10K,1%,R0402,6469.51,13749.14,0.000,YES,,,
PR7,"Q_RES_0402LF-8.87K,1%,1/16W,EMPTY,CS28872FB01",8.87K,1%,R0402,13793.76,13588.43,0.000,NO,,,
PR8,"Q_RES_0402LF-8.66K,1%,1/16W,CHIP,CS28662FB02",8.66K,1%,R0402,2694.05,5835.35,270.000,NO,,,
PR12,"Q_RES_0402LF-0,5%,1/16W,CHIP,CS00002JB13",0,5%,R0402,1245.00,14235.00,270.000,YES,,,
PR13,"Q_RES_0402LF-0,5%,1/16W,CHIP,CS00002JB13",0,5%,R0402,6462.36,13549.37,270.000,NO,,,
PR14,"Q_RES_0402LF-0,5%,1/16W,CHIP,CS00002JB13",0,5%,R0402,6500.36,13549.37,270.000,NO,,,
PR32,"Q_RES_0402LF-0,5%,1/16W,CHIP,CS00002JB13",0,5%,R0402,12255.00,14100.00,270.000,YES,,,
PR33,"Q_RES_0402LF-0,5%,1/16W,CHIP,CS00002JB13",0,5%,R0402,16530.24,14082.21,270.000,NO,,,
PR34,"Q_RES_0402LF-0,5%,1/16W,CHIP,CS00002JB13",0,5%,R0402,16568.24,14082.21,270.000,NO,,,
PR35,"Q_RES_0402LF-0,5%,1/16W,CHIP,CS00002JB13",0,5%,R0402,16606.24,14082.21,270.000,NO,,,
PR36,"Q_RES_0402LF-0,5%,1/16W,CHIP,CS00002JB13",0,5%,R0402,16684.24,14082.21,270.000,NO,,,
PR37,"Q_RES_0402LF-0,5%,1/16W,CHIP,CS00002JB13",0,5%,R0402,16490.24,14082.21,270.000,NO,,,
PR40,"Q_RES_0402LF-0,5%,1/16W,CHIP,CS00002JB13",0,5%,R0402,11895.00,13965.00,180.000,NO,,,
PR41,"Q_RES_0402LF-1K,1%,1/16W,EMPTY,CS21002FB06",1K,1%,R0402,11895.00,13965.00,180.000,YES,,,
PR46,"Q_RES_0402LF-1.5,1%,1/8W,EMPTY,CS-1504FB00",1.5,1%,R0402,3056.62,7061.42,270.000,NO,,,
PR49,"Q_RES_0402LF-49.9,1%,1/16W,CHIP,CS04992FB07",49.9,1%,R0402,14091.90,12857.65,180.000,NO,,,
PR50,"Q_RES_0402LF-49.9,1%,1/16W,CHIP,CS04992FB07",49.9,1%,R0402,10591.46,13112.03,0.000,NO,,,
PR51,"Q_RES_0402LF-49.9,1%,1/16W,CHIP,CS04992FB07",49.9,1%,R0402,14091.90,12897.65,180.000,NO,,,
PR52,"Q_RES_0402LF-49.9,1%,1/16W,CHIP,CS04992FB07",49.9,1%,R0402,10591.46,13072.03,0.000,NO,,,
PR53,"Q_RES_0402LF-40.2K,1%,1/16W,CHIP,CS34022FB04",40.2K,1%,R0402,12568.59,14215.00,90.000,NO,,,
PR54,"Q_RES_0402LF-10K,1%,1/16W,CHIP,CS31002FB08",10K,1%,R0402,12528.59,14215.00,270.000,NO,,,
PR55,"Q_RES_0402LF-1K,1%,1/16W,CHIP,CS21002FB06",1K,1%,R0402,11617.75,14542.34,180.000,NO,,,
PR59,"Q_RES_0402LF-0,5%,1/16W,CHIP,CS00002JB13",0,5%,R0402,13443.91,12243.09,0.000,YES,,,
PR60,"Q_RES_0402LF-0,5%,1/16W,CHIP,CS00002JB13",0,5%,R0402,13352.32,12285.59,0.000,YES,,,
PR62,"Q_RES_0402LF-0,5%,1/16W,CHIP,CS00002JB13",0,5%,R0402,11985.00,13965.00,0.000,NO,,,
PR67,"Q_RES_0402LF-1.96K,1%,1/16W,CHIP,CS21962FB05",1.96K,1%,R0402,12305.00,14170.00,0.000,YES,,,
PR68,"Q_RES_0402LF-0,5%,1/16W,CHIP,CS00002JB13",0,5%,R0402,12080.00,13955.00,90.000,NO,,,
PR69,"Q_RES_0402LF-0,5%,1/16W,CHIP,CS00002JB13",0,5%,R0402,12470.00,14050.00,90.000,NO,,,
PR74,"Q_RES_0402LF-0,5%,1/16W,CHIP,CS00002JB13",0,5%,R0402,12530.00,14285.00,270.000,NO,,,
PR76,"Q_RES_0402LF-1,1%,1/16W,CHIP,CS-1002FB04",1,1%,R0402,12530.00,14355.00,90.000,NO,,,
PR77,"Q_RES_0402LF-8.87K,1%,1/16W,EMPTY,CS28872FB01",8.87K,1%,R0402,12810.90,13393.69,0.000,NO,,,
PR78,"Q_RES_0402LF-8.87K,1%,1/16W,EMPTY,CS28872FB01",8.87K,1%,R0402,13139.94,13393.12,0.000,NO,,,
PR79,"Q_RES_0402LF-2.2,1%,1/16W,CHIP,CS-2202FB01",2.2,1%,R0402,13100.32,13229.64,270.000,YES,,,
PR80,"Q_RES_0402LF-2.2,1%,1/16W,CHIP,CS-2202FB01",2.2,1%,R0402,12771.28,13230.21,270.000,YES,,,
PR81,"Q_RES_0402LF-5.6,1%,1/16W,CHIP,CS-5602FB01",5.6,1%,R0402,12892.15,13371.65,90.000,NO,,,
PR82,"Q_RES_0402LF-5.6,1%,1/16W,CHIP,CS-5602FB01",5.6,1%,R0402,13221.19,13371.08,90.000,NO,,,
PR83,"Q_RES_0402LF-0,5%,1/16W,CHIP,CS00002JB13",0,5%,R0402,12718.11,13293.44,270.000,YES,,,
PR84,"Q_RES_0402LF-0,5%,1/16W,CHIP,CS00002JB13",0,5%,R0402,13047.15,13292.87,270.000,YES,,,
PR85,"Q_RES_0402LF-8.87K,1%,1/16W,EMPTY,CS28872FB01",8.87K,1%,R0402,12102.03,13855.43,0.000,NO,,,
PR86,"Q_RES_0402LF-8.87K,1%,1/16W,EMPTY,CS28872FB01",8.87K,1%,R0402,12481.94,13393.97,0.000,NO,,,
PR87,"Q_RES_0402LF-2.2,1%,1/16W,CHIP,CS-2202FB01",2.2,1%,R0402,12062.41,13691.95,270.000,YES,,,
PR88,"Q_RES_0402LF-2.2,1%,1/16W,CHIP,CS-2202FB01",2.2,1%,R0402,12442.32,13230.49,270.000,YES,,,
PR89,"Q_RES_0402LF-5.6,1%,1/16W,CHIP,CS-5602FB01",5.6,1%,R0402,12183.28,13833.39,90.000,NO,,,
PR90,"Q_RES_0402LF-5.6,1%,1/16W,CHIP,CS-5602FB01",5.6,1%,R0402,12563.19,13371.93,90.000,NO,,,
PR91,"Q_RES_0402LF-0,5%,1/16W,CHIP,CS00002JB13",0,5%,R0402,12009.24,13755.18,270.000,YES,,,
PR92,"Q_RES_0402LF-0,5%,1/16W,CHIP,CS00002JB13",0,5%,R0402,12389.15,13293.72,270.000,YES,,,
PR93,"Q_RES_0402LF-8.87K,1%,1/16W,EMPTY,CS28872FB01",8.87K,1%,R0402,13467.94,13395.12,0.000,NO,,,
PR94,"Q_RES_0402LF-2.2,1%,1/16W,CHIP,CS-2202FB01",2.2,1%,R0402,13428.32,13231.64,270.000,YES,,,
PR95,"Q_RES_0402LF-5.6,1%,1/16W,CHIP,CS-5602FB01",5.6,1%,R0402,13549.19,13373.08,90.000,NO,,,
PR96,"Q_RES_0402LF-0,5%,1/16W,CHIP,CS00002JB13",0,5%,R0402,13375.15,13294.87,270.000,YES,,,
PR97,"Q_RES_0402LF-8.87K,1%,1/16W,EMPTY,CS28872FB01",8.87K,1%,R0402,11445.03,13855.43,0.000,NO,,,
PR98,"Q_RES_0402LF-8.87K,1%,1/16W,EMPTY,CS28872FB01",8.87K,1%,R0402,11774.03,13855.43,0.000,NO,,,
PR99,"Q_RES_0402LF-2.2,1%,1/16W,CHIP,CS-2202FB01",2.2,1%,R0402,11405.41,13691.95,270.000,YES,,,
PR100,"Q_RES_0402LF-2.2,1%,1/16W,CHIP,CS-2202FB01",2.2,1%,R0402,11734.41,13691.95,270.000,YES,,,
PR101,"Q_RES_0402LF-5.6,1%,1/16W,CHIP,CS-5602FB01",5.6,1%,R0402,11855.28,13833.39,90.000,NO,,,
PR102,"Q_RES_0402LF-5.6,1%,1/16W,CHIP,CS-5602FB01",5.6,1%,R0402,11526.28,13833.39,90.000,NO,,,
PR103,"Q_RES_0402LF-0,5%,1/16W,CHIP,CS00002JB13",0,5%,R0402,11681.24,13755.18,270.000,YES,,,
PR104,"Q_RES_0402LF-0,5%,1/16W,CHIP,CS00002JB13",0,5%,R0402,11352.24,13755.18,270.000,YES,,,
PR105,"Q_RES_0402LF-8.87K,1%,1/16W,EMPTY,CS28872FB01",8.87K,1%,R0402,10792.03,13855.43,0.000,NO,,,
PR106,"Q_RES_0402LF-8.87K,1%,1/16W,EMPTY,CS28872FB01",8.87K,1%,R0402,11118.03,13855.43,0.000,NO,,,
PR107,"Q_RES_0402LF-2.2,1%,1/16W,CHIP,CS-2202FB01",2.2,1%,R0402,10752.41,13691.95,270.000,YES,,,
PR108,"Q_RES_0402LF-2.2,1%,1/16W,CHIP,CS-2202FB01",2.2,1%,R0402,11078.41,13691.95,270.000,YES,,,
PR109,"Q_RES_0402LF-5.6,1%,1/16W,CHIP,CS-5602FB01",5.6,1%,R0402,10873.28,13833.39,90.000,NO,,,
PR110,"Q_RES_0402LF-5.6,1%,1/16W,CHIP,CS-5602FB01",5.6,1%,R0402,11199.28,13833.39,90.000,NO,,,
PR111,"Q_RES_0402LF-0,5%,1/16W,CHIP,CS00002JB13",0,5%,R0402,11025.24,13755.18,270.000,YES,,,
PR112,"Q_RES_0402LF-0,5%,1/16W,CHIP,CS00002JB13",0,5%,R0402,10699.24,13755.18,270.000,YES,,,
PR113,"Q_RES_0402LF-40.2K,1%,1/16W,CHIP,CS34022FB04",40.2K,1%,R0402,16718.37,14266.86,0.000,YES,,,
PR114,"Q_RES_0402LF-49.9,1%,1/16W,CHIP,CS04992FB07",49.9,1%,R0402,16363.33,13118.74,180.000,NO,,,
PR115,"Q_RES_0402LF-49.9,1%,1/16W,CHIP,CS04992FB07",49.9,1%,R0402,16363.33,13068.74,0.000,NO,,,
PR121,"Q_RES_0402LF-0,5%,1/16W,CHIP,CS00002JB13",0,5%,R0402,16343.27,14079.40,90.000,NO,,,
PR125,"Q_RES_0402LF-0,5%,1/16W,CHIP,CS00002JB13",0,5%,R0402,16810.00,14415.00,270.000,NO,,,
PR126,"Q_RES_0402LF-3.09K,1%,1/16W,CHIP,CS23092FB04",3.09K,1%,R0402,16678.42,14205.67,0.000,NO,,,
PR127,"Q_RES_0402LF-0,5%,1/16W,EMPTY,CS00002JB13",0,5%,R0402,16298.26,14229.41,270.000,YES,,,
PR128,"Q_RES_0402LF-1K,1%,1/16W,EMPTY,CS21002FB06",1K,1%,R0402,16312.03,14283.66,180.000,NO,,,
PR129,"Q_RES_0402LF-0,5%,1/16W,EMPTY,CS00002JB13",0,5%,R0402,16312.03,14244.66,180.000,NO,,,
PR130,"Q_RES_0402LF-1,1%,1/16W,CHIP,CS-1002FB04",1,1%,R0402,16701.47,14401.49,90.000,NO,,,
PR131,"Q_RES_0402LF-2.2,1%,1/16W,CHIP,CS-2202FB01",2.2,1%,R0402,16587.92,13865.12,270.000,YES,,,
PR132,"Q_RES_0402LF-2.2,1%,1/16W,CHIP,CS-2202FB01",2.2,1%,R0402,16915.74,13866.12,270.000,YES,,,
PR133,"Q_RES_0402LF-4.87K,1%,1/16W,EMPTY,CS24872FB01",4.87K,1%,R0402,16627.54,14028.60,180.000,NO,,,
PR134,"Q_RES_0402LF-4.87K,1%,1/16W,EMPTY,CS24872FB01",4.87K,1%,R0402,16955.36,14029.60,180.000,NO,,,
PR135,"Q_RES_0402LF-5.6,1%,1/16W,CHIP,CS-5602FB01",5.6,1%,R0402,16708.79,14004.66,90.000,NO,,,
PR136,"Q_RES_0402LF-5.6,1%,1/16W,CHIP,CS-5602FB01",5.6,1%,R0402,17036.61,14005.66,90.000,NO,,,
PR137,"Q_RES_0402LF-0,5%,1/16W,CHIP,CS00002JB13",0,5%,R0402,16534.75,13928.35,270.000,YES,,,
PR138,"Q_RES_0402LF-0,5%,1/16W,CHIP,CS00002JB13",0,5%,R0402,16862.57,13929.35,270.000,YES,,,
PR147,"Q_RES_0402LF-10K,1%,1/16W,CHIP,CS31002FB08",10K,1%,R0402,2853.01,5851.78,179.946,NO,,,
PR148,"Q_RES_0402LF-20K,1%,1/16W,CHIP,CS32002FB06",20K,1%,R0402,2852.91,5812.98,180.000,NO,,,
PR150,"Q_RES_0402LF-0,5%,1/16W,CHIP,CS00002JB13",0,5%,R0402,3471.57,5913.35,0.000,YES,,,
PR151,"Q_RES_0402LF-1K,1%,1/16W,EMPTY,CS21002FB06",1K,1%,R0402,3575.57,5904.15,180.000,NO,,,
PR152,"Q_RES_0402LF-1K,1%,1/16W,CHIP,CS21002FB06",1K,1%,R0402,4127.71,5326.38,90.000,NO,,,
PR155,"Q_RES_0402LF-1.5,1%,1/8W,EMPTY,CS-1504FB00",1.5,1%,R0402,13700.35,13314.97,90.000,NO,,,
PR157,"Q_RES_0402LF-40.2K,1%,1/16W,CHIP,CS34022FB04",40.2K,1%,R0402,4013.71,5614.15,180.000,NO,,,
PR158,"Q_RES_0402LF-1.5,1%,1/8W,EMPTY,CS-1504FB00",1.5,1%,R0402,13374.53,13121.66,90.000,NO,,,
PR159,"Q_RES_0402LF-5.23K,1%,1/16W,CHIP,CS25232FB08",5.23K,1%,R0402,3889.57,5711.15,180.000,NO,,,
PR161,"Q_RES_0402LF-49.9,1%,1/16W,CHIP,CS04992FB07",49.9,1%,R0402,2342.43,7158.23,180.000,NO,,,
PR162,"Q_RES_0402LF-49.9,1%,1/16W,CHIP,CS04992FB07",49.9,1%,R0402,2342.86,7116.02,0.000,NO,,,
PR163,"Q_RES_0402LF-49.9,1%,1/16W,CHIP,CS04992FB07",49.9,1%,R0402,5457.37,6636.89,0.000,NO,,,
PR164,"Q_RES_0402LF-49.9,1%,1/16W,CHIP,CS04992FB07",49.9,1%,R0402,5457.37,6594.89,180.000,NO,,,
PR169,"Q_RES_0402LF-0,5%,1/16W,CHIP,CS00002JB13",0,5%,R0402,5702.16,7660.12,90.000,NO,,,
PR170,"Q_RES_0402LF-0,5%,1/16W,CHIP,CS00002JB13",0,5%,R0402,5752.16,7660.12,90.000,NO,,,
PR172,"Q_RES_0402LF-0,5%,1/16W,CHIP,CS00002JB13",0,5%,R0402,3551.57,5904.15,180.000,YES,,,
PR173,"Q_RES_0402LF-0,5%,1/16W,CHIP,CS00002JB13",0,5%,R0402,3620.73,5959.71,90.000,YES,,,
PR174,"Q_RES_0402LF-0,5%,1/16W,CHIP,CS00002JB13",0,5%,R0402,4031.57,5774.15,0.000,YES,,,
PR181,"Q_RES_0402LF-0,5%,1/16W,CHIP,CS00002JB13",0,5%,R0402,4013.71,5559.15,180.000,NO,,,
PR183,"Q_RES_0402LF-1,1%,1/16W,CHIP,CS-1002FB04",1,1%,R0402,4036.57,5509.15,90.000,YES,,,
PR185,"Q_RES_0402LF-2.2,1%,1/16W,CHIP,CS-2202FB01",2.2,1%,R0402,3330.53,7152.94,90.000,YES,,,
PR186,"Q_RES_0402LF-2.2,1%,1/16W,CHIP,CS-2202FB01",2.2,1%,R0402,3661.13,7150.26,90.000,YES,,,
PR187,"Q_RES_0402LF-8.87K,1%,1/16W,EMPTY,CS28872FB01",8.87K,1%,R0402,3290.91,6989.46,0.000,NO,,,
PR188,"Q_RES_0402LF-8.87K,1%,1/16W,EMPTY,CS28872FB01",8.87K,1%,R0402,3621.51,6986.78,0.000,NO,,,
PR189,"Q_RES_0402LF-5.6,1%,1/16W,CHIP,CS-5602FB01",5.6,1%,R0402,3209.66,7011.50,270.000,NO,,,
PR190,"Q_RES_0402LF-5.6,1%,1/16W,CHIP,CS-5602FB01",5.6,1%,R0402,3540.26,7008.82,270.000,NO,,,
PR191,"Q_RES_0402LF-0,5%,1/16W,CHIP,CS00002JB13",0,5%,R0402,3383.70,7089.71,90.000,YES,,,
PR192,"Q_RES_0402LF-0,5%,1/16W,CHIP,CS00002JB13",0,5%,R0402,3714.30,7087.03,90.000,YES,,,
PR193,"Q_RES_0402LF-2.2,1%,1/16W,CHIP,CS-2202FB01",2.2,1%,R0402,3991.53,7150.94,90.000,YES,,,
PR194,"Q_RES_0402LF-2.2,1%,1/16W,CHIP,CS-2202FB01",2.2,1%,R0402,4321.53,6972.94,90.000,YES,,,
PR195,"Q_RES_0402LF-8.87K,1%,1/16W,EMPTY,CS28872FB01",8.87K,1%,R0402,3951.91,6987.46,0.000,NO,,,
PR196,"Q_RES_0402LF-8.87K,1%,1/16W,EMPTY,CS28872FB01",8.87K,1%,R0402,4281.91,6809.46,0.000,NO,,,
PR197,"Q_RES_0402LF-5.6,1%,1/16W,CHIP,CS-5602FB01",5.6,1%,R0402,3870.66,7009.50,270.000,NO,,,
PR198,"Q_RES_0402LF-5.6,1%,1/16W,CHIP,CS-5602FB01",5.6,1%,R0402,4200.66,6831.50,270.000,NO,,,
PR199,"Q_RES_0402LF-0,5%,1/16W,CHIP,CS00002JB13",0,5%,R0402,4044.70,7087.71,90.000,YES,,,
PR200,"Q_RES_0402LF-0,5%,1/16W,CHIP,CS00002JB13",0,5%,R0402,4374.70,6909.71,90.000,YES,,,
PR201,"Q_RES_0402LF-2.2,1%,1/16W,CHIP,CS-2202FB01",2.2,1%,R0402,3002.83,6951.44,90.000,YES,,,
PR202,"Q_RES_0402LF-8.87K,1%,1/16W,EMPTY,CS28872FB01",8.87K,1%,R0402,2963.21,6787.96,0.000,NO,,,
PR203,"Q_RES_0402LF-5.6,1%,1/16W,CHIP,CS-5602FB01",5.6,1%,R0402,2881.96,6810.00,270.000,NO,,,
PR204,"Q_RES_0402LF-0,5%,1/16W,CHIP,CS00002JB13",0,5%,R0402,3056.00,6888.21,90.000,YES,,,
PR205,"Q_RES_0402LF-2.2,1%,1/16W,CHIP,CS-2202FB01",2.2,1%,R0402,4645.53,6726.94,90.000,YES,,,
PR206,"Q_RES_0402LF-2.2,1%,1/16W,CHIP,CS-2202FB01",2.2,1%,R0402,4971.53,6461.94,90.000,YES,,,
PR207,"Q_RES_0402LF-8.87K,1%,1/16W,EMPTY,CS28872FB01",8.87K,1%,R0402,4605.91,6563.46,0.000,NO,,,
PR208,"Q_RES_0402LF-8.87K,1%,1/16W,EMPTY,CS28872FB01",8.87K,1%,R0402,4931.91,6298.46,0.000,NO,,,
PR209,"Q_RES_0402LF-5.6,1%,1/16W,CHIP,CS-5602FB01",5.6,1%,R0402,4524.66,6585.50,270.000,NO,,,
PR210,"Q_RES_0402LF-5.6,1%,1/16W,CHIP,CS-5602FB01",5.6,1%,R0402,4850.66,6320.50,270.000,NO,,,
PR211,"Q_RES_0402LF-0,5%,1/16W,CHIP,CS00002JB13",0,5%,R0402,4698.70,6663.71,90.000,YES,,,
PR212,"Q_RES_0402LF-0,5%,1/16W,CHIP,CS00002JB13",0,5%,R0402,5024.70,6398.71,90.000,YES,,,
PR213,"Q_RES_0402LF-2.2,1%,1/16W,CHIP,CS-2202FB01",2.2,1%,R0402,5304.53,6120.94,90.000,YES,,,
PR214,"Q_RES_0402LF-8.87K,1%,1/16W,EMPTY,CS28872FB01",8.87K,1%,R0402,5264.91,5957.46,0.000,NO,,,
PR215,"Q_RES_0402LF-5.6,1%,1/16W,CHIP,CS-5602FB01",5.6,1%,R0402,5183.66,5979.50,270.000,NO,,,
PR216,"Q_RES_0402LF-0,5%,1/16W,CHIP,CS00002JB13",0,5%,R0402,5357.70,6057.71,90.000,YES,,,
PR217,"Q_RES_0402LF-0,5%,1/16W,CHIP,CS00002JB13",0,5%,R0402,885.00,14080.00,180.000,NO,,,
PR218,"Q_RES_0402LF-1K,1%,1/16W,EMPTY,CS21002FB06",1K,1%,R0402,885.00,14080.00,180.000,YES,,,
PR221,"Q_RES_0402LF-1.5,1%,1/8W,EMPTY,CS-1504FB00",1.5,1%,R0402,11680.62,13581.97,90.000,NO,,,
PR223,"Q_RES_0402LF-1.5,1%,1/8W,EMPTY,CS-1504FB00",1.5,1%,R0402,11351.62,13581.97,90.000,NO,,,
PR226,"Q_RES_0402LF-49.9,1%,1/16W,CHIP,CS04992FB07",49.9,1%,R0402,4327.51,12896.94,180.000,NO,,,
PR227,"Q_RES_0402LF-49.9,1%,1/16W,CHIP,CS04992FB07",49.9,1%,R0402,885.55,13074.99,0.000,NO,,,
PR228,"Q_RES_0402LF-49.9,1%,1/16W,CHIP,CS04992FB07",49.9,1%,R0402,4327.51,12856.94,180.000,NO,,,
PR229,"Q_RES_0402LF-49.9,1%,1/16W,CHIP,CS04992FB07",49.9,1%,R0402,6726.00,13125.02,180.000,NO,,,
PR230,"Q_RES_0402LF-40.2K,1%,1/16W,CHIP,CS34022FB04",40.2K,1%,R0402,1390.00,14250.00,0.000,YES,,,
PR231,"Q_RES_0402LF-10K,1%,1/16W,CHIP,CS31002FB08",10K,1%,R0402,1360.00,14290.00,0.000,YES,,,
PR232,"Q_RES_0402LF-1K,1%,1/16W,CHIP,CS21002FB06",1K,1%,R0402,750.00,14340.00,180.000,NO,,,
PR236,"Q_RES_0402LF-0,5%,1/16W,CHIP,CS00002JB13",0,5%,R0402,3612.71,12149.88,90.000,YES,,,
PR237,"Q_RES_0402LF-0,5%,1/16W,CHIP,CS00002JB13",0,5%,R0402,3572.71,12149.88,90.000,YES,,,
PR239,"Q_RES_0402LF-0,5%,1/16W,CHIP,CS00002JB13",0,5%,R0402,975.00,14080.00,0.000,NO,,,
PR244,"Q_RES_0402LF-9.53K,1%,1/16W,CHIP,CS29532FB06",9.53K,1%,R0402,1285.00,14365.00,0.000,YES,,,
PR245,"Q_RES_0402LF-0,5%,1/16W,CHIP,CS00002JB13",0,5%,R0402,1070.00,14090.00,90.000,NO,,,
PR246,"Q_RES_0402LF-0,5%,1/16W,CHIP,CS00002JB13",0,5%,R0402,1480.00,14160.00,90.000,NO,,,
PR251,"Q_RES_0402LF-0,5%,1/16W,CHIP,CS00002JB13",0,5%,R0402,1510.00,14440.00,90.000,NO,,,
PR253,"Q_RES_0402LF-1,1%,1/16W,CHIP,CS-1002FB04",1,1%,R0402,1490.28,14506.12,90.000,NO,,,
PR254,"Q_RES_0402LF-8.87K,1%,1/16W,EMPTY,CS28872FB01",8.87K,1%,R0402,3049.61,13393.88,0.000,NO,,,
PR255,"Q_RES_0402LF-8.87K,1%,1/16W,EMPTY,CS28872FB01",8.87K,1%,R0402,3378.65,13393.31,0.000,NO,,,
PR256,"Q_RES_0402LF-2.2,1%,1/16W,CHIP,CS-2202FB01",2.2,1%,R0402,3339.03,13229.83,270.000,YES,,,
PR257,"Q_RES_0402LF-2.2,1%,1/16W,CHIP,CS-2202FB01",2.2,1%,R0402,3009.99,13230.40,270.000,YES,,,
PR258,"Q_RES_0402LF-5.6,1%,1/16W,CHIP,CS-5602FB01",5.6,1%,R0402,3459.90,13371.27,90.000,NO,,,
PR259,"Q_RES_0402LF-5.6,1%,1/16W,CHIP,CS-5602FB01",5.6,1%,R0402,3130.86,13371.84,90.000,NO,,,
PR260,"Q_RES_0402LF-0,5%,1/16W,CHIP,CS00002JB13",0,5%,R0402,2956.82,13293.63,270.000,YES,,,
PR261,"Q_RES_0402LF-0,5%,1/16W,CHIP,CS00002JB13",0,5%,R0402,3285.86,13293.06,270.000,YES,,,
PR262,"Q_RES_0402LF-8.87K,1%,1/16W,EMPTY,CS28872FB01",8.87K,1%,R0402,2384.65,13855.62,0.000,NO,,,
PR263,"Q_RES_0402LF-8.87K,1%,1/16W,EMPTY,CS28872FB01",8.87K,1%,R0402,2720.65,13394.16,0.000,NO,,,
PR264,"Q_RES_0402LF-2.2,1%,1/16W,CHIP,CS-2202FB01",2.2,1%,R0402,2345.03,13692.14,270.000,YES,,,
PR265,"Q_RES_0402LF-2.2,1%,1/16W,CHIP,CS-2202FB01",2.2,1%,R0402,2681.03,13230.68,270.000,YES,,,
PR266,"Q_RES_0402LF-5.6,1%,1/16W,CHIP,CS-5602FB01",5.6,1%,R0402,2465.90,13833.58,90.000,NO,,,
PR267,"Q_RES_0402LF-5.6,1%,1/16W,CHIP,CS-5602FB01",5.6,1%,R0402,2801.90,13372.12,90.000,NO,,,
PR268,"Q_RES_0402LF-0,5%,1/16W,CHIP,CS00002JB13",0,5%,R0402,2291.86,13755.37,270.000,YES,,,
PR269,"Q_RES_0402LF-0,5%,1/16W,CHIP,CS00002JB13",0,5%,R0402,2627.86,13293.91,270.000,YES,,,
PR270,"Q_RES_0402LF-8.87K,1%,1/16W,EMPTY,CS28872FB01",8.87K,1%,R0402,3706.65,13395.31,0.000,NO,,,
PR271,"Q_RES_0402LF-2.2,1%,1/16W,CHIP,CS-2202FB01",2.2,1%,R0402,3667.03,13231.83,270.000,YES,,,
PR272,"Q_RES_0402LF-5.6,1%,1/16W,CHIP,CS-5602FB01",5.6,1%,R0402,3787.90,13373.27,90.000,NO,,,
PR273,"Q_RES_0402LF-0,5%,1/16W,CHIP,CS00002JB13",0,5%,R0402,3613.86,13295.06,270.000,YES,,,
PR274,"Q_RES_0402LF-8.87K,1%,1/16W,EMPTY,CS28872FB01",8.87K,1%,R0402,1727.65,13855.62,0.000,NO,,,
PR275,"Q_RES_0402LF-8.87K,1%,1/16W,EMPTY,CS28872FB01",8.87K,1%,R0402,2056.65,13855.62,0.000,NO,,,
PR276,"Q_RES_0402LF-2.2,1%,1/16W,CHIP,CS-2202FB01",2.2,1%,R0402,1688.03,13692.14,270.000,YES,,,
PR277,"Q_RES_0402LF-2.2,1%,1/16W,CHIP,CS-2202FB01",2.2,1%,R0402,2017.03,13692.14,270.000,YES,,,
PR278,"Q_RES_0402LF-5.6,1%,1/16W,CHIP,CS-5602FB01",5.6,1%,R0402,1808.90,13833.58,90.000,NO,,,
PR279,"Q_RES_0402LF-5.6,1%,1/16W,CHIP,CS-5602FB01",5.6,1%,R0402,2137.90,13833.58,90.000,NO,,,
PR280,"Q_RES_0402LF-0,5%,1/16W,CHIP,CS00002JB13",0,5%,R0402,1963.86,13755.37,270.000,YES,,,
PR281,"Q_RES_0402LF-0,5%,1/16W,CHIP,CS00002JB13",0,5%,R0402,1634.86,13755.37,270.000,YES,,,
PR283,"Q_RES_0402LF-0,5%,1/16W,CHIP,CS00002JB13",0,5%,R0402,14602.57,5809.77,0.000,YES,,,
PR284,"Q_RES_0402LF-1K,1%,1/16W,EMPTY,CS21002FB06",1K,1%,R0402,14682.57,5809.77,180.000,NO,,,
PR285,"Q_RES_0402LF-1K,1%,1/16W,CHIP,CS21002FB06",1K,1%,R0402,14470.27,5613.18,180.000,YES,,,
PR288,"Q_RES_0402LF-49.9,1%,1/16W,CHIP,CS04992FB07",49.9,1%,R0402,6726.00,13080.02,0.000,NO,,,
PR290,"Q_RES_0402LF-40.2K,1%,1/16W,CHIP,CS34022FB04",40.2K,1%,R0402,15122.57,5519.77,180.000,NO,,,
PR291,"Q_RES_0402LF-1.5,1%,1/8W,EMPTY,CS-1504FB00",1.5,1%,R0402,10698.62,13581.97,90.000,NO,,,
PR292,"Q_RES_0402LF-681,1%,1/16W,CHIP,CS16812FB02",681,1%,R0402,15023.57,5616.77,180.000,NO,,,
PR294,"Q_RES_0402LF-49.9,1%,1/16W,CHIP,CS04992FB07",49.9,1%,R0402,13447.96,6783.93,180.000,NO,,,
PR295,"Q_RES_0402LF-49.9,1%,1/16W,CHIP,CS04992FB07",49.9,1%,R0402,13447.60,6744.43,0.000,NO,,,
PR296,"Q_RES_0402LF-49.9,1%,1/16W,CHIP,CS04992FB07",49.9,1%,R0402,16581.66,6963.18,0.000,NO,,,
PR297,"Q_RES_0402LF-49.9,1%,1/16W,CHIP,CS04992FB07",49.9,1%,R0402,16581.48,6923.28,180.000,NO,,,
PR302,"Q_RES_0402LF-0,5%,1/16W,CHIP,CS00002JB13",0,5%,R0402,14452.87,8476.52,180.000,YES,,,
PR303,"Q_RES_0402LF-0,5%,1/16W,CHIP,CS00002JB13",0,5%,R0402,14513.03,8436.52,180.000,YES,,,
PR305,"Q_RES_0402LF-0,5%,1/16W,CHIP,CS00002JB13",0,5%,R0402,14682.57,5809.77,180.000,YES,,,
PR306,"Q_RES_0402LF-0,5%,1/16W,CHIP,CS00002JB13",0,5%,R0402,14754.73,5868.33,90.000,YES,,,
PR307,"Q_RES_0402LF-0,5%,1/16W,CHIP,CS00002JB13",0,5%,R0402,15162.57,5679.77,0.000,YES,,,
PR314,"Q_RES_0402LF-0,5%,1/16W,CHIP,CS00002JB13",0,5%,R0402,15122.57,5479.77,180.000,NO,,,
PR316,"Q_RES_0402LF-1,1%,1/16W,CHIP,CS-1002FB04",1,1%,R0402,15167.57,5414.77,90.000,YES,,,
PR318,"Q_RES_0402LF-2.2,1%,1/16W,CHIP,CS-2202FB01",2.2,1%,R0402,14434.05,6957.17,90.000,YES,,,
PR319,"Q_RES_0402LF-2.2,1%,1/16W,CHIP,CS-2202FB01",2.2,1%,R0402,14763.23,7152.94,90.000,YES,,,
PR320,"Q_RES_0402LF-8.87K,1%,1/16W,EMPTY,CS28872FB01",8.87K,1%,R0402,14394.43,6793.69,0.000,NO,,,
PR321,"Q_RES_0402LF-8.87K,1%,1/16W,EMPTY,CS28872FB01",8.87K,1%,R0402,14723.61,6989.46,0.000,NO,,,
PR322,"Q_RES_0402LF-5.6,1%,1/16W,CHIP,CS-5602FB01",5.6,1%,R0402,14313.18,6815.73,270.000,NO,,,
PR323,"Q_RES_0402LF-5.6,1%,1/16W,CHIP,CS-5602FB01",5.6,1%,R0402,14642.36,7011.50,270.000,NO,,,
PR324,"Q_RES_0402LF-0,5%,1/16W,CHIP,CS00002JB13",0,5%,R0402,14487.22,6893.94,90.000,YES,,,
PR325,"Q_RES_0402LF-0,5%,1/16W,CHIP,CS00002JB13",0,5%,R0402,14816.40,7089.71,90.000,YES,,,
PR326,"Q_RES_0402LF-2.2,1%,1/16W,CHIP,CS-2202FB01",2.2,1%,R0402,7110.59,13872.23,270.000,YES,,,
PR327,"Q_RES_0402LF-2.2,1%,1/16W,CHIP,CS-2202FB01",2.2,1%,R0402,7438.41,13873.23,270.000,YES,,,
PR328,"Q_RES_0402LF-4.87K,1%,1/16W,EMPTY,CS24872FB07",4.87K,1%,R0402,7150.21,14035.71,180.000,NO,,,
PR329,"Q_RES_0402LF-4.87K,1%,1/16W,EMPTY,CS24872FB07",4.87K,1%,R0402,7478.03,14036.71,180.000,NO,,,
PR330,"Q_RES_0402LF-5.6,1%,1/16W,CHIP,CS-5602FB01",5.6,1%,R0402,7231.46,14011.77,90.000,NO,,,
PR331,"Q_RES_0402LF-5.6,1%,1/16W,CHIP,CS-5602FB01",5.6,1%,R0402,7559.28,14012.77,90.000,NO,,,
PR332,"Q_RES_0402LF-0,5%,1/16W,CHIP,CS00002JB13",0,5%,R0402,7057.42,13935.46,270.000,YES,,,
PR333,"Q_RES_0402LF-0,5%,1/16W,CHIP,CS00002JB13",0,5%,R0402,7385.24,13936.46,270.000,YES,,,
PR334,"Q_RES_0402LF-1K,1%,1/16W,CHIP,CS21002FB06",1K,1%,R0402,16551.47,6783.08,90.000,YES,,,
PR335,"Q_RES_0402LF-0,5%,1/16W,CHIP,CS00002JB13",0,5%,R0402,5433.71,5969.28,270.000,NO,,,
PR336,"Q_RES_0402LF-0,5%,1/16W,EMPTY,CS00002JB13",0,5%,R0402,5395.03,5969.16,270.000,NO,,,
PR337,"Q_RES_0402LF-1K,1%,1/16W,CHIP,CS21002FB06",1K,1%,R0402,2348.27,6980.73,90.000,YES,,,
PR339,"Q_RES_0402LF-1K,1%,1/16W,CHIP,CS21002FB06",1K,1%,R0402,5446.51,6494.38,90.000,YES,,,
PR340,"Q_RES_0402LF-0,5%,1/16W,CHIP,CS00002JB13",0,5%,R0402,947.13,13843.37,90.000,NO,,,
PR341,"Q_RES_0402LF-0,5%,1/16W,EMPTY,CS00002JB13",0,5%,R0402,906.01,13842.89,90.000,NO,,,
PR342,"Q_RES_0402LF-1K,1%,1/16W,CHIP,CS21002FB06",1K,1%,R0402,4306.91,13047.44,270.000,YES,,,
PR344,"Q_RES_0402LF-2.2,1%,1/16W,CHIP,CS-2202FB01",2.2,1%,R0402,15094.05,7152.94,90.000,YES,,,
PR345,"Q_RES_0402LF-2.2,1%,1/16W,CHIP,CS-2202FB01",2.2,1%,R0402,15422.05,7152.94,90.000,YES,,,
PR346,"Q_RES_0402LF-8.87K,1%,1/16W,EMPTY,CS28872FB01",8.87K,1%,R0402,15054.43,6989.46,0.000,NO,,,
PR347,"Q_RES_0402LF-8.87K,1%,1/16W,EMPTY,CS28872FB01",8.87K,1%,R0402,15382.43,6989.46,0.000,NO,,,
PR348,"Q_RES_0402LF-5.6,1%,1/16W,CHIP,CS-5602FB01",5.6,1%,R0402,14973.18,7011.50,270.000,NO,,,
PR349,"Q_RES_0402LF-5.6,1%,1/16W,CHIP,CS-5602FB01",5.6,1%,R0402,15301.18,7011.50,270.000,NO,,,
PR350,"Q_RES_0402LF-0,5%,1/16W,CHIP,CS00002JB13",0,5%,R0402,15147.22,7089.71,90.000,YES,,,
PR351,"Q_RES_0402LF-0,5%,1/16W,CHIP,CS00002JB13",0,5%,R0402,15475.22,7089.71,90.000,YES,,,
PR352,"Q_RES_0402LF-2.2,1%,1/16W,CHIP,CS-2202FB01",2.2,1%,R0402,14108.05,6631.37,90.000,YES,,,
PR353,"Q_RES_0402LF-8.87K,1%,1/16W,EMPTY,CS28872FB01",8.87K,1%,R0402,14068.43,6467.89,0.000,NO,,,
PR354,"Q_RES_0402LF-5.6,1%,1/16W,CHIP,CS-5602FB01",5.6,1%,R0402,13987.18,6489.93,270.000,NO,,,
PR355,"Q_RES_0402LF-0,5%,1/16W,CHIP,CS00002JB13",0,5%,R0402,14161.22,6568.14,90.000,YES,,,
PR356,"Q_RES_0402LF-2.2,1%,1/16W,CHIP,CS-2202FB01",2.2,1%,R0402,15753.35,6933.54,90.000,YES,,,
PR357,"Q_RES_0402LF-2.2,1%,1/16W,CHIP,CS-2202FB01",2.2,1%,R0402,16081.05,6595.85,90.000,YES,,,
PR358,"Q_RES_0402LF-8.87K,1%,1/16W,EMPTY,CS28872FB01",8.87K,1%,R0402,15713.73,6770.06,0.000,NO,,,
PR359,"Q_RES_0402LF-8.87K,1%,1/16W,EMPTY,CS28872FB01",8.87K,1%,R0402,16041.43,6432.37,0.000,NO,,,
PR360,"Q_RES_0402LF-5.6,1%,1/16W,CHIP,CS-5602FB01",5.6,1%,R0402,15632.48,6792.10,270.000,NO,,,
PR361,"Q_RES_0402LF-5.6,1%,1/16W,CHIP,CS-5602FB01",5.6,1%,R0402,15960.18,6454.41,270.000,NO,,,
PR362,"Q_RES_0402LF-0,5%,1/16W,CHIP,CS00002JB13",0,5%,R0402,15806.52,6870.31,90.000,YES,,,
PR363,"Q_RES_0402LF-0,5%,1/16W,CHIP,CS00002JB13",0,5%,R0402,16134.22,6532.62,90.000,YES,,,
PR364,"Q_RES_0402LF-2.2,1%,1/16W,CHIP,CS-2202FB01",2.2,1%,R0402,16411.05,6405.85,90.000,YES,,,
PR365,"Q_RES_0402LF-8.87K,1%,1/16W,EMPTY,CS28872FB01",8.87K,1%,R0402,16371.43,6242.37,0.000,NO,,,
PR366,"Q_RES_0402LF-5.6,1%,1/16W,CHIP,CS-5602FB01",5.6,1%,R0402,16290.18,6264.41,270.000,NO,,,
PR367,"Q_RES_0402LF-0,5%,1/16W,CHIP,CS00002JB13",0,5%,R0402,16464.22,6342.62,90.000,YES,,,
PR368,"Q_RES_0402LF-8.87K,1%,1/16W,EMPTY,CS28872FB01",8.87K,1%,R0402,1074.65,13855.62,0.000,NO,,,
PR369,"Q_RES_0402LF-8.87K,1%,1/16W,EMPTY,CS28872FB01",8.87K,1%,R0402,1400.65,13855.62,0.000,NO,,,
PR370,"Q_RES_0402LF-2.2,1%,1/16W,CHIP,CS-2202FB01",2.2,1%,R0402,1035.03,13692.14,270.000,YES,,,
PR371,"Q_RES_0402LF-2.2,1%,1/16W,CHIP,CS-2202FB01",2.2,1%,R0402,1361.03,13692.14,270.000,YES,,,
PR372,"Q_RES_0402LF-5.6,1%,1/16W,CHIP,CS-5602FB01",5.6,1%,R0402,1155.90,13833.58,90.000,NO,,,
PR373,"Q_RES_0402LF-5.6,1%,1/16W,CHIP,CS-5602FB01",5.6,1%,R0402,1481.90,13833.58,90.000,NO,,,
PR374,"Q_RES_0402LF-0,5%,1/16W,CHIP,CS00002JB13",0,5%,R0402,1307.86,13755.37,270.000,YES,,,
PR375,"Q_RES_0402LF-0,5%,1/16W,CHIP,CS00002JB13",0,5%,R0402,981.86,13755.37,270.000,YES,,,
PR376,"Q_RES_0402LF-40.2K,1%,1/16W,CHIP,CS34022FB04",40.2K,1%,R0402,6611.67,13768.36,0.000,YES,,,
PR378,"Q_RES_0402LF-1K,1%,1/16W,CHIP,CS21002FB06",1K,1%,R0402,928.26,13310.55,270.000,YES,,,
PR379,"Q_RES_0402LF-1.5,1%,1/8W,EMPTY,CS-1504FB00",1.5,1%,R0402,11024.62,13581.97,90.000,NO,,,
PR384,"Q_RES_0402LF-0,5%,1/16W,CHIP,CS00002JB13",0,5%,R0402,6267.03,13516.84,90.000,NO,,,
PR387,"Q_RES_0402LF-0,5%,1/16W,CHIP,CS00002JB13",0,5%,R0402,6977.31,13935.38,90.000,NO,,,
PR388,"Q_RES_0402LF-0,5%,1/16W,CHIP,CS00002JB13",0,5%,R0402,6611.67,13808.36,0.000,YES,,,
PR389,"Q_RES_0402LF-1.5,1%,1/8W,EMPTY,CS-1504FB00",1.5,1%,R0402,16861.95,13756.14,90.000,NO,,,
PR390,"Q_RES_0402LF-0,5%,1/16W,EMPTY,CS00002JB13",0,5%,R0402,6296.33,13687.52,180.000,YES,,,
PR391,"Q_RES_0402LF-1K,1%,1/16W,EMPTY,CS21002FB06",1K,1%,R0402,6208.13,13750.82,180.000,NO,,,
PR392,"Q_RES_0402LF-0,5%,1/16W,EMPTY,CS00002JB13",0,5%,R0402,6208.13,13711.82,180.000,NO,,,
PR393,"Q_RES_0402LF-1,1%,1/16W,CHIP,CS-1002FB04",1,1%,R0402,6518.77,13868.90,90.000,NO,,,
PR394,"Q_RES_0402LF-0,5%,1/16W,EMPTY,CS00002JB13",0,5%,R0402,7016.61,13935.68,90.000,NO,,,
PR395,"Q_RES_0402LF-1K,1%,1/16W,CHIP,CS21002FB06",1K,1%,R0402,6986.99,13473.70,90.000,NO,,,
PR397,"Q_RES_0402LF-0,5%,1/16W,CHIP,CS00002JB13",0,5%,R0402,2973.15,5844.54,270.000,YES,,,
PR398,"Q_RES_0402LF-0,5%,1/16W,CHIP,CS00002JB13",0,5%,R0402,2730.69,5835.70,90.000,NO,,,
PR399,"Q_RES_0402LF-49.9,1%,1/16W,CHIP,CS04992FB07",49.9,1%,R0402,2328.17,5655.77,270.000,NO,,,
PR400,"Q_RES_0402LF-10,1%,1/16W,CHIP,CS01002FB07",10,1%,R0402,2852.91,5703.98,0.000,NO,,,
PR401,"Q_RES_0402LF-0,5%,1/16W,CHIP,CS00002JB13",0,5%,R0402,2784.26,5703.98,180.000,NO,,,
PR402,"Q_RES_0402LF-49.9,1%,1/16W,CHIP,CS04992FB07",49.9,1%,R0402,2286.75,5656.09,270.000,NO,,,
PR403,"Q_RES_0402LF-1K,1%,1/16W,CHIP,CS21002FB06",1K,1%,R0402,2306.33,5839.48,180.000,YES,,,
PR406,"Q_RES_0402LF-0,5%,1/16W,CHIP,CS00002JB13",0,5%,R0402,6384.36,13549.37,270.000,NO,,,
PR407,"Q_RES_0402LF-0,5%,1/16W,CHIP,CS00002JB13",0,5%,R0402,6424.36,13549.37,270.000,NO,,,
PR408,"Q_RES_0402LF-0,5%,1/16W,CHIP,CS00002JB13",0,5%,R0402,6538.36,13549.37,270.000,NO,,,
PR409,"Q_RES_0402LF-0,5%,1/16W,CHIP,CS00002JB13",0,5%,R0402,6578.36,13549.37,270.000,NO,,,
PR410,"Q_RES_0402LF-1K,1%,1/16W,CHIP,CS21002FB06",1K,1%,R0402,10639.68,13312.09,270.000,YES,,,
PR411,"Q_RES_0402LF-0,5%,1/16W,CHIP,CS00002JB13",0,5%,R0402,16491.97,13927.68,90.000,NO,,,
PR412,"Q_RES_0402LF-0,5%,1/16W,CHIP,CS00002JB13",0,5%,R0402,16555.70,14162.84,0.000,YES,,,
PR413,"Q_RES_0402LF-0,5%,1/16W,EMPTY,CS00002JB13",0,5%,R0402,16451.55,13928.20,90.000,NO,,,
PR414,"Q_RES_0402LF-1K,1%,1/16W,CHIP,CS21002FB06",1K,1%,R0402,16801.47,13095.58,90.000,YES,,,
PR415,"Q_RES_0402LF-0,5%,1/16W,CHIP,CS00002JB13",0,5%,R0402,6469.51,13707.89,0.000,YES,,,
PR416,"Q_RES_0402LF-2.2,1%,1/16W,CHIP,CS-2202FB01",2.2,1%,R0402,13754.14,13424.95,270.000,YES,,,
PR417,"Q_RES_0402LF-0,5%,1/16W,CHIP,CS00002JB13",0,5%,R0402,13057.58,5565.45,0.000,NO,,,
PR418,"Q_RES_0402LF-49.9,1%,1/16W,CHIP,CS04992FB07",49.9,1%,R0402,12933.34,5928.71,180.000,NO,,,
PR419,"Q_RES_0402LF-0,5%,1/16W,CHIP,CS00002JB13",0,5%,R0402,16644.24,14082.21,270.000,NO,,,
PR420,"Q_RES_0402LF-5.6,1%,1/16W,CHIP,CS-5602FB01",5.6,1%,R0402,13875.01,13566.39,90.000,NO,,,
PR421,"Q_RES_0402LF-0,5%,1/16W,CHIP,CS00002JB13",0,5%,R0402,13700.97,13488.18,270.000,YES,,,
PR422,"Q_RES_0402LF-2.2,1%,1/16W,CHIP,CS-2202FB01",2.2,1%,R0402,2675.53,6609.03,90.000,YES,,,
PR423,"Q_RES_0402LF-8.87K,1%,1/16W,EMPTY,CS28872FB01",8.87K,1%,R0402,2635.91,6445.55,0.000,NO,,,
PR424,"Q_RES_0402LF-5.6,1%,1/16W,CHIP,CS-5602FB01",5.6,1%,R0402,2554.66,6467.59,270.000,NO,,,
PR425,"Q_RES_0402LF-0,5%,1/16W,CHIP,CS00002JB13",0,5%,R0402,2728.70,6545.80,90.000,YES,,,
PR426,"Q_RES_0402LF-8.87K,1%,1/16W,EMPTY,CS28872FB01",8.87K,1%,R0402,4032.47,13588.62,0.000,NO,,,
PR427,"Q_RES_0402LF-2.2,1%,1/16W,CHIP,CS-2202FB01",2.2,1%,R0402,3992.85,13425.14,270.000,YES,,,
PR428,"Q_RES_0402LF-5.6,1%,1/16W,CHIP,CS-5602FB01",5.6,1%,R0402,4113.72,13566.58,90.000,NO,,,
PR429,"Q_RES_0402LF-0,5%,1/16W,CHIP,CS00002JB13",0,5%,R0402,3939.68,13488.37,270.000,YES,,,
PR430,"Q_RES_0402LF-2.2,1%,1/16W,CHIP,CS-2202FB01",2.2,1%,R0402,13781.05,6302.37,90.000,YES,,,
PR431,"Q_RES_0402LF-8.87K,1%,1/16W,EMPTY,CS28872FB01",8.87K,1%,R0402,13741.43,6138.89,0.000,NO,,,
PR432,"Q_RES_0402LF-5.6,1%,1/16W,CHIP,CS-5602FB01",5.6,1%,R0402,13660.18,6160.93,270.000,NO,,,
PR433,"Q_RES_0402LF-0,5%,1/16W,CHIP,CS00002JB13",0,5%,R0402,13834.22,6239.14,90.000,YES,,,
PR434,"Q_RES_0402LF-10,1%,1/16W,CHIP,CS01002FB07",10,1%,R0402,12927.86,5468.23,270.000,NO,,,
PR435,"Q_RES_0402LF-0,5%,1/16W,CHIP,CS00002JB13",0,5%,R0402,12961.56,5574.48,90.000,NO,,,
PR436,"Q_RES_0402LF-0,5%,1/16W,CHIP,CS00002JB13",0,5%,R0402,3854.43,5933.03,270.000,YES,,,
PR437,"Q_RES_0402LF-0,5%,1/16W,CHIP,CS00002JB13",0,5%,R0402,3894.43,5933.03,270.000,YES,,,
PR438,"Q_RES_0402LF-49.9,1%,1/16W,CHIP,CS04992FB07",49.9,1%,R0402,12933.66,5970.13,0.000,NO,,,
PR439,"Q_RES_0402LF-1K,1%,1/16W,CHIP,CS21002FB06",1K,1%,R0402,13078.24,5950.11,90.000,YES,,,
PR440,"Q_RES_0402LF-0,5%,1/16W,CHIP,CS00002JB13",0,5%,R0402,14985.43,5838.65,270.000,YES,,,
PR441,"Q_RES_0402LF-0,5%,1/16W,CHIP,CS00002JB13",0,5%,R0402,15025.43,5838.65,270.000,YES,,,
PR442,"Q_RES_0402LF-0,5%,1/16W,CHIP,CS00002JB13",0,5%,R0402,10624.05,13840.18,90.000,NO,,,
PR443,"Q_RES_0402LF-0,5%,1/16W,EMPTY,CS00002JB13",0,5%,R0402,10663.63,13840.50,90.000,NO,,,
PR444,"Q_RES_0402LF-1K,1%,1/16W,CHIP,CS21002FB06",1K,1%,R0402,14056.86,13047.58,270.000,YES,,,
PR445,"Q_RES_0402LF-0,5%,1/16W,CHIP,CS00002JB13",0,5%,R0402,16541.47,6204.98,270.000,NO,,,
PR446,"Q_RES_0402LF-0,5%,1/16W,EMPTY,CS00002JB13",0,5%,R0402,16499.79,6205.46,270.000,NO,,,
PR447,"Q_RES_0402LF-1K,1%,1/16W,CHIP,CS21002FB06",1K,1%,R0402,13467.17,6678.88,90.000,YES,,,
PR448,"Q_RES_0402LF-8.66K,1%,1/16W,CHIP,CS28662FB02",8.66K,1%,R0402,13057.23,5602.09,180.000,NO,,,
PR452,"Q_RES_0402LF-6.98K,1%,1/16W,CHIP,CS26982FB08",6.98K,1%,R0402,8058.64,13363.34,0.000,NO,,,
PR454,"Q_RES_0402LF-12.4K,1%,1/16W,CHIP,CS31242FB02",12.4K,1%,R0402,8044.56,13467.53,269.946,NO,,,
PR455,"Q_RES_0402LF-56K,1%,1/16W,CHIP,CS35602FB00",56K,1%,R0402,8085.26,13467.53,270.000,NO,,,
PR460,"Q_RES_0402LF-49.9,1%,1/16W,CHIP,CS04992FB07",49.9,1%,R0402,885.75,13116.19,0.000,NO,,,
PR464,"Q_RES_0402LF-13.7K,1%,1/16W,CHIP,CS31372FB03",13.7K,1%,R0402,6572.54,13672.83,180.000,NO,,,
PR470,"Q_RES_0402LF-10K,1%,1/16W,CHIP,CS31002FB08",10K,1%,R0402,13037.66,5468.13,89.946,NO,,,
PR471,"Q_RES_0402LF-20K,1%,1/16W,CHIP,CS32002FB06",20K,1%,R0402,12999.86,5468.23,90.000,NO,,,
PR477,"Q_RES_0402LF-0,5%,1/16W,CHIP,CS00002JB13",0,5%,R0402,13056.66,5373.03,180.000,YES,,,
PR482,"Q_RES_0402LF-1.5,1%,1/8W,EMPTY,CS-1504FB00",1.5,1%,R0402,16534.13,13755.14,90.000,NO,,,
PR485,"Q_RES_0402LF-1.5,1%,1/8W,EMPTY,CS-1504FB00",1.5,1%,R0402,3384.32,7262.92,270.000,NO,,,
PR486,"Q_RES_0402LF-1.5,1%,1/8W,EMPTY,CS-1504FB00",1.5,1%,R0402,3714.92,7260.24,270.000,NO,,,
PR488,"Q_RES_0402LF-1.5,1%,1/8W,EMPTY,CS-1504FB00",1.5,1%,R0402,1963.24,13582.16,90.000,NO,,,
PR489,"Q_RES_0402LF-1.5,1%,1/8W,EMPTY,CS-1504FB00",1.5,1%,R0402,1634.24,13582.16,90.000,NO,,,
PR491,"Q_RES_0402LF-1.5,1%,1/8W,EMPTY,CS-1504FB00",1.5,1%,R0402,981.24,13582.16,90.000,NO,,,
PR492,"Q_RES_0402LF-1.5,1%,1/8W,EMPTY,CS-1504FB00",1.5,1%,R0402,1307.24,13582.16,90.000,NO,,,
PR495,"Q_RES_0402LF-1.5,1%,1/8W,EMPTY,CS-1504FB00",1.5,1%,R0402,14487.84,7067.15,270.000,NO,,,
PR496,"Q_RES_0402LF-1.5,1%,1/8W,EMPTY,CS-1504FB00",1.5,1%,R0402,14817.02,7262.92,270.000,NO,,,
PR498,"Q_RES_0402LF-1.5,1%,1/8W,EMPTY,CS-1504FB00",1.5,1%,R0402,15147.84,7262.92,270.000,NO,,,
PR499,"Q_RES_0402LF-1.5,1%,1/8W,EMPTY,CS-1504FB00",1.5,1%,R0402,15475.84,7262.92,270.000,NO,,,
PR500,"Q_RES_0402LF-1.5,1%,1/8W,EMPTY,CS-1504FB00",1.5,1%,R0402,13834.84,6412.35,270.000,NO,,,
PR501,"Q_RES_0402LF-1.5,1%,1/8W,EMPTY,CS-1504FB00",1.5,1%,R0402,14161.84,6741.35,270.000,NO,,,
PR502,"Q_RES_0402LF-1.5,1%,1/8W,EMPTY,CS-1504FB00",1.5,1%,R0402,15807.14,7043.52,270.000,NO,,,
PR503,"Q_RES_0402LF-1.5,1%,1/8W,EMPTY,CS-1504FB00",1.5,1%,R0402,16134.84,6705.83,270.000,NO,,,
PR505,"Q_RES_0402LF-1.5,1%,1/8W,EMPTY,CS-1504FB00",1.5,1%,R0402,16464.84,6515.83,270.000,NO,,,
PR506,"Q_RES_0402LF-1.5,1%,1/8W,EMPTY,CS-1504FB00",1.5,1%,R0402,13046.53,13119.66,90.000,NO,,,
PR507,"Q_RES_0402LF-1.5,1%,1/8W,EMPTY,CS-1504FB00",1.5,1%,R0402,12717.49,13120.23,90.000,NO,,,
PR509,"Q_RES_0402LF-1.5,1%,1/8W,EMPTY,CS-1504FB00",1.5,1%,R0402,12008.62,13581.97,90.000,NO,,,
PR510,"Q_RES_0402LF-1.5,1%,1/8W,EMPTY,CS-1504FB00",1.5,1%,R0402,12388.53,13120.51,90.000,NO,,,
PR511,"Q_RES_0402LF-1.5,1%,1/8W,EMPTY,CS-1504FB00",1.5,1%,R0402,5358.32,6230.92,270.000,NO,,,
PR512,"Q_RES_0402LF-1.5,1%,1/8W,EMPTY,CS-1504FB00",1.5,1%,R0402,3285.24,13119.85,90.000,NO,,,
PR513,"Q_RES_0402LF-1.5,1%,1/8W,EMPTY,CS-1504FB00",1.5,1%,R0402,2956.20,13120.42,90.000,NO,,,
PR515,"Q_RES_0402LF-1.5,1%,1/8W,EMPTY,CS-1504FB00",1.5,1%,R0402,2291.24,13582.16,90.000,NO,,,
PR516,"Q_RES_0402LF-1.5,1%,1/8W,EMPTY,CS-1504FB00",1.5,1%,R0402,2627.24,13120.70,90.000,NO,,,
PR517,"Q_RES_0402LF-1.5,1%,1/8W,EMPTY,CS-1504FB00",1.5,1%,R0402,3613.24,13121.85,90.000,NO,,,
PR518,"Q_RES_0402LF-1.5,1%,1/8W,EMPTY,CS-1504FB00",1.5,1%,R0402,3939.06,13315.16,90.000,NO,,,
PR519,"Q_RES_0402LF-1.5,1%,1/8W,EMPTY,CS-1504FB00",1.5,1%,R0402,7384.62,13763.25,90.000,NO,,,
PR520,"Q_RES_0402LF-1.5,1%,1/8W,EMPTY,CS-1504FB00",1.5,1%,R0402,7056.80,13762.25,90.000,NO,,,
PR522,"Q_RES_0402LF-1.5,1%,1/8W,EMPTY,CS-1504FB00",1.5,1%,R0402,4045.32,7260.92,270.000,NO,,,
PR523,"Q_RES_0402LF-1.5,1%,1/8W,EMPTY,CS-1504FB00",1.5,1%,R0402,4375.32,7082.92,270.000,NO,,,
PR524,"Q_RES_0402LF-1.5,1%,1/8W,EMPTY,CS-1504FB00",1.5,1%,R0402,2729.32,6719.01,270.000,NO,,,
PR525,"Q_RES_0402LF-1.5,1%,1/8W,EMPTY,CS-1504FB00",1.5,1%,R0402,4699.32,6836.92,270.000,NO,,,
PR526,"Q_RES_0402LF-1.5,1%,1/8W,EMPTY,CS-1504FB00",1.5,1%,R0402,5025.32,6571.92,270.000,NO,,,
PR530,"Q_RES_0402LF-0,5%,1/16W,CHIP,CS00002JB13",0,5%,R0402,3814.43,5933.03,270.000,YES,,,
PR531,"Q_RES_0402LF-0,5%,1/16W,CHIP,CS00002JB13",0,5%,R0402,14945.43,5838.65,270.000,YES,,,
PR532,"Q_RES_0402LF-0,5%,1/16W,CHIP,CS00002JB13",0,5%,R0402,12310.00,14100.00,270.000,YES,,,
PR533,"Q_RES_0402LF-0,5%,1/16W,CHIP,CS00002JB13",0,5%,R0402,1300.00,14235.00,270.000,YES,,,
PR599,"Q_RES_0402LF-4.99K,1%,1/16W,EMPTY,CS24992FB07",4.99K,1%,R0402,15122.57,5439.77,0.000,NO,,,
PR600,"Q_RES_0402LF-4.99K,1%,1/16W,EMPTY,CS24992FB07",4.99K,1%,R0402,12490.00,14285.00,90.000,NO,,,
PR601,"Q_RES_0402LF-4.99K,1%,1/16W,EMPTY,CS24992FB07",4.99K,1%,R0402,16810.00,14350.00,270.000,NO,,,
PR602,"Q_RES_0402LF-4.99K,1%,1/16W,EMPTY,CS24992FB07",4.99K,1%,R0402,4013.71,5519.15,0.000,NO,,,
PR603,"Q_RES_0402LF-4.99K,1%,1/16W,EMPTY,CS24992FB07",4.99K,1%,R0402,1470.00,14440.00,270.000,NO,,,
PR604,"Q_RES_0402LF-4.99K,1%,1/16W,EMPTY,CS24992FB07",4.99K,1%,R0402,6469.51,13809.53,0.000,YES,,,
PR830,"Q_RES_0402LF-15K,0.1%,1/16W,CHIP,CS31502BB03",15K,0.1%,R0402,18005.11,1821.44,270.000,NO,,,
PR831,"Q_RES_0402LF-47K,0.1%,1/16W,CHIP,CS34702BB05",47K,0.1%,R0402,17970.11,1821.44,270.000,NO,,,
PR832,"Q_RES_0402LF-0,5%,1/16W,CHIP,CS00002JB13",0,5%,R0402,18041.11,1821.44,270.000,NO,,,
PR833,"Q_RES_0402LF-1.5K,1%,1/16W,EMPTY,CS21502FB07",1.5K,1%,R0402,17898.11,1821.44,270.000,NO,,,
PR834,"Q_RES_0402LF-21.5K,1%,1/16W,CHIP,CS32152FB04",21.5K,1%,R0402,18077.11,1821.44,270.000,NO,,,
PR835,"Q_RES_0402LF-0,5%,1/16W,CHIP,CS00002JB13",0,5%,R0402,17800.75,1943.99,180.000,NO,,,
PR836,"Q_RES_0402LF-1K,1%,1/16W,CHIP,CS21002FB06",1K,1%,R0402,17825.04,1824.63,180.000,NO,,,
PR883,"Q_RES_0402LF-0,5%,1/16W,EMPTY,CS00002JB13",0,5%,R0402,17284.63,16589.65,0.000,YES,,,
PR885,"Q_RES_0402LF-5.36K,1%,1/16W,EMPTY,CS25362FB02",5.36K,1%,R0402,466.67,16254.05,180.000,YES,,,
PR1101,"Q_RES_0402LF-2K,0.1%,1/16W,CHIP,CS22002BB07",2K,0.1%,R0402,8061.50,15826.33,180.000,NO,,,
PR1131,"Q_RES_0402LF-2K,0.1%,1/16W,CHIP,CS22002BB07",2K,0.1%,R0402,7036.10,15725.23,180.000,NO,,,
PR1133,"Q_RES_0402LF-2K,0.1%,1/16W,CHIP,CS22002BB07",2K,0.1%,R0402,7036.10,15685.23,180.000,NO,,,
PR1134,"Q_RES_0402LF-120K,1%,1/16W,CHIP,CS41202FB05",120K,1%,R0402,8061.50,16026.33,180.000,NO,,,
PR2106,"Q_RES_0402LF-10K,1%,1/16W,CHIP,CS31002FB08",10K,1%,R0402,7035.00,16005.00,0.000,NO,,,
PR2149,"Q_RES_0402LF-0,5%,1/16W,CHIP,CS00002JB13",0,5%,R0402,7036.10,15885.23,180.000,NO,,,
PR2510,"Q_RES_0402LF-1,1%,1/16W,CHIP,CS-1002FB04",1,1%,R0402,8207.14,14868.76,0.000,YES,,,
PR2511,"Q_RES_0402LF-1,1%,1/16W,CHIP,CS-1002FB04",1,1%,R0402,8207.14,15162.84,0.000,YES,,,
PR2512,"Q_RES_0402LF-1,1%,1/16W,CHIP,CS-1002FB04",1,1%,R0402,8207.14,14968.76,0.000,YES,,,
PR2513,"Q_RES_0402LF-1,1%,1/16W,CHIP,CS-1002FB04",1,1%,R0402,8207.14,15062.84,0.000,YES,,,
PR2514,"Q_RES_0402LF-10,1%,1/16W,CHIP,CS01002FB07",10,1%,R0402,8207.14,15262.84,0.000,YES,,,
PR2515,"Q_RES_0402LF-10,1%,1/16W,CHIP,CS01002FB07",10,1%,R0402,8207.14,14908.76,0.000,YES,,,
PR2516,"Q_RES_0402LF-10,1%,1/16W,CHIP,CS01002FB07",10,1%,R0402,8207.14,15202.84,0.000,YES,,,
PR2517,"Q_RES_0402LF-10,1%,1/16W,CHIP,CS01002FB07",10,1%,R0402,8207.14,15008.76,0.000,YES,,,
PR2518,"Q_RES_0402LF-10,1%,1/16W,CHIP,CS01002FB07",10,1%,R0402,8207.14,15102.84,0.000,YES,,,
PR2519,"Q_RES_0402LF-100,1%,1/16W,CHIP,CS11002FB07",100,1%,R0402,8207.14,15302.84,0.000,YES,,,
PR2520,"Q_RES_0402LF-1,1%,1/16W,CHIP,CS-1002FB04",1,1%,R0402,8127.14,14868.76,180.000,YES,,,
PR2521,"Q_RES_0402LF-1,1%,1/16W,CHIP,CS-1002FB04",1,1%,R0402,8127.14,15162.84,180.000,YES,,,
PR2522,"Q_RES_0402LF-1,1%,1/16W,CHIP,CS-1002FB04",1,1%,R0402,8127.14,14968.76,180.000,YES,,,
PR2523,"Q_RES_0402LF-1,1%,1/16W,CHIP,CS-1002FB04",1,1%,R0402,8127.14,15062.84,180.000,YES,,,
PR2524,"Q_RES_0402LF-10,1%,1/16W,CHIP,CS01002FB07",10,1%,R0402,8127.14,14908.76,180.000,YES,,,
PR2525,"Q_RES_0402LF-10,1%,1/16W,CHIP,CS01002FB07",10,1%,R0402,8127.14,15202.84,180.000,YES,,,
PR2526,"Q_RES_0402LF-10,1%,1/16W,CHIP,CS01002FB07",10,1%,R0402,8127.14,15008.76,180.000,YES,,,
PR2527,"Q_RES_0402LF-10,1%,1/16W,CHIP,CS01002FB07",10,1%,R0402,8127.14,15102.84,180.000,YES,,,
PR2528,"Q_RES_0402LF-10,1%,1/16W,CHIP,CS01002FB07",10,1%,R0402,10072.09,14986.95,0.000,NO,,,
PR2529,"Q_RES_0402LF-10,1%,1/16W,CHIP,CS01002FB07",10,1%,R0402,10305.75,14986.95,0.000,NO,,,
PR2530,"Q_RES_0402LF-10,1%,1/16W,CHIP,CS01002FB07",10,1%,R0402,10539.41,14986.95,0.000,NO,,,
PR2531,"Q_RES_0402LF-10,1%,1/16W,CHIP,CS01002FB07",10,1%,R0402,10773.07,14986.95,0.000,NO,,,
PR2532,"Q_SP_RES4P-0.0003,1%,4W,SMLF,CHIP,SP_CS0000FFT09",,,R2725_4P,10558.96,15508.40,270.000,NO,,,
PR2533,"Q_SP_RES4P-0.0003,1%,4W,SMLF,CHIP,SP_CS0000FFT09",,,R2725_4P,9926.96,15508.40,270.000,NO,,,
PR2534,"Q_SP_RES4P-0.0003,1%,4W,SMLF,CHIP,SP_CS0000FFT09",,,R2725_4P,10242.96,15508.40,270.000,NO,,,
PR2535,"Q_RES_0402LF-10,1%,1/16W,CHIP,CS01002FB07",10,1%,R0402,9604.77,14986.95,0.000,NO,,,
PR2536,"Q_RES_0402LF-10,1%,1/16W,CHIP,CS01002FB07",10,1%,R0402,9838.43,14986.95,0.000,NO,,,
PR2537,"Q_RES_0402LF-10,1%,1/16W,EMPTY,CS01002FB07",10,1%,R0402,9555.23,15097.77,180.000,YES,,,
PR2538,"Q_RES_0402LF-10,1%,1/16W,CHIP,CS01002FB07",10,1%,R0402,11006.73,14986.95,0.000,NO,,,
PR3002,"Q_RES_0402LF-0,5%,1/16W,CHIP,CS00002JB13",0,5%,R0402,7036.10,15805.23,0.000,NO,,,
PR3337,"Q_RES_0402LF-0,5%,1/16W,CHIP,CS00002JB13",0,5%,R0402,16089.44,5567.30,0.000,YES,,,
PR3780,"Q_RES_0402LF-5.36K,1%,1/16W,CHIP,CS25362FB02",5.36K,1%,R0402,17011.24,4296.75,90.000,NO,,,
PR3781,"Q_RES_0402LF-845,1%,1/16W,CHIP,CS18452FB01",845,1%,R0402,17625.48,871.07,180.000,NO,,,
PR3782,"Q_RES_0402LF-10,1%,1/16W,CHIP,CS01002FB07",10,1%,R0402,3673.15,2153.61,0.000,NO,,,
PR3786,"Q_RES_0402LF-160K,1%,1/16W,CHIP,CS41602FB05",160K,1%,R0402,17620.38,726.37,0.000,NO,,,
PR3787,"Q_RES_0402LF-6.8K,1%,1/16W,CHIP,CS26802FB02",6.8K,1%,R0402,17676.38,711.16,270.000,NO,,,
PR3788,"Q_RES_0402LF-15K,1%,1/16W,CHIP,CS31502FB05",15K,1%,R0402,17620.38,686.37,180.000,NO,,,
PR3789,"Q_RES_0402LF-25.5K,1%,1/16W,CHIP,CS32552FB06",25.5K,1%,R0402,16901.54,4301.85,270.000,NO,,,
PR3790,"Q_RES_0402LF-7.15K,1%,1/16W,CHIP,CS27152FB03",7.15K,1%,R0402,16886.33,4246.94,180.000,NO,,,
PR3791,"Q_RES_0402LF-15K,1%,1/16W,CHIP,CS31502FB05",15K,1%,R0402,16861.54,4301.85,90.000,NO,,,
PR3792,"Q_RES_0402LF-10,1%,1/16W,CHIP,CS01002FB07",10,1%,R0402,17718.91,988.20,270.000,NO,,,
PR3795,"Q_RES_0402LF-25.5K,1%,1/16W,CHIP,CS32552FB06",25.5K,1%,R0402,3755.55,2396.15,180.000,NO,,,
PR3798,"Q_RES_0402LF-10,1%,1/16W,CHIP,CS01002FB07",10,1%,R0402,17165.27,4203.40,180.000,NO,,,
PR3805,"Q_RES_0402LF-160K,1%,1/16W,CHIP,CS41602FB05",160K,1%,R0402,2996.66,711.28,0.000,NO,,,
PR3806,"Q_RES_0402LF-6.8K,1%,1/16W,CHIP,CS26802FB02",6.8K,1%,R0402,3052.66,696.07,270.000,NO,,,
PR3812,"Q_RES_0402LF-15K,1%,1/16W,CHIP,CS31502FB05",15K,1%,R0402,3755.55,2436.15,0.000,NO,,,
PR3821,"Q_RES_0402LF-30.1K,1%,1/16W,CHIP,CS33012FB03",30.1K,1%,R0402,2974.27,824.83,180.000,NO,,,
PR3822,"Q_RES_0402LF-5.36K,1%,1/16W,CHIP,CS25362FB02",5.36K,1%,R0402,3750.45,2286.45,0.000,NO,,,
PR3823,"Q_RES_0402LF-845,1%,1/16W,CHIP,CS18452FB01",845,1%,R0402,2974.27,859.83,180.000,NO,,,
PR3824,"Q_RES_0402LF-4.53K,1%,1/16W,CHIP,CS24532FB03",4.53K,1%,R0402,3750.45,2251.45,0.000,NO,,,
PR3828,"Q_RES_0402LF-15K,1%,1/16W,CHIP,CS31502FB05",15K,1%,R0402,2996.66,671.28,180.000,NO,,,
PR3829,"Q_RES_0402LF-7.15K,1%,1/16W,CHIP,CS27152FB03",7.15K,1%,R0402,3700.64,2411.36,90.000,NO,,,
PR3830,"Q_RES_0402LF-10,1%,1/16W,CHIP,CS01002FB07",10,1%,R0402,3053.15,972.99,270.000,NO,,,
PR3835,"Q_RES_0402LF-14.3K,1%,1/16W,CHIP,CS31432FB02",14.3K,1%,R0402,17434.18,1301.67,90.000,NO,,,
PR3837,"Q_RES_0402LF-17.4K,1%,1/16W,CHIP,CS31742FB04",17.4K,1%,R0402,17254.18,1266.67,90.000,NO,,,
PR3838,"Q_RES_0402LF-100,1%,1/16W,EMPTY,CS11002FB07",100,1%,R0402,17346.18,898.27,180.000,NO,,,
PR3839,"Q_RES_0402LF-10K,1%,1/16W,CHIP,CS31002FB08",10K,1%,R0402,17239.18,1168.67,180.000,NO,,,
PR3840,"Q_RES_0402LF-71.5K,1%,1/16W,EMPTY,CS37152FB05",71.5K,1%,R0402,17186.08,1025.84,90.000,NO,,,
PR3841,"Q_RES_0402LF-120K,1%,1/16W,CHIP,CS41202FB05",120K,1%,R0402,17226.08,1073.84,90.000,NO,,,
PR3842,"Q_RES_0402LF-10K,1%,1/16W,CHIP,CS31002FB08",10K,1%,R0402,17266.08,1073.84,270.000,NO,,,
PR3843,"Q_RES_0603LF-49.9,1%,1/10W,CHIP,CS04993F909",49.9,1%,R0603,17295.08,945.27,0.000,NO,,,
PR3844,"Q_RES_0402LF-71.5K,1%,1/16W,CHIP,CS37152FB05",71.5K,1%,R0402,16636.10,3987.02,270.000,NO,,,
PR3846,"Q_RES_0402LF-1.33K,1%,1/16W,CHIP,CS21332FB05",1.33K,1%,R0402,16526.10,3987.02,90.000,NO,,,
PR3847,"Q_RES_0402LF-14.3K,1%,1/16W,CHIP,CS31432FB02",14.3K,1%,R0402,2682.97,1290.43,90.000,NO,,,
PR3849,"Q_RES_0402LF-17.4K,1%,1/16W,CHIP,CS31742FB04",17.4K,1%,R0402,2502.97,1255.43,90.000,NO,,,
PR3850,"Q_RES_0402LF-100,1%,1/16W,EMPTY,CS11002FB07",100,1%,R0402,2592.97,875.43,180.000,NO,,,
PR3851,"Q_RES_0402LF-10K,1%,1/16W,CHIP,CS31002FB08",10K,1%,R0402,2487.97,1157.43,180.000,NO,,,
PR3852,"Q_RES_0402LF-71.5K,1%,1/16W,EMPTY,CS37152FB05",71.5K,1%,R0402,2434.87,1062.60,90.000,NO,,,
PR3853,"Q_RES_0402LF-120K,1%,1/16W,CHIP,CS41202FB05",120K,1%,R0402,2474.87,1062.60,90.000,NO,,,
PR3854,"Q_RES_0402LF-10K,1%,1/16W,CHIP,CS31002FB08",10K,1%,R0402,2514.87,1062.60,270.000,NO,,,
PR3855,"Q_RES_0402LF-71.5K,1%,1/16W,CHIP,CS37152FB05",71.5K,1%,R0402,3526.08,2783.30,270.000,NO,,,
PR3856,"Q_RES_0402LF-1.33K,1%,1/16W,CHIP,CS21332FB05",1.33K,1%,R0402,3558.28,2933.90,270.000,NO,,,
PR3857,"Q_RES_0603LF-49.9,1%,1/10W,CHIP,CS04993F909",49.9,1%,R0603,2543.87,927.33,0.000,NO,,,
PR3910,"Q_RES_0402LF-0,5%,1/16W,CHIP,CS00002JB13",0,5%,R0402,7623.50,15828.08,270.000,YES,,,
PR3911,"Q_RES_0402LF-0,5%,1/16W,CHIP,CS00002JB13",0,5%,R0402,8054.50,15856.08,270.000,YES,,,
PR3912,"Q_RES_0402LF-120K,1%,1/16W,CHIP,CS41202FB05",120K,1%,R0402,8481.50,16026.33,180.000,NO,,,
PR3914,"Q_RES_0402LF-2K,0.1%,1/16W,CHIP,CS22002BB07",2K,0.1%,R0402,7646.50,15747.33,180.000,NO,,,
PR3915,"Q_RES_0402LF-2K,0.1%,1/16W,CHIP,CS22002BB07",2K,0.1%,R0402,8061.50,15786.33,180.000,NO,,,
PR3916,"Q_RES_0402LF-0,5%,1/16W,CHIP,CS00002JB13",0,5%,R0402,7646.50,15917.33,0.000,NO,,,
PR3917,"Q_RES_0402LF-0,5%,1/16W,CHIP,CS00002JB13",0,5%,R0402,8061.50,16066.33,0.000,NO,,,
PR3918,"Q_RES_0402LF-2K,0.1%,1/16W,CHIP,CS22002BB07",2K,0.1%,R0402,7646.50,15787.33,180.000,NO,,,
PR3919,"Q_RES_0402LF-0,5%,1/16W,CHIP,CS00002JB13",0,5%,R0402,8061.50,15746.33,0.000,NO,,,
PR3920,"Q_RES_0402LF-0,5%,1/16W,CHIP,CS00002JB13",0,5%,R0402,8061.50,15986.33,0.000,NO,,,
PR3921,"Q_RES_0402LF-0,5%,1/16W,CHIP,CS00002JB13",0,5%,R0402,8481.50,15746.33,0.000,NO,,,
PR3922,"Q_RES_0402LF-0,5%,1/16W,CHIP,CS00002JB13",0,5%,R0402,8481.50,15986.33,0.000,NO,,,
PR3926,"Q_RES_0402LF-75K,0.1%,1/16W,CHIP,CS37502BB01",75K,0.1%,R0402,7267.50,16067.33,180.000,NO,,,
PR3927,"Q_RES_0402LF-4.99K,0.1%,1/16W,CHIP,CS24992BB04",4.99K,0.1%,R0402,7218.90,16032.37,270.000,YES,,,
PR3928,"Q_RES_0402LF-0,5%,1/16W,CHIP,CS00002JB13",0,5%,R0402,7536.10,15800.23,180.000,NO,,,
PR3929,"Q_RES_0402LF-1K,1%,1/16W,EMPTY,CS21002FB06",1K,1%,R0402,7035.00,15565.00,180.000,NO,,,
PR3930,"Q_RES_0402LF-0,5%,1/16W,CHIP,CS00002JB13",0,5%,R0402,7036.40,15605.73,0.000,NO,,,
PR3931,"Q_RES_0402LF-75K,0.1%,1/16W,CHIP,CS37502BB01",75K,0.1%,R0402,7257.50,15663.33,0.000,YES,,,
PR3932,"Q_RES_0402LF-4.99K,0.1%,1/16W,CHIP,CS24992BB04",4.99K,0.1%,R0402,7211.21,15742.83,0.000,YES,,,
PR3935,"Q_RES_0402LF-10K,1%,1/16W,CHIP,CS31002FB08",10K,1%,R0402,7036.10,15925.23,180.000,NO,,,
PR3937,"Q_RES_0402LF-120K,1%,1/16W,CHIP,CS41202FB05",120K,1%,R0402,7536.10,15890.23,0.000,NO,,,
PR3944,"Q_RES_0402LF-46.4K,1%,1/16W,CHIP,CS34642FB02",46.4K,1%,R0402,10151.20,2030.99,0.000,NO,,,
PR3945,"Q_RES_0402LF-71.5K,1%,1/16W,CHIP,CS37152FB05",71.5K,1%,R0402,7582.66,2653.22,180.000,NO,,,
PR3947,"Q_RES_0402LF-2.8K,1%,1/16W,CHIP,CS22802FB04",2.8K,1%,R0402,7582.67,2763.22,0.000,NO,,,
PR3949,"Q_RES_0402LF-56K,1%,1/16W,CHIP,CS35602FB00",56K,1%,R0402,10151.95,2184.23,0.000,NO,,,
PR3950,"Q_RES_0402LF-100,1%,1/16W,EMPTY,CS11002FB07",100,1%,R0402,9771.95,2094.23,90.000,NO,,,
PR3951,"Q_RES_0402LF-10K,1%,1/16W,CHIP,CS31002FB08",10K,1%,R0402,10053.95,2199.23,90.000,NO,,,
PR3952,"Q_RES_0402LF-71.5K,1%,1/16W,EMPTY,CS37152FB05",71.5K,1%,R0402,9959.12,2252.33,0.000,NO,,,
PR3953,"Q_RES_0402LF-120K,1%,1/16W,CHIP,CS41202FB05",120K,1%,R0402,9959.12,2212.33,0.000,NO,,,
PR3954,"Q_RES_0402LF-10K,1%,1/16W,CHIP,CS31002FB08",10K,1%,R0402,9959.12,2172.33,180.000,NO,,,
PR3957,"Q_RES_0603LF-49.9,1%,1/10W,CHIP,CS04993F909",49.9,1%,R0603,9833.28,2143.33,270.000,NO,,,
PR3960,"Q_RES_0402LF-160K,1%,1/16W,CHIP,CS41602FB05",160K,1%,R0402,9854.45,1810.83,270.000,NO,,,
PR3961,"Q_RES_0402LF-6.8K,1%,1/16W,CHIP,CS26802FB02",6.8K,1%,R0402,9839.24,1754.83,180.000,NO,,,
PR3962,"Q_RES_0402LF-15K,1%,1/16W,CHIP,CS31502FB05",15K,1%,R0402,9814.45,1810.83,90.000,NO,,,
PR3963,"Q_RES_0402LF-25.5K,1%,1/16W,CHIP,CS32552FB06",25.5K,1%,R0402,8578.03,2690.57,0.000,NO,,,
PR3964,"Q_RES_0402LF-7.15K,1%,1/16W,CHIP,CS27152FB03",7.15K,1%,R0402,8632.94,2675.36,270.000,NO,,,
PR3965,"Q_RES_0402LF-15K,1%,1/16W,CHIP,CS31502FB05",15K,1%,R0402,8578.03,2650.57,180.000,NO,,,
PR3966,"Q_RES_0402LF-10,1%,1/16W,CHIP,CS01002FB07",10,1%,R0402,10113.76,1712.78,180.000,NO,,,
PR3967,"Q_RES_0402LF-10,1%,1/16W,CHIP,CS01002FB07",10,1%,R0402,8675.71,2953.85,270.000,NO,,,
PR3968,"Q_RES_0402LF-9.31K,1%,1/16W,CHIP,CS29312FB02",9.31K,1%,R0402,9964.15,1805.73,90.000,NO,,,
PR3969,"Q_RES_0402LF-2.49K,1%,1/16W,CHIP,CS22492FB05",2.49K,1%,R0402,8583.13,2800.27,180.000,NO,,,
PR3970,"Q_RES_0402LF-2.67K,1%,1/16W,CHIP,CS22672FB03",2.67K,1%,R0402,9999.15,1805.73,90.000,NO,,,
PR3971,"Q_RES_0402LF-9.76K,1%,1/16W,CHIP,CS29762FB05",9.76K,1%,R0402,8583.13,2835.27,180.000,NO,,,
PR3980,"Q_RES_0402LF-0,5%,1/16W,CHIP,CS00002JB13",0,5%,R0402,8474.50,15856.08,270.000,YES,,,
PR3981,"Q_RES_0402LF-0,5%,1/16W,CHIP,CS00002JB13",0,5%,R0402,8894.50,15856.08,270.000,YES,,,
PR3982,"Q_RES_0402LF-120K,1%,1/16W,CHIP,CS41202FB05",120K,1%,R0402,8901.50,16026.33,180.000,NO,,,
PR3984,"Q_RES_0402LF-120K,1%,1/16W,CHIP,CS41202FB05",120K,1%,R0402,9321.50,15902.33,180.000,NO,,,
PR3986,"Q_RES_0402LF-2K,0.1%,1/16W,CHIP,CS22002BB07",2K,0.1%,R0402,8481.50,15786.33,180.000,NO,,,
PR3987,"Q_RES_0402LF-2K,0.1%,1/16W,CHIP,CS22002BB07",2K,0.1%,R0402,8901.50,15786.33,180.000,NO,,,
PR3988,"Q_RES_0402LF-0,5%,1/16W,CHIP,CS00002JB13",0,5%,R0402,8481.50,16066.33,0.000,NO,,,
PR3989,"Q_RES_0402LF-0,5%,1/16W,CHIP,CS00002JB13",0,5%,R0402,8901.50,16066.33,0.000,NO,,,
PR3990,"Q_RES_0402LF-2K,0.1%,1/16W,CHIP,CS22002BB07",2K,0.1%,R0402,8481.50,15826.33,180.000,NO,,,
PR3991,"Q_RES_0402LF-2K,0.1%,1/16W,CHIP,CS22002BB07",2K,0.1%,R0402,8901.50,15826.33,180.000,NO,,,
PR3992,"Q_RES_0402LF-0,5%,1/16W,CHIP,CS00002JB13",0,5%,R0402,8901.50,15746.33,0.000,NO,,,
PR3993,"Q_RES_0402LF-0,5%,1/16W,CHIP,CS00002JB13",0,5%,R0402,8901.50,15986.33,0.000,NO,,,
PR3994,"Q_RES_0402LF-0,5%,1/16W,CHIP,CS00002JB13",0,5%,R0402,9321.50,15782.33,0.000,NO,,,
PR3995,"Q_RES_0402LF-0,5%,1/16W,CHIP,CS00002JB13",0,5%,R0402,9321.50,15862.33,0.000,NO,,,
PR3999,"Q_RES_0402LF-24.3K,1%,1/16W,CHIP,CS32432FB03",24.3K,1%,R0402,7009.63,1297.28,90.000,NO,,,
PR4000,"Q_RES_0402LF-160K,1%,1/16W,CHIP,CS41602FB05",160K,1%,R0402,7314.93,909.98,0.000,NO,,,
PR4001,"Q_RES_0402LF-6.8K,1%,1/16W,CHIP,CS26802FB02",6.8K,1%,R0402,7370.93,894.77,270.000,NO,,,
PR4002,"Q_RES_0402LF-15K,1%,1/16W,CHIP,CS31502FB05",15K,1%,R0402,7314.93,869.98,180.000,NO,,,
PR4003,"Q_RES_0402LF-10,1%,1/16W,CHIP,CS01002FB07",10,1%,R0402,7412.70,1171.59,270.000,NO,,,
PR4004,"Q_RES_0402LF-17.8K,1%,1/16W,CHIP,CS31782FB04",17.8K,1%,R0402,7320.03,1019.68,180.000,NO,,,
PR4005,"Q_RES_0402LF-30.1K,1%,1/16W,CHIP,CS33012FB03",30.1K,1%,R0402,6834.53,1296.68,90.000,NO,,,
PR4006,"Q_RES_0402LF-100,1%,1/16W,EMPTY,CS11002FB07",100,1%,R0402,6924.53,916.68,180.000,NO,,,
PR4007,"Q_RES_0402LF-10K,1%,1/16W,CHIP,CS31002FB08",10K,1%,R0402,6819.53,1198.68,180.000,NO,,,
PR4008,"Q_RES_0402LF-1.33K,1%,1/16W,CHIP,CS21332FB05",1.33K,1%,R0402,7320.03,1054.68,180.000,NO,,,
PR4009,"Q_RES_0402LF-71.5K,1%,1/16W,EMPTY,CS37152FB05",71.5K,1%,R0402,6758.43,1056.85,90.000,NO,,,
PR4010,"Q_RES_0402LF-120K,1%,1/16W,CHIP,CS41202FB05",120K,1%,R0402,6806.23,1103.85,90.000,NO,,,
PR4011,"Q_RES_0402LF-10K,1%,1/16W,CHIP,CS31002FB08",10K,1%,R0402,6846.43,1103.85,270.000,NO,,,
PR4012,"Q_RES_0402LF-0,5%,1/16W,CHIP,CS00002JB13",0,5%,R0402,7586.18,893.48,0.000,NO,,,
PR4014,"Q_RES_0603LF-49.9,1%,1/10W,CHIP,CS04993F909",49.9,1%,R0603,6875.43,968.58,0.000,NO,,,
PR4522,"Q_RES_0402LF-10M,1%,1/16W,CHIP,CS61002FB02",10M,1%,R0402,3186.03,998.37,180.000,NO,,,
PR4523,"Q_RES_0402LF-10M,1%,1/16W,CHIP,CS61002FB02",10M,1%,R0402,3539.33,2114.07,0.000,NO,,,
PR4524,"Q_RES_0402LF-10M,1%,1/16W,CHIP,CS61002FB02",10M,1%,R0402,17836.36,1009.39,180.000,NO,,,
PR4525,"Q_RES_0402LF-10M,1%,1/16W,CHIP,CS61002FB02",10M,1%,R0402,17189.31,4085.37,90.000,NO,,,
PR4526,"Q_RES_0402LF-10M,1%,1/16W,CHIP,CS61002FB02",10M,1%,R0402,7531.35,1191.72,180.000,NO,,,
PR4527,"Q_RES_0402LF-10M,1%,1/16W,CHIP,CS61002FB02",10M,1%,R0402,8794.66,2973.65,180.000,NO,,,
PR4528,"Q_RES_0402LF-10M,1%,1/16W,CHIP,CS61002FB02",10M,1%,R0402,10113.10,1538.68,0.000,NO,,,
PR4540,"Q_RES_0402LF-20K,1%,1/16W,CHIP,CS32002FB06",20K,1%,R0402,6939.54,1265.27,270.000,YES,,,
PR4541,"Q_RES_0402LF-20K,1%,1/16W,CHIP,CS32002FB06",20K,1%,R0402,10165.67,2091.28,90.000,YES,,,
PR5481,"Q_RES_0402LF-4.53K,1%,1/16W,CHIP,CS24532FB03",4.53K,1%,R0402,17046.24,4296.75,90.000,NO,,,
PR5484,"Q_RES_0402LF-30.1K,1%,1/16W,CHIP,CS33012FB03",30.1K,1%,R0402,17625.48,836.07,180.000,NO,,,
PR6000,"Q_RES_0402LF-0,5%,1/16W,CHIP,CS00002JB13",0,5%,R0402,8027.46,13458.78,180.000,YES,,,
PR6001,"Q_SP_RES4P-0.0003,1%,4W,SMLF,CHIP,SP_CS0000FFT09",,,R2725_4P,9610.84,15508.24,270.000,NO,,,
PR6002,"Q_SP_RES4P-0.003,1%,2W,SMLF,CHIP,SP_CS+003AFR00_1",,,R2512_4PXM,10914.34,15507.84,270.000,NO,,,
PR6003,"Q_RES_0402LF-10K,1%,1/16W,CHIP,CS31002FB08",10K,1%,R0402,5526.99,2960.60,270.000,NO,,,
PR6004,"Q_RES_0402LF-11.5K,1%,1/16W,CHIP,CS31152FB03",11.5K,1%,R0402,4656.99,2870.60,270.000,NO,,,
PR6005,"Q_RES_0402LF-60.4K,1%,1/16W,CHIP,CS36042FB04",60.4K,1%,R0402,4840.63,3099.72,270.000,NO,,,
PR6006,"Q_RES_0402LF-60.4K,1%,1/16W,CHIP,CS36042FB04",60.4K,1%,R0402,5710.63,3189.72,270.000,NO,,,
PR6007,"Q_RES_0402LF-20K,1%,1/16W,CHIP,CS32002FB06",20K,1%,R0402,5619.28,2898.58,0.000,NO,,,
PR6008,"Q_RES_0402LF-10K,1%,1/16W,CHIP,CS31002FB08",10K,1%,R0402,4749.28,2808.58,0.000,NO,,,
PR6010,"Q_RES_0402LF-10K,1%,1/16W,CHIP,CS31002FB08",10K,1%,R0402,5619.28,2975.68,359.946,NO,,,
PR6011,"Q_RES_0402LF-10K,1%,1/16W,CHIP,CS31002FB08",10K,1%,R0402,4749.28,2885.68,359.946,NO,,,
PR6500,"Q_RES_0402LF-0,5%,1/16W,CHIP,CS00002JB13",0,5%,R0402,9461.73,11439.53,0.000,YES,,,
PR6501,"Q_RES_0402LF-0,5%,1/16W,CHIP,CS00002JB13",0,5%,R0402,9525.12,11398.97,270.000,YES,,,
PR6502,"Q_RES_0402LF-7.15K,1%,1/16W,CHIP,CS27152FB03",7.15K,1%,R0402,9430.55,11534.97,180.000,NO,,,
PR6505,"Q_RES_0402LF-20K,1%,1/16W,CHIP,CS32002FB06",20K,1%,R0402,9403.93,11430.78,90.000,NO,,,
PR6507,"Q_RES_0402LF-10K,1%,1/16W,CHIP,CS31002FB08",10K,1%,R0402,9444.63,11430.78,89.946,NO,,,
PR6520,"Q_RES_0402LF-0,5%,1/16W,CHIP,CS00002JB13",0,5%,R0402,8991.48,11439.53,0.000,YES,,,
PR6521,"Q_RES_0402LF-0,5%,1/16W,CHIP,CS00002JB13",0,5%,R0402,9054.87,11398.97,270.000,YES,,,
PR6522,"Q_RES_0402LF-7.15K,1%,1/16W,CHIP,CS27152FB03",7.15K,1%,R0402,8960.30,11534.97,180.000,NO,,,
PR6524,"Q_RES_0402LF-20K,1%,1/16W,CHIP,CS32002FB06",20K,1%,R0402,8933.68,11430.78,90.000,NO,,,
PR6526,"Q_RES_0402LF-10K,1%,1/16W,CHIP,CS31002FB08",10K,1%,R0402,8974.38,11430.78,89.946,NO,,,
PR6530,"Q_RES_0402LF-49.9,1%,1/16W,CHIP,CS04992FB07",49.9,1%,R0402,17315.79,15309.50,0.000,NO,,,
PR6531,"Q_RES_0402LF-0,5%,1/16W,CHIP,CS00002JB13",0,5%,R0402,17369.29,16494.56,0.000,NO,,,
PR6532,"Q_RES_0402LF-49.9,1%,1/16W,CHIP,CS04992FB07",49.9,1%,R0402,17315.79,15352.50,0.000,NO,,,
PR6533,"Q_RES_0402LF-22.1K,1%,1/16W,CHIP,CS32212FB02",22.1K,1%,R0402,396.33,16228.96,0.000,NO,,,
PR6538,"Q_RES_0402LF-1,1%,1/16W,CHIP,CS-1002FB04",1,1%,R0402,396.33,15943.96,180.000,NO,,,
PR6539,"Q_RES_0402LF-0,5%,1/16W,CHIP,CS00002JB13",0,5%,R0402,611.33,16379.96,90.000,NO,,,
PR6540,"Q_RES_0402LF-0,5%,1/16W,CHIP,CS00002JB13",0,5%,R0402,586.33,16363.96,270.000,YES,,,
PR6541,"Q_RES_0402LF-0,5%,1/16W,CHIP,CS00002JB13",0,5%,R0402,561.33,16379.96,90.000,NO,,,
PR6542,"Q_RES_0402LF-0,5%,1/16W,CHIP,CS00002JB13",0,5%,R0402,536.33,16363.96,270.000,YES,,,
PR6543,"Q_RES_0402LF-0,5%,1/16W,CHIP,CS00002JB13",0,5%,R0402,511.33,16348.96,90.000,NO,,,
PR6544,"Q_RES_0402LF-0,5%,1/16W,CHIP,CS00002JB13",0,5%,R0402,461.33,16348.96,90.000,NO,,,
PR6548,"Q_RES_0402LF-0,5%,1/16W,CHIP,CS00002JB13",0,5%,R0402,387.33,16120.96,90.000,YES,,,
PR6550,"Q_RES_0402LF-0,5%,1/16W,CHIP,CS00002JB13",0,5%,R0402,17302.02,15975.93,270.000,NO,,,
PR6551,"Q_RES_0402LF-0,5%,1/16W,EMPTY,CS00002JB13",0,5%,R0402,17262.02,15975.93,270.000,NO,,,
PR6552,"Q_RES_0402LF-2.2,5%,1/16W,CHIP,TMP_QCS-2202JB25",2.2,5%,R0402,17415.19,15730.85,270.000,YES,,,
PR6553,"Q_RES_0402LF-8.87K,1%,1/16W,EMPTY,CS28872FB01",8.87K,1%,R0402,17504.79,15859.05,0.000,NO,,,
PR6554,"Q_RES_0402LF-5.6,1%,1/16W,CHIP,CS-5602FB01",5.6,1%,R0402,17560.51,15818.32,90.000,NO,,,
PR6555,"Q_RES_0402LF-1.5,1%,1/8W,EMPTY,CS-1504FB00",1.5,1%,R0402,17359.45,15578.71,90.000,NO,,,
PR6556,"Q_RES_0402LF-0,5%,1/16W,CHIP,CS00002JB13",0,5%,R0402,17379.79,15789.05,90.000,NO,,,
PR6557,"Q_RES_0603LF-499,1%,1/10W,CHIP,CS14993F901",499,1%,R0603,18235.14,15319.93,270.000,YES,,,
PR6560,"Q_RES_0402LF-2.2,5%,1/16W,CHIP,TMP_QCS-2202JB25",2.2,5%,R0402,17742.79,15666.05,270.000,YES,,,
PR6561,"Q_RES_0402LF-8.87K,1%,1/16W,EMPTY,CS28872FB01",8.87K,1%,R0402,17842.94,15858.32,0.000,NO,,,
PR6562,"Q_RES_0402LF-5.6,1%,1/16W,CHIP,CS-5602FB01",5.6,1%,R0402,17917.94,15815.32,90.000,NO,,,
PR6563,"Q_RES_0402LF-1.5,1%,1/8W,EMPTY,CS-1504FB00",1.5,1%,R0402,17716.88,15578.71,90.000,NO,,,
PR6564,"Q_RES_0402LF-0,5%,1/16W,CHIP,CS00002JB13",0,5%,R0402,17719.79,15779.05,180.000,NO,,,
PR6600,"Q_RES_0402LF-49.9,1%,1/16W,CHIP,CS04992FB07",49.9,1%,R0402,330.96,14979.14,0.000,NO,,,
PR6601,"Q_RES_0402LF-0,5%,1/16W,CHIP,CS00002JB13",0,5%,R0402,721.67,16349.05,180.000,NO,,,
PR6602,"Q_RES_0402LF-49.9,1%,1/16W,CHIP,CS04992FB07",49.9,1%,R0402,330.96,15022.14,0.000,NO,,,
PR6603,"Q_RES_0402LF-0,5%,1/16W,CHIP,CS00002JB13",0,5%,R0402,17694.63,16614.65,180.000,NO,,,
PR6604,"Q_RES_0402LF-5.36K,1%,1/16W,EMPTY,CS25362FB02",5.36K,1%,R0402,17624.29,16589.56,0.000,YES,,,
PR6605,"Q_RES_0402LF-0,5%,1/16W,CHIP,CS00002JB13",0,5%,R0402,17698.89,16705.14,0.000,NO,,,
PR6606,"Q_RES_0402LF-0,5%,1/16W,CHIP,CS00002JB13",0,5%,R0402,17702.63,16768.65,0.000,YES,,,
PR6607,"Q_RES_0402LF-1K,1%,1/16W,EMPTY,CS21002FB06",1K,1%,R0402,17696.63,16729.65,180.000,YES,,,
PR6608,"Q_RES_0402LF-1,1%,1/16W,CHIP,CS-1002FB04",1,1%,R0402,17694.63,16899.65,0.000,NO,,,
PR6609,"Q_RES_0402LF-0,5%,1/16W,CHIP,CS00002JB13",0,5%,R0402,17479.63,16463.65,270.000,NO,,,
PR6610,"Q_RES_0402LF-0,5%,1/16W,CHIP,CS00002JB13",0,5%,R0402,17504.63,16479.65,90.000,YES,,,
PR6611,"Q_RES_0402LF-0,5%,1/16W,CHIP,CS00002JB13",0,5%,R0402,17529.63,16463.65,270.000,NO,,,
PR6612,"Q_RES_0402LF-0,5%,1/16W,CHIP,CS00002JB13",0,5%,R0402,17554.63,16479.65,90.000,YES,,,
PR6613,"Q_RES_0402LF-0,5%,1/16W,CHIP,CS00002JB13",0,5%,R0402,17579.63,16494.65,270.000,NO,,,
PR6614,"Q_RES_0402LF-0,5%,1/16W,CHIP,CS00002JB13",0,5%,R0402,17629.63,16494.65,270.000,NO,,,
PR6615,"Q_RES_0402LF-1K,1%,1/16W,CHIP,CS21002FB06",1K,1%,R0402,17274.29,16739.56,270.000,YES,,,
PR6616,"Q_RES_0402LF-0,5%,1/16W,CHIP,CS00002JB13",0,5%,R0402,17314.29,16739.56,270.000,YES,,,
PR6618,"Q_RES_0402LF-0,5%,1/16W,CHIP,CS00002JB13",0,5%,R0402,17708.65,16690.37,180.000,YES,,,
PR6619,"Q_RES_0402LF-0,5%,1/16W,CHIP,CS00002JB13",0,5%,R0402,461.50,15520.80,270.000,NO,,,
PR6620,"Q_RES_0402LF-0,5%,1/16W,EMPTY,CS00002JB13",0,5%,R0402,421.50,15520.80,270.000,NO,,,
PR6621,"Q_RES_0402LF-2.2,5%,1/16W,CHIP,TMP_QCS-2202JB25",2.2,5%,R0402,512.53,15335.69,270.000,YES,,,
PR6622,"Q_RES_0402LF-8.87K,1%,1/16W,EMPTY,CS28872FB01",8.87K,1%,R0402,631.96,15528.69,0.000,NO,,,
PR6623,"Q_RES_0402LF-5.6,1%,1/16W,CHIP,CS-5602FB01",5.6,1%,R0402,687.68,15487.96,90.000,NO,,,
PR6624,"Q_RES_0402LF-1.5,1%,1/8W,EMPTY,CS-1504FB00",1.5,1%,R0402,486.62,15248.35,90.000,NO,,,
PR6625,"Q_RES_0603LF-499,1%,1/10W,CHIP,CS14993F901",499,1%,R0603,300.00,15080.00,270.000,YES,,,
PR6626,"Q_RES_0402LF-0,5%,1/16W,CHIP,CS00002JB13",0,5%,R0402,506.96,15458.69,90.000,NO,,,
PR6627,"Q_RES_0402LF-2.2,5%,1/16W,CHIP,TMP_QCS-2202JB25",2.2,5%,R0402,869.96,15335.69,270.000,YES,,,
PR6628,"Q_RES_0402LF-8.87K,1%,1/16W,EMPTY,CS28872FB01",8.87K,1%,R0402,970.11,15527.96,0.000,NO,,,
PR6629,"Q_RES_0402LF-5.6,1%,1/16W,CHIP,CS-5602FB01",5.6,1%,R0402,1045.11,15484.96,90.000,NO,,,
PR6630,"Q_RES_0402LF-1.5,1%,1/8W,EMPTY,CS-1504FB00",1.5,1%,R0402,844.05,15248.35,90.000,NO,,,
PR6631,"Q_RES_0402LF-0,5%,1/16W,CHIP,CS00002JB13",0,5%,R0402,846.96,15448.69,180.000,NO,,,
PR6800,"Q_RES_0402LF-2.2,1%,1/16W,CHIP,CS-2202FB01",2.2,1%,R0402,9479.19,11598.31,180.000,NO,,,
PR6801,"Q_RES_0402LF-2.2,1%,1/16W,CHIP,CS-2202FB01",2.2,1%,R0402,9008.94,11598.31,180.000,NO,,,
PR6802,"Q_RES_0402LF-0,5%,1/16W,EMPTY,CS00002JB13",0,5%,R0402,806.33,16253.96,180.000,YES,,,
PR6803,"Q_RES_0402LF-1K,1%,1/16W,EMPTY,CS21002FB06",1K,1%,R0402,17284.63,16634.65,0.000,NO,,,
PR6804,"Q_RES_0402LF-1K,1%,1/16W,EMPTY,CS21002FB06",1K,1%,R0402,806.33,16208.96,180.000,NO,,,
PR6805,"Q_RES_0402LF-1K,1%,1/16W,EMPTY,CS21002FB06",1K,1%,R0402,17284.63,16679.65,0.000,NO,,,
PR6806,"Q_RES_0402LF-1K,1%,1/16W,EMPTY,CS21002FB06",1K,1%,R0402,806.33,16163.96,180.000,NO,,,
PR6807,"Q_RES_0402LF-0,5%,1/16W,EMPTY,CS00002JB13",0,5%,R0402,17609.29,16529.56,270.000,YES,,,
PR6808,"Q_RES_0402LF-0,5%,1/16W,EMPTY,CS00002JB13",0,5%,R0402,481.67,16314.05,90.000,YES,,,
PR6809,"Q_RES_0402LF-0,5%,1/16W,CHIP,CS00002JB13",0,5%,R0402,396.33,15988.96,180.000,YES,,,
PR6810,"Q_RES_0402LF-0,5%,1/16W,CHIP,CS00002JB13",0,5%,R0402,17284.63,16679.65,0.000,YES,,,
PR6811,"Q_RES_0402LF-0,5%,1/16W,CHIP,CS00002JB13",0,5%,R0402,806.33,16163.96,180.000,YES,,,
PR6812,"Q_RES_0402LF-1K,1%,1/16W,CHIP,CS21002FB06",1K,1%,R0402,816.67,16104.05,90.000,YES,,,
PR6813,"Q_RES_0402LF-1K,1%,1/16W,EMPTY,CS21002FB06",1K,1%,R0402,396.33,16033.96,0.000,YES,,,
PR6814,"Q_RES_0402LF-10K,1%,1/16W,EMPTY,CS31002FB08",10K,1%,R0402,17694.63,16614.65,180.000,YES,,,
PR6815,"Q_RES_0402LF-10K,1%,1/16W,EMPTY,CS31002FB08",10K,1%,R0402,396.33,16231.96,0.000,YES,,,
PR6816,"Q_RES_0402LF-0,5%,1/16W,CHIP,CS00002JB13",0,5%,R0402,776.67,16104.05,90.000,YES,,,
PR6817,"Q_RES_0402LF-1K,1%,1/16W,EMPTY,CS21002FB06",1K,1%,R0402,17284.63,16589.65,0.000,NO,,,
PR6818,"Q_RES_0402LF-1K,1%,1/16W,EMPTY,CS21002FB06",1K,1%,R0402,806.33,16253.96,180.000,NO,,,
PR6819,"Q_RES_0402LF-0,5%,1/16W,CHIP,CS00002JB13",0,5%,R0402,17284.63,16634.65,0.000,YES,,,
PR6820,"Q_RES_0402LF-0,5%,1/16W,CHIP,CS00002JB13",0,5%,R0402,806.33,16208.96,180.000,YES,,,
PR6821,"Q_RES_0402LF-0,5%,1/16W,CHIP,CS00002JB13",0,5%,R0402,521.33,16126.96,180.000,YES,,,
PR8000,"Q_RES_0402LF-0,5%,1/16W,CHIP,CS00002JB13",0,5%,R0402,8010.00,13300.00,0.000,NO,,,
PR8001,"Q_RES_0402LF-2.2,1%,1/16W,CHIP,CS-2202FB01",2.2,1%,R0402,13106.87,5657.71,180.000,NO,,,
PR8002,"Q_RES_0402LF-2.2,1%,1/16W,CHIP,CS-2202FB01",2.2,1%,R0402,2638.66,5894.54,270.000,NO,,,
PR8003,"Q_RES_0402LF-2.2,1%,1/16W,CHIP,CS-2202FB01",2.2,1%,R0402,5755.67,3026.68,90.000,NO,,,
PR8004,"Q_RES_0402LF-2.2,1%,1/16W,CHIP,CS-2202FB01",2.2,1%,R0402,4885.44,2935.24,90.000,NO,,,
PR8005,"Q_RES_0402LF-0,5%,1/16W,CHIP,CS00002JB13",0,5%,R0402,14682.57,5729.77,180.000,YES,,,
PR8006,"Q_RES_0402LF-0,5%,1/16W,CHIP,CS00002JB13",0,5%,R0402,14682.57,5689.77,180.000,YES,,,
PR8007,"Q_RES_0402LF-0,5%,1/16W,CHIP,CS00002JB13",0,5%,R0402,11985.00,14055.00,0.000,NO,,,
PR8008,"Q_RES_0402LF-0,5%,1/16W,CHIP,CS00002JB13",0,5%,R0402,11985.00,14100.00,0.000,NO,,,
PR8009,"Q_RES_0402LF-0,5%,1/16W,CHIP,CS00002JB13",0,5%,R0402,3470.00,5825.00,180.000,YES,,,
PR8010,"Q_RES_0402LF-0,5%,1/16W,CHIP,CS00002JB13",0,5%,R0402,3470.00,5785.00,180.000,YES,,,
PR8011,"Q_RES_0402LF-0,5%,1/16W,CHIP,CS00002JB13",0,5%,R0402,975.00,14170.00,0.000,NO,,,
PR8012,"Q_RES_0402LF-0,5%,1/16W,CHIP,CS00002JB13",0,5%,R0402,975.00,14215.00,0.000,NO,,,
PR8073,"Q_RES_0402LF-1K,1%,1/16W,CHIP,CS21002FB06",1K,1%,R0402,18126.22,1708.69,180.000,YES,,,
PR8089,"Q_RES_0402LF-16.9K,1%,1/16W,CHIP,CS31692FB03",16.9K,1%,R0402,16120.11,5590.92,180.000,NO,,,
PR8091,"Q_RES_0402LF-11.8K,0.1%,1/16W,CHIP,CS31182BB06",11.8K,0.1%,R0402,16133.56,5486.73,89.946,NO,,,
PR8092,"Q_RES_0402LF-86.6K,1%,1/16W,CHIP,CS38662FB05",86.6K,1%,R0402,16092.86,5486.73,270.000,NO,,,
PR8389,"Q_RES_0402LF-1,1%,1/16W,CHIP,CS-1002FB04",1,1%,R0402,18163.08,2035.29,270.000,NO,,,
PU2,"ISL99390FRZTR5935-ISL99390FRZ-TR5935,SMLF,IC,AL099A",,,QFN21_6X5XB,12862.26,13188.51,0.000,NO,,,
PU3,"MPQ8633BGLEC838Z-MPQ8633BGLE-C838-Z,SMLF,IC,AL0086A",,,QFN14_4X3,2750.05,5997.35,90.000,NO,,,
PU4,"ISL99390FRZTR5935-ISL99390FRZ-TR5935,SMLF,IC,AL099A",,,QFN21_6X5XB,3239.55,7194.64,180.000,NO,,,
PU5,"ISL99390FRZTR5935-ISL99390FRZ-TR5935,SMLF,IC,AL099A",,,QFN21_6X5XB,3100.97,13188.70,0.000,NO,,,
PU6,"ISL99390FRZTR5935-ISL99390FRZ-TR5935,SMLF,IC,AL099A",,,QFN21_6X5XB,14343.07,6998.87,180.000,NO,,,
PU9,"NCP3284AMNTXG-NCP3284AMNTXG,SMLF,IC,AL003284002",,,PQFN22_6X5,17972.45,2010.51,180.000,NO,,,
PU10,"ISL99390FRZTR5935-ISL99390FRZ-TR5935,SMLF,IC,AL099A",,,QFN21_6X5XB,13690.07,6344.07,180.000,NO,,,
PU11,"ISL99390FRZTR5935-ISL99390FRZ-TR5935,SMLF,IC,AL099A",,,QFN21_6X5XB,13845.12,13383.25,0.000,NO,,,
PU12,"RAA229620GNPHA0-RAA229620GNP#HA0,SMLF,IC,ARF0TGP40A",,,QFN48_TH_0-4_6X6XH,12210.00,14200.00,270.000,NO,,,
PU13,"ISL99390FRZTR5935-ISL99390FRZ-TR5935,SMLF,IC,AL099A",,,QFN21_6X5XB,13191.30,13187.94,0.000,NO,,,
PU14,"ISL99390FRZTR5935-ISL99390FRZ-TR5935,SMLF,IC,AL099A",,,QFN21_6X5XB,12153.39,13650.25,0.000,NO,,,
PU15,"ISL99390FRZTR5935-ISL99390FRZ-TR5935,SMLF,IC,AL099A",,,QFN21_6X5XB,12533.30,13188.79,0.000,NO,,,
PU16,"ISL99390FRZTR5935-ISL99390FRZ-TR5935,SMLF,IC,AL099A",,,QFN21_6X5XB,13519.30,13189.94,0.000,NO,,,
PU17,"ISL99390FRZTR5935-ISL99390FRZ-TR5935,SMLF,IC,AL099A",,,QFN21_6X5XB,11825.39,13650.25,0.000,NO,,,
PU18,"ISL99390FRZTR5935-ISL99390FRZ-TR5935,SMLF,IC,AL099A",,,QFN21_6X5XB,11496.39,13650.25,0.000,NO,,,
PU19,"ISL99390FRZTR5935-ISL99390FRZ-TR5935,SMLF,IC,AL099A",,,QFN21_6X5XB,11169.39,13650.25,0.000,NO,,,
PU20,"ISL99390FRZTR5935-ISL99390FRZ-TR5935,SMLF,IC,AL099A",,,QFN21_6X5XB,10843.39,13650.25,0.000,NO,,,
PU21,"RAA229621GNPHA0-RAA229621GNP#HA0,SMLF,IC,ARF0TGP40A",,,QFN40_TH_0-4_5X5XE,16492.83,14255.41,270.000,NO,,,
PU22,"ISL99390FRZTR5935-ISL99390FRZ-TR5935,SMLF,IC,AL099A",,,QFN21_6X5XB,16678.90,13823.42,0.000,NO,,,
PU23,"ISL99390FRZTR5935-ISL99390FRZ-TR5935,SMLF,IC,AL099A",,,QFN21_6X5XB,17006.72,13824.42,0.000,NO,,,
PU24,"ISL99390FRZTR5935-ISL99390FRZ-TR5935,SMLF,IC,AL099A",,,QFN21_6X5XB,2584.55,6650.73,180.000,NO,,,
PU25,"RAA229620GNPHA0-RAA229620GNP#HA0,SMLF,IC,ARF0TGP40A",,,QFN48_TH_0-4_6X6XH,3766.57,5699.15,270.000,YES,,,
PU26,"ISL99390FRZTR5935-ISL99390FRZ-TR5935,SMLF,IC,AL099A",,,QFN21_6X5XB,3570.15,7191.96,180.000,NO,,,
PU27,"ISL99390FRZTR5935-ISL99390FRZ-TR5935,SMLF,IC,AL099A",,,QFN21_6X5XB,3900.55,7192.64,180.000,NO,,,
PU28,"ISL99390FRZTR5935-ISL99390FRZ-TR5935,SMLF,IC,AL099A",,,QFN21_6X5XB,4230.55,7014.64,180.000,NO,,,
PU29,"ISL99390FRZTR5935-ISL99390FRZ-TR5935,SMLF,IC,AL099A",,,QFN21_6X5XB,2911.85,6993.14,180.000,NO,,,
PU30,"ISL99390FRZTR5935-ISL99390FRZ-TR5935,SMLF,IC,AL099A",,,QFN21_6X5XB,4554.55,6768.64,180.000,NO,,,
PU31,"ISL99390FRZTR5935-ISL99390FRZ-TR5935,SMLF,IC,AL099A",,,QFN21_6X5XB,4880.55,6503.64,180.000,NO,,,
PU32,"ISL99390FRZTR5935-ISL99390FRZ-TR5935,SMLF,IC,AL099A",,,QFN21_6X5XB,5213.55,6162.64,180.000,NO,,,
PU33,"ISL99390FRZTR5935-ISL99390FRZ-TR5935,SMLF,IC,AL099A",,,QFN21_6X5XB,4083.83,13383.44,0.000,NO,,,
PU34,"RAA229620GNPHA0-RAA229620GNP#HA0,SMLF,IC,ARF0TGP40A",,,QFN48_TH_0-4_6X6XH,1200.00,14335.00,270.000,NO,,,
PU35,"ISL99390FRZTR5935-ISL99390FRZ-TR5935,SMLF,IC,AL099A",,,QFN21_6X5XB,3430.01,13188.13,0.000,NO,,,
PU36,"ISL99390FRZTR5935-ISL99390FRZ-TR5935,SMLF,IC,AL099A",,,QFN21_6X5XB,2436.01,13650.44,0.000,NO,,,
PU37,"ISL99390FRZTR5935-ISL99390FRZ-TR5935,SMLF,IC,AL099A",,,QFN21_6X5XB,2772.01,13188.98,0.000,NO,,,
PU38,"ISL99390FRZTR5935-ISL99390FRZ-TR5935,SMLF,IC,AL099A",,,QFN21_6X5XB,3758.01,13190.13,0.000,NO,,,
PU39,"ISL99390FRZTR5935-ISL99390FRZ-TR5935,SMLF,IC,AL099A",,,QFN21_6X5XB,2108.01,13650.44,0.000,NO,,,
PU40,"ISL99390FRZTR5935-ISL99390FRZ-TR5935,SMLF,IC,AL099A",,,QFN21_6X5XB,1779.01,13650.44,0.000,NO,,,
PU42,"RAA229620GNPHA0-RAA229620GNP#HA0,SMLF,IC,ARF0TGP40A",,,QFN48_TH_0-4_6X6XH,14897.57,5604.77,270.000,YES,,,
PU43,"ISL99390FRZTR5935-ISL99390FRZ-TR5935,SMLF,IC,AL099A",,,QFN21_6X5XB,14672.25,7194.64,180.000,NO,,,
PU44,"ISL99390FRZTR5935-ISL99390FRZ-TR5935,SMLF,IC,AL099A",,,QFN21_6X5XB,7201.57,13830.53,0.000,NO,,,
PU45,"ISL99390FRZTR5935-ISL99390FRZ-TR5935,SMLF,IC,AL099A",,,QFN21_6X5XB,7529.39,13831.53,0.000,NO,,,
PU46,"ISL99390FRZTR5935-ISL99390FRZ-TR5935,SMLF,IC,AL099A",,,QFN21_6X5XB,15003.07,7196.32,180.000,NO,,,
PU47,"ISL99390FRZTR5935-ISL99390FRZ-TR5935,SMLF,IC,AL099A",,,QFN21_6X5XB,15331.07,7194.64,180.000,NO,,,
PU48,"ISL99390FRZTR5935-ISL99390FRZ-TR5935,SMLF,IC,AL099A",,,QFN21_6X5XB,14017.07,6673.07,180.000,NO,,,
PU49,"ISL99390FRZTR5935-ISL99390FRZ-TR5935,SMLF,IC,AL099A",,,QFN21_6X5XB,15662.37,6975.24,180.000,NO,,,
PU50,"ISL99390FRZTR5935-ISL99390FRZ-TR5935,SMLF,IC,AL099A",,,QFN21_6X5XB,15990.07,6637.55,180.000,NO,,,
PU51,"ISL99390FRZTR5935-ISL99390FRZ-TR5935,SMLF,IC,AL099A",,,QFN21_6X5XB,16320.07,6447.55,180.000,NO,,,
PU52,"ISL99390FRZTR5935-ISL99390FRZ-TR5935,SMLF,IC,AL099A",,,QFN21_6X5XB,1452.01,13650.44,0.000,NO,,,
PU53,"ISL99390FRZTR5935-ISL99390FRZ-TR5935,SMLF,IC,AL099A",,,QFN21_6X5XB,1126.01,13650.44,0.000,NO,,,
PU54,"RAA229621GNPHA0-RAA229621GNP#HA0,SMLF,IC,ARF0TGP40A",,,QFN40_TH_0-4_5X5XE,6386.95,13722.57,270.000,NO,,,
PU55,"MPQ8633AGLEC807Z-MPQ8633AGLE-C807-Z,SMLF,IC,AL0086A",,,QFN14_4X3,7907.64,13411.62,180.000,NO,,,
PU57,"MPQ8633BGLEC838Z-MPQ8633BGLE-C838-Z,SMLF,IC,AL0086A",,,QFN14_4X3,13209.23,5546.09,0.000,NO,,,
PU200,"MAX15090BEWIT-MAX15090BEWI+T,SMLF,IC,AL015080B00",,,BGA28_0-5_3-525X2-065,3600.45,2296.55,180.000,NO,,,
PU201,"MAX15090BEWIT-MAX15090BEWI+T,SMLF,IC,AL015080B00",,,BGA28_0-5_3-525X2-065,3124.27,814.73,0.000,NO,,,
PU202,"MAX15090BEWIT-MAX15090BEWI+T,SMLF,IC,AL015080B00",,,BGA28_0-5_3-525X2-065,17001.14,4146.75,270.000,NO,,,
PU203,"MAX15090BEWIT-MAX15090BEWI+T,SMLF,IC,AL015080B00",,,BGA28_0-5_3-525X2-065,17775.48,825.97,0.000,NO,,,
PU204,"MP5022CGQVZ-MP5022CGQV-Z,SMLF,IC,AL005022001",,,QFN22_TH_3X5,17415.48,1109.27,270.000,NO,,,
PU205,"MP5016GQHLZ-MP5016GQH-L-Z,SMLF,IC,AL005016007",,,QFN8_2X1-5,16556.10,4142.02,0.000,NO,,,
PU206,"MP5022CGQVZ-MP5022CGQV-Z,SMLF,IC,AL005022001",,,QFN22_TH_3X5,2664.27,1098.03,270.000,NO,,,
PU207,"MP5016GQHLZ-MP5016GQH-L-Z,SMLF,IC,AL005016007",,,QFN8_2X1-5,3665.88,2858.70,270.000,NO,,,
PU287,"MP5991GLUZ-MP5991GLU-Z,SMLF,IC,AL005991A00",,,LGA32_TH_0-5_5X5,7855.77,15823.63,180.000,NO,,,
PU288,"MP5991GLUZ-MP5991GLU-Z,SMLF,IC,AL005991A00",,,LGA32_TH_0-5_5X5,8275.77,15823.63,180.000,NO,,,
PU289,"MP5990GMA1111Z-MP5990GMA-1111-Z,SMLF,IC,AR0F0TP4023",,,LGA45_TH_0-45_7X5,7294.43,15823.61,270.000,NO,,,
PU292,"MP5022CGQVZ-MP5022CGQV-Z,SMLF,IC,AL005022001",,,QFN22_TH_3X5,9994.55,2022.93,180.000,NO,,,
PU293,"MP5016GQHLZ-MP5016GQH-L-Z,SMLF,IC,AL005016007",,,QFN8_2X1-5,7737.66,2733.22,270.000,NO,,,
PU294,"MAX15090BEWIT-MAX15090BEWI+T,SMLF,IC,AL015080B00",,,BGA28_0-5_3-525X2-065,9954.05,1655.73,270.000,NO,,,
PU295,"MAX15090BEWIT-MAX15090BEWI+T,SMLF,IC,AL015080B00",,,BGA28_0-5_3-525X2-065,8733.13,2790.17,0.000,NO,,,
PU296,"MP5991GLUZ-MP5991GLU-Z,SMLF,IC,AL005991A00",,,LGA32_TH_0-5_5X5,8695.77,15823.63,180.000,NO,,,
PU297,"MP5991GLUZ-MP5991GLU-Z,SMLF,IC,AL005991A00",,,LGA32_TH_0-5_5X5,9115.77,15823.63,180.000,NO,,,
PU299,"MP5022CGQVZ-MP5022CGQV-Z,SMLF,IC,AL005022001",,,QFN22_TH_3X5,6995.83,1139.28,270.000,NO,,,
PU300,"MAX15090BEWIT-MAX15090BEWI+T,SMLF,IC,AL015080B00",,,BGA28_0-5_3-525X2-065,7470.03,1009.58,0.000,NO,,,
PU6000,"MPQ8626GDZ-MPQ8626GD-Z,SMLF,IC,AL008626000",,,QFN14_0-5_3X2XA,5648.10,3082.19,0.000,NO,,,
PU6001,"MPQ8626GDZ-MPQ8626GD-Z,SMLF,IC,AL008626000",,,QFN14_0-5_3X2XA,4778.10,2992.19,0.000,NO,,,
PU6500,"MPQ8633BGLEC838Z-MPQ8633BGLE-C838-Z,SMLF,IC,AL0086A",,,QFN14_4X3,9581.55,11486.69,0.000,NO,,,
PU6501,"MPQ8633BGLEC838Z-MPQ8633BGLE-C838-Z,SMLF,IC,AL0086A",,,QFN14_4X3,9111.30,11486.69,0.000,NO,,,
PU6502,"ISL69260IRAZT-ISL69260IRAZ-T,SMLF,IC,AL069260000",,,QFN40_TH_0-4_5X5XE,17493.29,16689.56,270.000,NO,,,
PU6503,"ISL99390FRZTR5935-ISL99390FRZ-TR5935,SMLF,IC,AL099A",,,QFN21_6X5XB,17524.88,15639.58,0.000,NO,,,
PU6504,"ISL99390FRZTR5935-ISL99390FRZ-TR5935,SMLF,IC,AL099A",,,QFN21_6X5XB,17882.31,15639.58,0.000,NO,,,
PU6510,"ISL69260IRAZT-ISL69260IRAZ-T,SMLF,IC,AL069260000",,,QFN40_TH_0-4_5X5XE,597.67,16154.05,90.000,NO,,,
PU6511,"ISL99390FRZTR5935-ISL99390FRZ-TR5935,SMLF,IC,AL099A",,,QFN21_6X5XB,652.05,15309.22,0.000,NO,,,
PU6512,"ISL99390FRZTR5935-ISL99390FRZ-TR5935,SMLF,IC,AL099A",,,QFN21_6X5XB,1009.48,15309.22,0.000,NO,,,
Q1,"MOSFET_NCH_DUAL-PJT138K,SMLF,IC,BAM138K0003",,,SOT363XD,6432.44,5100.38,0.000,NO,,,
Q2,"MOSFET_DUAL_6P-2N7002KDW,SMLF,IC,BAM70020047",,,SOT363XD,13423.99,791.09,270.000,NO,,,
Q3,"MOSFET_NCH_DUAL-PJT138K,SMLF,IC,BAM138K0003",,,SOT363XD,8200.00,5245.00,90.000,NO,,,
Q4,"MOSFET_DUAL_6P-2N7002KDW,SMLF,IC,BAM70020047",,,SOT363XD,6400.45,2997.30,0.000,NO,,,
Q8,"MOSFET_DUAL_6P-2N7002KDW,SMLF,IC,BAM70020047",,,SOT363XD,11859.13,789.25,270.000,NO,,,
Q11,"MOSFET_DUAL_6P-2N7002KDW,SMLF,IC,BAM70020047",,,SOT363XD,13543.09,790.75,270.000,NO,,,
Q12,"MOSFET_N_GSD-NX138BK,SMLF,IC,BAM01380023",,,SOT23_GDSXE,13737.45,792.78,270.000,NO,,,
Q18,"BSS138DW7F-BSS138DW-7-F,SMLF,IC,BAM01380032",,,SOT363A,4021.84,4867.85,270.000,NO,,,
Q19,"BSS138DW7F-BSS138DW-7-F,SMLF,IC,BAM01380032",,,SOT363A,4159.84,4867.08,270.000,NO,,,
Q27,"BSS138DW7F-BSS138DW-7-F,SMLF,IC,BAM01380032",,,SOT363A,4297.84,4866.31,270.000,NO,,,
Q28,"MOSFET_DUAL_6P-2N7002KDW,SMLF,IC,BAM70020047",,,SOT363XD,13054.45,803.07,0.000,NO,,,
Q29,"MOSFET_N_GSD-NX138BK,SMLF,IC,BAM01380023",,,SOT23_GDSXE,13236.04,792.78,270.000,NO,,,
Q30,"MOSFET_N_GSD-NX138BK,SMLF,IC,BAM01380023",,,SOT23_GDSXE,13236.04,969.18,270.000,NO,,,
Q37,"MOSFET_NCH_DUAL-PJT138K,SMLF,IC,BAM138K0003",,,SOT363XD,5696.48,4239.49,180.000,NO,,,
Q39,"MOSFET_NCH_GDS_ESD_PROTECTED-2N7002K,SMLF,IC,BAM70A",,,SOT23_GDSXC,7630.29,1473.75,90.000,NO,,,
Q50,"MOSFET_NCH_DUAL-PJT138K,SMLF,IC,BAM138K0003",,,SOT363XD,15866.67,5337.85,180.000,NO,,,
Q54,"MOSFET_NCH_GDS_ESD_PROTECTED-2N7002K,SMLF,IC,BAM70A",,,SOT23_GDSXC,8252.84,5613.47,0.000,NO,,,
Q56,"MOSFET_NCH_1D3S-PSMNR58-30YLH,SMLF,IC,BAMNR580000",,,SOT1023,17380.71,2750.44,270.000,NO,,,
Q57,"MOSFET_NCH_1D3S-PSMNR58-30YLH,SMLF,IC,BAMNR580000",,,SOT1023,15884.91,5815.22,0.000,NO,,,
Q61,"MOSFET_N_GSD-NX138BK,SMLF,IC,BAM01380023",,,SOT23_GDSXE,14132.26,1129.74,0.000,NO,,,
Q62,"MOSFET_N_SMLF-BSS138K,BSS138K,IC,BAM138K0000",,,SOT23_GDSXD,5924.30,2574.31,0.000,NO,,,
Q63,"MOSFET_N_SMLF-BSS138K,BSS138K,IC,BAM138K0000",,,SOT23_GDSXD,9242.99,5582.88,0.000,NO,,,
Q64,"MOSFET_N_SMLF-BSS138K,BSS138K,IC,BAM138K0000",,,SOT23_GDSXD,8595.15,5345.85,0.000,NO,,,
Q67,"MOSFET_NCH_DUAL-PJT138K,SMLF,IC,BAM138K0003",,,SOT363XD,6609.13,17302.77,0.000,NO,,,
Q69,"MOSFET_NCH_DUAL-PJT138K,SMLF,IC,BAM138K0003",,,SOT363XD,16667.60,17294.68,0.000,NO,,,
Q70,"MOSFET_NCH_DUAL-PJT138K,SMLF,IC,BAM138K0003",,,SOT363XD,17017.60,17143.18,0.000,NO,,,
Q71,"MOSFET_NCH_DUAL-PJT138K,SMLF,IC,BAM138K0003",,,SOT363XD,13986.85,16442.40,0.000,YES,,,
Q72,"MOSFET_NCH_DUAL-PJT138K,SMLF,IC,BAM138K0003",,,SOT363XD,1914.13,16743.12,0.000,YES,,,
Q74,"MOSFET_NCH_DUAL-PJT138K,SMLF,IC,BAM138K0003",,,SOT363XD,4200.00,16430.00,90.000,YES,,,
Q75,"MOSFET_NCH_DUAL-PJT138K,SMLF,IC,BAM138K0003",,,SOT363XD,4535.00,16350.00,180.000,NO,,,
Q78,"MOSFET_NCH_DUAL-PJT138K,SMLF,IC,BAM138K0003",,,SOT363XD,12609.16,2895.07,0.000,YES,,,
Q79,"MOSFET_NCH_DUAL-PJT138K,SMLF,IC,BAM138K0003",,,SOT363XD,12769.16,2895.07,0.000,YES,,,
Q80,"MOSFET_NCH_DUAL-PJT138K,SMLF,IC,BAM138K0003",,,SOT363XD,12929.16,2895.07,0.000,YES,,,
Q81,"MOSFET_NCH_DUAL-PJT138K,SMLF,IC,BAM138K0003",,,SOT363XD,13089.16,2895.07,0.000,YES,,,
Q83,"MOSFET_NCH_DUAL-PJT138K,SMLF,IC,BAM138K0003",,,SOT363XD,13083.34,3006.25,180.000,YES,,,
Q84,"MOSFET_NCH_DUAL-PJT138K,SMLF,IC,BAM138K0003",,,SOT363XD,13329.16,2895.07,0.000,YES,,,
Q85,"MOSFET_NCH_DUAL-PJT138K,SMLF,IC,BAM138K0003",,,SOT363XD,13489.16,2895.07,0.000,YES,,,
Q86,"MOSFET_NCH_DUAL-PJT138K,SMLF,IC,BAM138K0003",,,SOT363XD,13649.16,2895.07,0.000,YES,,,
Q87,"MOSFET_NCH_DUAL-PJT138K,SMLF,IC,BAM138K0003",,,SOT363XD,12289.16,2895.07,0.000,YES,,,
Q95,"MOSFET_NCH_DUAL-PJT138K,SMLF,IC,BAM138K0003",,,SOT363XD,5696.48,4132.87,0.000,NO,,,
Q96,"MOSFET_NCH_DUAL-PJT138K,SMLF,IC,BAM138K0003",,,SOT363XD,1914.13,16592.94,0.000,YES,,,
Q101,"MOSFET_NCH_DUAL-PJT138K,SMLF,IC,BAM138K0003",,,SOT363XD,1915.60,17045.47,0.000,YES,,,
Q102,"MOSFET_NCH_DUAL-PJT138K,SMLF,IC,BAM138K0003",,,SOT363XD,6609.13,17196.15,0.000,NO,,,
Q103,"MOSFET_NCH_DUAL-PJT138K,SMLF,IC,BAM138K0003",,,SOT363XD,4730.00,16470.00,270.000,NO,,,
Q104,"MOSFET_NCH_DUAL-PJT138K,SMLF,IC,BAM138K0003",,,SOT363XD,11980.07,17097.02,180.000,NO,,,
Q106,"MOSFET_NCH_DUAL-PJT138K,SMLF,IC,BAM138K0003",,,SOT363XD,17408.80,17108.24,0.000,NO,,,
Q107,"MOSFET_NCH_DUAL-PJT138K,SMLF,IC,BAM138K0003",,,SOT363XD,1915.60,16894.29,0.000,YES,,,
Q108,"MOSFET_NCH_DUAL-PJT138K,SMLF,IC,BAM138K0003",,,SOT363XD,4485.00,16440.00,0.000,YES,,,
Q118,"MOSFET_NCH_DUAL-PJT138K,SMLF,IC,BAM138K0003",,,SOT363XD,2459.55,1468.79,180.000,NO,,,
Q119,"MOSFET_NCH_DUAL-PJT138K,SMLF,IC,BAM138K0003",,,SOT363XD,2459.95,1576.03,0.000,NO,,,
Q123,"MOSFET_NCH_DUAL-PJT138K,SMLF,IC,BAM138K0003",,,SOT363XD,18313.76,1618.34,180.000,NO,,,
Q124,"MOSFET_NCH_DUAL-PJT138K,SMLF,IC,BAM138K0003",,,SOT363XD,18063.05,1618.34,0.000,NO,,,
Q125,"MOSFET_NCH_DUAL-PJT138K,SMLF,IC,BAM138K0003",,,SOT363XD,7649.85,1700.77,180.000,NO,,,
Q126,"MOSFET_NCH_DUAL-PJT138K,SMLF,IC,BAM138K0003",,,SOT363XD,10014.29,2714.43,0.000,NO,,,
Q127,"MOSFET_NCH_DUAL-PJT138K,SMLF,IC,BAM138K0003",,,SOT363XD,10014.29,2607.81,0.000,NO,,,
Q128,"MOSFET_NCH_DUAL-PJT138K,SMLF,IC,BAM138K0003",,,SOT363XD,6548.33,16293.22,90.000,YES,,,
Q129,"MOSFET_NCH_DUAL-PJT138K,SMLF,IC,BAM138K0003",,,SOT363XD,11980.54,17237.02,180.000,NO,,,
Q130,"MOSFET_NCH_DUAL-PJT138K,SMLF,IC,BAM138K0003",,,SOT363XD,11951.71,16816.50,270.000,NO,,,
Q131,"MOSFET_NCH_DUAL-PJT138K,SMLF,IC,BAM138K0003",,,SOT363XD,6594.58,16981.36,180.000,YES,,,
Q132,"MOSFET_NCH_DUAL-PJT138K,SMLF,IC,BAM138K0003",,,SOT363XD,6594.58,17121.36,180.000,YES,,,
Q133,"MOSFET_NCH_DUAL-PJT138K,SMLF,IC,BAM138K0003",,,SOT363XD,12105.13,16816.59,270.000,NO,,,
Q134,"MOSFET_NCH_DUAL-PJT138K,SMLF,IC,BAM138K0003",,,SOT363XD,14024.99,16383.67,90.000,NO,,,
Q135,"MOSFET_NCH_DUAL-PJT138K,SMLF,IC,BAM138K0003",,,SOT363XD,16667.60,17143.18,0.000,NO,,,
Q136,"MOSFET_NCH_DUAL-PJT138K,SMLF,IC,BAM138K0003",,,SOT363XD,17408.80,17259.74,0.000,NO,,,
Q137,"MOSFET_NCH_DUAL-PJT138K,SMLF,IC,BAM138K0003",,,SOT363XD,17016.30,17210.34,180.000,YES,,,
Q144,"MOSFET_NCH_DUAL-PJT138K,SMLF,IC,BAM138K0003",,,SOT363XD,12395.85,3027.16,180.000,YES,,,
Q145,"MOSFET_NCH_DUAL-PJT138K,SMLF,IC,BAM138K0003",,,SOT363XD,11107.61,17215.50,0.000,NO,,,
Q146,"MOSFET_NCH_DUAL-PJT138K,SMLF,IC,BAM138K0003",,,SOT363XD,13863.59,16866.38,90.000,NO,,,
Q148,"MOSFET_NCH_DUAL-PJT138K,SMLF,IC,BAM138K0003",,,SOT363XD,4300.00,16340.00,270.000,YES,,,
Q6000,"MOSFET_NCH_DUAL-PJT138K,SMLF,IC,BAM138K0003",,,SOT363XD,12129.16,2895.07,0.000,YES,,,
Q6001,"METR3904G-METR3904-G,SMLF,IC,BA039040020",,,SOT23_BEC,11262.50,16113.27,270.000,NO,,,
Q7000,"MOSFET_PCH_GDS_ESD_PROTECTED-DMP2035U-7,SMLF,EMPTYA",,,SOT23_GDSXC,1546.40,4280.40,90.000,NO,,,
Q7001,"MOSFET_NCH_1D3S-PSMNR58-30YLH,SMLF,EMPTY,BAMNR5800A",,,SOT1023,1472.70,4576.30,90.000,NO,,,
Q7002,"MOSFET_PCH_GDS_ESD_PROTECTED-DMP2035U-7,SMLF,EMPTYA",,,SOT23_GDSXC,1814.20,4275.00,90.000,NO,,,
Q7003,"MOSFET_NCH_1D3S-PSMNR58-30YLH,SMLF,EMPTY,BAMNR5800A",,,SOT1023,1740.50,4570.90,90.000,NO,,,
Q8000,"MOSFET_NCH_DUAL-PJT138K,SMLF,IC,BAM138K0003",,,SOT363XD,3979.26,16727.77,180.000,YES,,,
Q8001,"MOSFET_NCH_DUAL-PJT138K,SMLF,IC,BAM138K0003",,,SOT363XD,7510.00,2165.00,90.000,NO,,,
Q9000,"MOSFET_NCH_DUAL-PJT138K,SMLF,IC,BAM138K0003",,,SOT363XD,14290.72,16367.29,90.000,NO,,,
Q9001,"MOSFET_NCH_DUAL-PJT138K,SMLF,IC,BAM138K0003",,,SOT363XD,6935.21,16433.32,0.000,NO,,,
Q9002,"MOSFET_NCH_DUAL-PJT138K,SMLF,IC,BAM138K0003",,,SOT363XD,14293.09,15991.04,180.000,NO,,,
Q9003,"MOSFET_NCH_DUAL-PJT138K,SMLF,IC,BAM138K0003",,,SOT363XD,6285.00,4190.00,180.000,NO,,,
R1,"Q_RES_0402LF-49.9,1%,1/16W,CHIP,CS04992FB07",49.9,1%,R0402,11180.34,7672.99,180.000,YES,,,
R2,"Q_RES_0402LF-33.2,1%,1/16W,CHIP,CS03322FB03",33.2,1%,R0402,7918.25,4565.18,180.000,YES,,,
R3,"Q_RES_0402LF-2K,1%,1/16W,CHIP,CS22002FB07",2K,1%,R0402,7918.25,4605.18,180.000,YES,,,
R4,"Q_RES_0402LF-4.7K,5%,1/16W,EMPTY,CS24702JB10",4.7K,5%,R0402,12384.54,4352.55,180.000,NO,,,
R5,"Q_RES_0402LF-54.9K,1%,1/16W,CHIP,CS35492FB03",54.9K,1%,R0402,10781.41,7672.65,180.000,YES,,,
R6,"Q_RES_0402LF-54.9K,1%,1/16W,CHIP,CS35492FB03",54.9K,1%,R0402,1020.60,7672.66,180.000,YES,,,
R7,"Q_RES_0402LF-10K,1%,1/16W,CHIP,CS31002FB08",10K,1%,R0402,11969.44,7672.65,180.000,YES,,,
R8,"Q_RES_0402LF-100K,1%,1/16W,CHIP,CS41002FB09",100K,1%,R0402,5795.24,2611.71,0.000,NO,,,
R9,"Q_RES_0402LF-0,5%,1/16W,CHIP,CS00002JB13",0,5%,R0402,6573.04,4444.97,180.000,YES,,,
R10,"Q_RES_0402LF-10K,1%,1/16W,CHIP,CS31002FB08",10K,1%,R0402,6875.00,3948.62,90.000,NO,,,
R11,"Q_RES_0402LF-10K,1%,1/16W,CHIP,CS31002FB08",10K,1%,R0402,6590.45,4163.61,90.000,YES,,,
R12,"Q_RES_0402LF-10K,1%,1/16W,CHIP,CS31002FB08",10K,1%,R0402,6740.45,4093.20,0.000,NO,,,
R13,"Q_RES_0402LF-0,5%,1/16W,CHIP,CS00002JB13",0,5%,R0402,5889.68,2521.35,90.000,YES,,,
R14,"Q_RES_0402LF-0,5%,1/16W,CHIP,CS00002JB13",0,5%,R0402,5589.68,2521.35,90.000,YES,,,
R15,"Q_RES_0402LF-0,5%,1/16W,CHIP,CS00002JB13",0,5%,R0402,5389.68,2521.35,90.000,YES,,,
R16,"Q_RES_0402LF-10K,1%,1/16W,CHIP,CS31002FB08",10K,1%,R0402,7017.38,5247.00,0.000,YES,,,
R17,"Q_RES_0402LF-10K,1%,1/16W,CHIP,CS31002FB08",10K,1%,R0402,6965.00,5258.62,90.000,NO,,,
R18,"Q_RES_0402LF-10K,1%,1/16W,CHIP,CS31002FB08",10K,1%,R0402,7005.00,5418.62,90.000,NO,,,
R19,"Q_RES_0402LF-10K,1%,1/16W,CHIP,CS31002FB08",10K,1%,R0402,7045.00,5518.62,90.000,NO,,,
R20,"Q_RES_0402LF-10K,1%,1/16W,CHIP,CS31002FB08",10K,1%,R0402,9900.56,5210.14,0.000,NO,,,
R21,"Q_RES_0402LF-1K,1%,1/16W,EMPTY,CS21002FB06",1K,1%,R0402,10145.00,5605.00,0.000,NO,,,
R22,"Q_RES_0402LF-100,1%,1/16W,CHIP,CS11002FB07",100,1%,R0402,16565.25,1517.62,0.000,NO,,,
R23,"Q_RES_0402LF-33,5%,1/16W,CHIP,CS03302JB10",33,5%,R0402,6740.00,4423.62,180.000,NO,,,
R24,"Q_RES_0402LF-4.7K,5%,1/16W,EMPTY,CS24702JB10",4.7K,5%,R0402,12384.54,4312.55,180.000,NO,,,
R25,"Q_RES_0402LF-10K,1%,1/16W,CHIP,CS31002FB08",10K,1%,R0402,6467.19,4294.37,90.000,YES,,,
R26,"Q_RES_0402LF-4.7K,5%,1/16W,EMPTY,CS24702JB10",4.7K,5%,R0402,12604.47,4591.82,180.000,NO,,,
R27,"Q_RES_0402LF-0,5%,1/16W,CHIP,CS00002JB13",0,5%,R0402,12401.77,7949.88,90.000,YES,,,
R28,"Q_RES_0402LF-0,5%,1/16W,CHIP,CS00002JB13",0,5%,R0402,12351.77,7949.88,90.000,YES,,,
R29,"Q_RES_0402LF-0,5%,1/16W,CHIP,CS00002JB13",0,5%,R0402,15296.77,7976.88,180.000,YES,,,
R30,"Q_RES_0402LF-0,5%,1/16W,CHIP,CS00002JB13",0,5%,R0402,15296.77,8014.88,180.000,YES,,,
R31,"Q_RES_0402LF-4.7K,1%,1/16W,EMPTY,CS24702FB06",4.7K,1%,R0402,17660.62,416.03,270.000,YES,,,
R32,"Q_RES_0402LF-4.7K,1%,1/16W,CHIP,CS24702FB06",4.7K,1%,R0402,17620.62,416.03,90.000,YES,,,
R33,"Q_RES_0402LF-4.7K,1%,1/16W,EMPTY,CS24702FB06",4.7K,1%,R0402,17737.57,329.00,90.000,YES,,,
R34,"Q_RES_0402LF-4.7K,1%,1/16W,CHIP,CS24702FB06",4.7K,1%,R0402,17697.57,329.00,270.000,YES,,,
R35,"Q_RES_0402LF-10K,1%,1/16W,CHIP,CS31002FB08",10K,1%,R0402,16264.71,7672.65,180.000,YES,,,
R36,"Q_RES_0402LF-10K,1%,1/16W,CHIP,CS31002FB08",10K,1%,R0402,2207.63,7672.66,180.000,YES,,,
R37,"Q_RES_0402LF-10K,1%,1/16W,CHIP,CS31002FB08",10K,1%,R0402,6503.29,7672.66,180.000,YES,,,
R38,"Q_RES_0402LF-0,5%,1/16W,CHIP,CS00002JB13",0,5%,R0402,17874.90,460.86,0.000,YES,,,
R39,"Q_RES_0402LF-0,5%,1/16W,CHIP,CS00002JB13",0,5%,R0402,17213.44,639.56,270.000,NO,,,
R40,"Q_RES_0402LF-0,5%,1/16W,CHIP,CS00002JB13",0,5%,R0402,17169.31,772.55,270.000,NO,,,
R41,"Q_RES_0402LF-0,5%,1/16W,CHIP,CS00002JB13",0,5%,R0402,17165.58,637.79,270.000,NO,,,
R42,"Q_RES_0402LF-0,5%,1/16W,CHIP,CS00002JB13",0,5%,R0402,15334.54,897.21,90.000,NO,,,
R43,"Q_RES_0402LF-4.7K,5%,1/16W,EMPTY,CS24702JB10",4.7K,5%,R0402,12605.17,4543.72,180.000,NO,,,
R44,"Q_RES_0402LF-1K,1%,1/16W,CHIP,CS21002FB06",1K,1%,R0402,12384.54,4432.55,0.000,NO,,,
R45,"Q_RES_0402LF-10K,1%,1/16W,CHIP,CS31002FB08",10K,1%,R0402,17913.90,1518.34,0.000,NO,,,
R46,"Q_RES_0402LF-0,5%,1/16W,CHIP,CS00002JB13",0,5%,R0402,15374.54,897.21,90.000,NO,,,
R47,"Q_RES_0402LF-33.2,1%,1/16W,CHIP,CS03322FB03",33.2,1%,R0402,16239.09,3027.42,180.000,NO,,,
R48,"Q_RES_0402LF-33.2,1%,1/16W,CHIP,CS03322FB03",33.2,1%,R0402,16239.09,2907.42,180.000,NO,,,
R49,"Q_RES_0402LF-33,5%,1/16W,CHIP,CS03302JB10",33,5%,R0402,6580.00,4258.62,180.000,NO,,,
R50,"Q_RES_0402LF-33,5%,1/16W,CHIP,CS03302JB10",33,5%,R0402,6740.00,4258.62,180.000,NO,,,
R51,"Q_RES_0402LF-0,5%,1/16W,CHIP,CS00002JB13",0,5%,R0402,6740.00,4578.62,0.000,NO,,,
R52,"Q_RES_0402LF-10K,1%,1/16W,EMPTY,CS31002FB08",10K,1%,R0402,11899.27,4362.02,0.000,NO,,,
R53,"Q_RES_0402LF-4.7K,1%,1/16W,CHIP,CS24702FB06",4.7K,1%,R0402,14664.05,615.63,0.000,NO,,,
R54,"Q_RES_0402LF-1K,1%,1/16W,CHIP,CS21002FB06",1K,1%,R0402,11899.27,4322.02,180.000,NO,,,
R55,"Q_RES_0402LF-33.2,1%,1/16W,CHIP,CS03322FB03",33.2,1%,R0402,6476.72,354.86,90.000,YES,,,
R56,"Q_RES_0402LF-0,5%,1/16W,CHIP,CS00002JB13",0,5%,R0402,6740.00,4538.62,0.000,NO,,,
R57,"Q_RES_0402LF-0,5%,1/16W,CHIP,CS00002JB13",0,5%,R0402,7165.00,5093.62,270.000,NO,,,
R58,"Q_RES_0402LF-33,5%,1/16W,CHIP,CS03302JB10",33,5%,R0402,6741.50,4472.02,0.000,YES,,,
R59,"Q_RES_0402LF-22,1%,1/16W,CHIP,CS02202FB02",22,1%,R0402,7652.43,2992.79,0.000,NO,,,
R60,"Q_RES_0402LF-10K,1%,1/16W,EMPTY,CS31002FB08",10K,1%,R0402,11899.27,4442.02,0.000,NO,,,
R61,"Q_RES_0402LF-49.9,1%,1/16W,CHIP,CS04992FB07",49.9,1%,R0402,11985.00,14010.00,0.000,NO,,,
R62,"Q_RES_0402LF-1K,1%,1/16W,CHIP,CS21002FB06",1K,1%,R0402,11899.27,4402.02,180.000,NO,,,
R63,"Q_RES_0402LF-33,5%,1/16W,CHIP,CS03302JB10",33,5%,R0402,6580.00,4698.62,180.000,YES,,,
R64,"Q_RES_0402LF-1K,1%,1/16W,EMPTY,CS21002FB06",1K,1%,R0402,6580.00,4538.62,180.000,NO,,,
R65,"Q_RES_0402LF-33.2,1%,1/16W,CHIP,CS03322FB03",33.2,1%,R0402,6519.10,354.86,90.000,YES,,,
R66,"Q_RES_0402LF-2.2K,5%,1/16W,CHIP,CS22202JB07",2.2K,5%,R0402,11712.06,4588.41,180.000,NO,,,
R67,"Q_RES_0402LF-2.2K,5%,1/16W,CHIP,CS22202JB07",2.2K,5%,R0402,11712.06,4533.41,180.000,NO,,,
R68,"Q_RES_0402LF-1K,1%,1/16W,EMPTY,CS21002FB06",1K,1%,R0402,11899.27,4522.02,0.000,NO,,,
R69,"Q_RES_0402LF-10K,1%,1/16W,CHIP,CS31002FB08",10K,1%,R0402,11899.27,4482.02,180.000,NO,,,
R70,"Q_RES_0402LF-0,5%,1/16W,CHIP,CS00002JB13",0,5%,R0402,7080.56,5790.81,90.000,NO,,,
R71,"Q_RES_0402LF-33,5%,1/16W,CHIP,CS03302JB10",33,5%,R0402,5950.00,4455.00,180.000,NO,,,
R72,"Q_RES_0402LF-22,1%,1/16W,CHIP,CS02202FB02",22,1%,R0402,7876.27,3034.10,180.000,NO,,,
R73,"Q_RES_0402LF-22,1%,1/16W,CHIP,CS02202FB02",22,1%,R0402,7875.42,3087.55,180.000,NO,,,
R74,"Q_RES_0402LF-0,5%,1/16W,CHIP,CS00002JB13",0,5%,R0402,8048.77,2686.21,0.000,YES,,,
R75,"Q_RES_0402LF-0,5%,1/16W,CHIP,CS00002JB13",0,5%,R0402,8565.03,2735.57,180.000,YES,,,
R76,"Q_RES_0402LF-0,5%,1/16W,CHIP,CS00002JB13",0,5%,R0402,8485.09,2876.02,0.000,YES,,,
R77,"Q_RES_0402LF-100K,1%,1/16W,CHIP,CS41002FB09",100K,1%,R0402,7790.43,2992.79,0.000,NO,,,
R78,"Q_RES_0402LF-4.7K,5%,1/16W,EMPTY,CS24702JB10",4.7K,5%,R0402,9480.00,8570.00,270.000,YES,,,
R79,"Q_RES_0402LF-100K,1%,1/16W,CHIP,CS41002FB09",100K,1%,R0402,7745.27,3034.10,180.000,NO,,,
R80,"Q_RES_0402LF-100K,1%,1/16W,CHIP,CS41002FB09",100K,1%,R0402,7744.42,3087.55,180.000,NO,,,
R81,"Q_RES_0402LF-33,5%,1/16W,CHIP,CS03302JB10",33,5%,R0402,7195.00,3948.62,90.000,YES,,,
R82,"Q_RES_0402LF-100K,1%,1/16W,CHIP,CS41002FB09",100K,1%,R0402,7527.28,2773.99,0.000,YES,,,
R83,"Q_RES_0402LF-100K,1%,1/16W,CHIP,CS41002FB09",100K,1%,R0402,8585.28,2663.82,90.000,YES,,,
R84,"Q_RES_0402LF-100K,1%,1/16W,CHIP,CS41002FB09",100K,1%,R0402,8484.82,2915.59,180.000,YES,,,
R85,"Q_RES_0402LF-0,5%,1/16W,CHIP,CS00002JB13",0,5%,R0402,12515.62,4581.82,180.000,NO,,,
R86,"Q_RES_0402LF-0,5%,1/16W,CHIP,CS00002JB13",0,5%,R0402,12515.62,4531.82,180.000,NO,,,
R87,"Q_RES_0402LF-1K,1%,1/16W,CHIP,CS21002FB06",1K,1%,R0402,6538.21,857.62,90.000,NO,,,
R88,"Q_RES_0402LF-1K,1%,1/16W,EMPTY,CS21002FB06",1K,1%,R0402,11753.01,7512.65,180.000,YES,,,
R89,"Q_RES_0402LF-1K,1%,1/16W,EMPTY,CS21002FB06",1K,1%,R0402,11969.44,7637.65,0.000,YES,,,
R90,"Q_RES_0402LF-1K,1%,1/16W,EMPTY,CS21002FB06",1K,1%,R0402,11672.43,7637.65,0.000,YES,,,
R91,"Q_RES_0402LF-1K,1%,1/16W,EMPTY,CS21002FB06",1K,1%,R0402,11375.42,7637.65,0.000,YES,,,
R92,"Q_RES_0402LF-1K,1%,1/16W,EMPTY,CS21002FB06",1K,1%,R0402,11078.41,7637.65,0.000,YES,,,
R93,"Q_RES_0402LF-1K,1%,1/16W,EMPTY,CS21002FB06",1K,1%,R0402,10781.41,7637.65,0.000,YES,,,
R94,"Q_RES_0402LF-1K,1%,1/16W,EMPTY,CS21002FB06",1K,1%,R0402,10484.40,7637.65,0.000,YES,,,
R95,"Q_RES_0402LF-1K,1%,1/16W,EMPTY,CS21002FB06",1K,1%,R0402,16303.01,7527.65,0.000,YES,,,
R96,"Q_RES_0402LF-1K,1%,1/16W,EMPTY,CS21002FB06",1K,1%,R0402,16264.71,7637.65,0.000,YES,,,
R97,"Q_RES_0402LF-1K,1%,1/16W,EMPTY,CS21002FB06",1K,1%,R0402,16561.72,7637.65,0.000,YES,,,
R98,"Q_RES_0402LF-1K,1%,1/16W,EMPTY,CS21002FB06",1K,1%,R0402,16858.73,7637.65,0.000,YES,,,
R99,"Q_RES_0402LF-1K,1%,1/16W,EMPTY,CS21002FB06",1K,1%,R0402,17155.74,7637.65,0.000,YES,,,
R100,"Q_RES_0402LF-1K,1%,1/16W,EMPTY,CS21002FB06",1K,1%,R0402,17452.75,7637.65,0.000,YES,,,
R101,"Q_RES_0402LF-1K,1%,1/16W,EMPTY,CS21002FB06",1K,1%,R0402,17749.75,7637.65,0.000,YES,,,
R102,"Q_RES_0402LF-1K,1%,1/16W,EMPTY,CS21002FB06",1K,1%,R0402,1991.59,7512.66,180.000,YES,,,
R103,"Q_RES_0402LF-1K,1%,1/16W,EMPTY,CS21002FB06",1K,1%,R0402,2207.63,7637.66,0.000,YES,,,
R104,"Q_RES_0402LF-1K,1%,1/16W,EMPTY,CS21002FB06",1K,1%,R0402,1911.62,7637.66,0.000,YES,,,
R105,"Q_RES_0402LF-1K,1%,1/16W,EMPTY,CS21002FB06",1K,1%,R0402,1614.00,7637.66,0.000,YES,,,
R106,"Q_RES_0402LF-1K,1%,1/16W,EMPTY,CS21002FB06",1K,1%,R0402,1317.61,7637.66,0.000,YES,,,
R107,"Q_RES_0402LF-1K,1%,1/16W,EMPTY,CS21002FB06",1K,1%,R0402,1020.60,7637.66,0.000,YES,,,
R108,"Q_RES_0402LF-1K,1%,1/16W,EMPTY,CS21002FB06",1K,1%,R0402,555.03,7573.32,270.000,YES,,,
R109,"Q_RES_0402LF-1K,1%,1/16W,EMPTY,CS21002FB06",1K,1%,R0402,6544.90,7512.66,0.000,YES,,,
R110,"Q_RES_0402LF-1K,1%,1/16W,EMPTY,CS21002FB06",1K,1%,R0402,6503.30,7637.66,0.000,YES,,,
R111,"Q_RES_0402LF-1K,1%,1/16W,EMPTY,CS21002FB06",1K,1%,R0402,6800.31,7637.66,0.000,YES,,,
R112,"Q_RES_0402LF-1K,1%,1/16W,EMPTY,CS21002FB06",1K,1%,R0402,7097.32,7637.66,0.000,YES,,,
R113,"Q_RES_0402LF-1K,1%,1/16W,EMPTY,CS21002FB06",1K,1%,R0402,7394.32,7637.66,0.000,YES,,,
R114,"Q_RES_0402LF-1K,1%,1/16W,EMPTY,CS21002FB06",1K,1%,R0402,7691.33,7637.66,0.000,YES,,,
R115,"Q_RES_0402LF-1K,1%,1/16W,EMPTY,CS21002FB06",1K,1%,R0402,7988.34,7637.65,0.000,YES,,,
R116,"Q_RES_0402LF-33,5%,1/16W,CHIP,CS03302JB10",33,5%,R0402,6267.05,2943.05,90.000,NO,,,
R117,"Q_RES_0402LF-1K,1%,1/16W,CHIP,CS21002FB06",1K,1%,R0402,16311.67,14400.16,0.000,NO,,,
R118,"Q_RES_0402LF-0,5%,1/16W,CHIP,CS00002JB13",0,5%,R0402,16411.67,14422.28,0.000,NO,,,
R119,"Q_RES_0402LF-0,5%,1/16W,CHIP,CS00002JB13",0,5%,R0402,16481.77,14404.88,180.000,NO,,,
R120,"Q_RES_0402LF-33,5%,1/16W,CHIP,CS03302JB10",33,5%,R0402,16361.67,14404.78,270.000,NO,,,
R121,"Q_RES_0402LF-0,5%,1/16W,CHIP,CS00002JB13",0,5%,R0402,12384.54,4392.55,180.000,NO,,,
R122,"Q_RES_0402LF-0,5%,1/16W,CHIP,CS00002JB13",0,5%,R0402,16311.67,14440.16,0.000,NO,,,
R123,"Q_RES_0402LF-0,5%,1/16W,CHIP,CS00002JB13",0,5%,R0402,16210.00,14340.00,270.000,NO,,,
R124,"Q_RES_0402LF-1K,1%,1/16W,EMPTY,CS21002FB06",1K,1%,R0402,16678.10,14166.78,180.000,NO,,,
R125,"Q_RES_0402LF-0,5%,1/16W,CHIP,CS00002JB13",0,5%,R0402,12384.54,4272.55,180.000,NO,,,
R126,"Q_RES_0402LF-10K,1%,1/16W,CHIP,CS31002FB08",10K,1%,R0402,8385.58,4355.52,180.000,NO,,,
R127,"Q_RES_0402LF-1K,1%,1/16W,EMPTY,CS21002FB06",1K,1%,R0402,10230.00,5660.00,0.000,NO,,,
R128,"Q_RES_0402LF-1K,1%,1/16W,EMPTY,CS21002FB06",1K,1%,R0402,10070.11,5516.49,270.000,NO,,,
R129,"Q_RES_0402LF-1K,1%,1/16W,EMPTY,CS21002FB06",1K,1%,R0402,10070.11,5434.99,90.000,NO,,,
R130,"Q_RES_0402LF-10K,5%,1/16W,EMPTY,CS31002JB08",10K,5%,R0402,12634.72,888.64,90.000,NO,,,
R131,"Q_RES_0402LF-10K,5%,1/16W,CHIP,CS31002JB08",10K,5%,R0402,12594.72,888.64,270.000,NO,,,
R132,"Q_RES_0402LF-0,5%,1/16W,CHIP,CS00002JB13",0,5%,R0402,8385.58,4435.52,180.000,NO,,,
R133,"Q_RES_0402LF-0,5%,1/16W,CHIP,CS00002JB13",0,5%,R0402,8385.58,4635.78,180.000,NO,,,
R134,"Q_RES_0402LF-4.7K,5%,1/16W,EMPTY,CS24702JB10",4.7K,5%,R0402,8385.58,4395.52,180.000,NO,,,
R135,"Q_RES_0402LF-4.7K,5%,1/16W,EMPTY,CS24702JB10",4.7K,5%,R0402,8385.58,4555.78,180.000,NO,,,
R136,"Q_RES_0402LF-10K,1%,1/16W,EMPTY,CS31002FB08",10K,1%,R0402,8385.58,4595.78,180.000,NO,,,
R137,"Q_RES_0402LF-0,5%,1/16W,CHIP,CS00002JB13",0,5%,R0402,7075.00,3948.62,270.000,YES,,,
R138,"Q_RES_0402LF-4.7K,1%,1/16W,EMPTY,CS24702FB06",4.7K,1%,R0402,6478.66,1742.01,0.000,NO,,,
R139,"Q_RES_0402LF-0,5%,1/16W,EMPTY,CS00002JB13",0,5%,R0402,9130.00,9140.00,90.000,YES,,,
R140,"Q_RES_0402LF-0,5%,1/16W,EMPTY,CS00002JB13",0,5%,R0402,9231.50,8930.00,180.000,YES,,,
R141,"Q_RES_0402LF-0,5%,1/16W,CHIP,CS00002JB13",0,5%,R0402,7035.00,3948.62,270.000,YES,,,
R142,"Q_RES_0402LF-0,5%,1/16W,EMPTY,CS00002JB13",0,5%,R0402,9140.00,9450.00,180.000,YES,,,
R143,"Q_RES_0402LF-0,5%,1/16W,EMPTY,CS00002JB13",0,5%,R0402,9055.00,9450.00,0.000,YES,,,
R144,"Q_RES_0402LF-0,5%,1/16W,EMPTY,CS00002JB13",0,5%,R0402,9425.00,9215.00,270.000,YES,,,
R145,"Q_RES_0402LF-0,5%,1/16W,EMPTY,CS00002JB13",0,5%,R0402,9505.00,9215.00,270.000,YES,,,
R146,"Q_RES_0402LF-0,5%,1/16W,EMPTY,CS00002JB13",0,5%,R0402,9170.00,9140.00,270.000,YES,,,
R147,"Q_RES_0402LF-0,5%,1/16W,EMPTY,CS00002JB13",0,5%,R0402,9010.00,9140.00,270.000,YES,,,
R148,"Q_RES_0402LF-0,5%,1/16W,EMPTY,CS00002JB13",0,5%,R0402,9295.00,9215.00,270.000,YES,,,
R149,"Q_RES_0402LF-0,5%,1/16W,CHIP,CS00002JB13",0,5%,R0402,3719.62,5356.67,90.000,NO,,,
R150,"Q_RES_0402LF-0,5%,1/16W,EMPTY,CS00002JB13",0,5%,R0402,9231.50,8980.00,180.000,YES,,,
R151,"Q_RES_0402LF-0,5%,1/16W,CHIP,CS00002JB13",0,5%,R0402,9200.00,8930.00,0.000,YES,,,
R152,"Q_RES_0402LF-33,5%,1/16W,CHIP,CS03302JB10",33,5%,R0402,6580.00,4338.62,180.000,NO,,,
R153,"Q_RES_0402LF-0,5%,1/16W,CHIP,CS00002JB13",0,5%,R0402,6478.14,1700.53,0.000,NO,,,
R154,"Q_RES_0402LF-1K,1%,1/16W,EMPTY,CS21002FB06",1K,1%,R0402,3575.57,5864.15,180.000,NO,,,
R155,"Q_RES_0402LF-1K,1%,1/16W,EMPTY,CS21002FB06",1K,1%,R0402,6478.14,1660.53,0.000,NO,,,
R156,"Q_RES_0402LF-0,5%,1/16W,CHIP,CS00002JB13",0,5%,R0402,12826.77,8028.24,90.000,YES,,,
R157,"Q_RES_0402LF-0,5%,1/16W,CHIP,CS00002JB13",0,5%,R0402,12882.52,8012.99,0.000,YES,,,
R158,"Q_RES_0402LF-33,5%,1/16W,CHIP,CS03302JB10",33,5%,R0402,7566.52,4993.44,270.000,YES,,,
R159,"Q_RES_0402LF-33,5%,1/16W,CHIP,CS03302JB10",33,5%,R0402,7160.16,5259.25,270.000,NO,,,
R160,"Q_RES_0402LF-33,5%,1/16W,CHIP,CS03302JB10",33,5%,R0402,6740.00,4498.62,180.000,NO,,,
R161,"Q_RES_0402LF-33,5%,1/16W,CHIP,CS03302JB10",33,5%,R0402,7364.39,4993.44,270.000,YES,,,
R162,"Q_RES_0402LF-0,5%,1/16W,CHIP,CS00002JB13",0,5%,R0402,9200.00,8980.00,0.000,YES,,,
R163,"Q_RES_0402LF-33,5%,1/16W,CHIP,CS03302JB10",33,5%,R0402,6915.00,3948.62,270.000,NO,,,
R164,"Q_RES_0402LF-33,5%,1/16W,CHIP,CS03302JB10",33,5%,R0402,6740.00,4178.62,180.000,NO,,,
R165,"Q_RES_0402LF-33,5%,1/16W,CHIP,CS03302JB10",33,5%,R0402,6739.96,4178.59,0.000,YES,,,
R166,"Q_RES_0402LF-33,5%,1/16W,CHIP,CS03302JB10",33,5%,R0402,6740.00,4418.62,0.000,YES,,,
R167,"Q_RES_0402LF-0,5%,1/16W,CHIP,CS00002JB13",0,5%,R0402,6740.00,4298.62,180.000,NO,,,
R168,"Q_RES_0402LF-0,5%,1/16W,CHIP,CS00002JB13",0,5%,R0402,6740.00,4338.62,0.000,YES,,,
R169,"Q_RES_0402LF-33,5%,1/16W,CHIP,CS03302JB10",33,5%,R0402,6740.00,4133.62,180.000,NO,,,
R170,"Q_RES_0402LF-33,5%,1/16W,CHIP,CS03302JB10",33,5%,R0402,6740.00,4218.62,180.000,NO,,,
R171,"Q_RES_0402LF-33,5%,1/16W,CHIP,CS03302JB10",33,5%,R0402,6740.50,4377.32,0.000,YES,,,
R172,"Q_RES_0402LF-33,5%,1/16W,CHIP,CS03302JB10",33,5%,R0402,6743.50,4293.52,0.000,YES,,,
R173,"Q_RES_0402LF-33,5%,1/16W,CHIP,CS03302JB10",33,5%,R0402,7565.00,5258.62,90.000,NO,,,
R174,"Q_RES_0402LF-33,5%,1/16W,CHIP,CS03302JB10",33,5%,R0402,7485.00,5093.62,90.000,NO,,,
R175,"Q_RES_0402LF-0,5%,1/16W,CHIP,CS00002JB13",0,5%,R0402,3621.57,5449.15,270.000,YES,,,
R176,"Q_RES_0402LF-33,5%,1/16W,CHIP,CS03302JB10",33,5%,R0402,7766.52,4353.44,180.000,NO,,,
R177,"Q_RES_0402LF-33,5%,1/16W,CHIP,CS03302JB10",33,5%,R0402,7766.52,4393.44,180.000,NO,,,
R178,"Q_RES_0402LF-1K,1%,1/16W,CHIP,CS21002FB06",1K,1%,R0402,7117.21,2218.62,180.000,NO,,,
R179,"Q_RES_0402LF-33,5%,1/16W,CHIP,CS03302JB10",33,5%,R0402,7163.00,3783.62,270.000,NO,,,
R180,"Q_RES_0402LF-0,5%,1/16W,CHIP,CS00002JB13",0,5%,R0402,7354.57,3822.28,270.000,YES,,,
R181,"Q_RES_0402LF-0,5%,1/16W,CHIP,CS00002JB13",0,5%,R0402,7355.00,3948.62,270.000,YES,,,
R182,"Q_RES_0402LF-0,5%,1/16W,CHIP,CS00002JB13",0,5%,R0402,7675.00,3948.62,270.000,NO,,,
R183,"Q_RES_0402LF-0,5%,1/16W,CHIP,CS00002JB13",0,5%,R0402,7435.00,3948.62,90.000,NO,,,
R184,"Q_RES_0402LF-0,5%,1/16W,CHIP,CS00002JB13",0,5%,R0402,7475.00,3948.62,90.000,NO,,,
R185,"Q_RES_0402LF-0,5%,1/16W,CHIP,CS00002JB13",0,5%,R0402,7475.00,3823.62,270.000,YES,,,
R186,"Q_RES_0402LF-33,5%,1/16W,CHIP,CS03302JB10",33,5%,R0402,7641.52,4993.44,270.000,YES,,,
R187,"Q_RES_0402LF-0,5%,1/16W,CHIP,CS00002JB13",0,5%,R0402,7083.00,3783.62,90.000,NO,,,
R188,"Q_RES_0402LF-0,5%,1/16W,CHIP,CS00002JB13",0,5%,R0402,6955.00,3948.62,270.000,YES,,,
R189,"Q_RES_0402LF-0,5%,1/16W,CHIP,CS00002JB13",0,5%,R0402,7115.00,3948.62,90.000,NO,,,
R190,"Q_RES_0402LF-0,5%,1/16W,CHIP,CS00002JB13",0,5%,R0402,7075.00,3948.62,90.000,NO,,,
R191,"Q_RES_0402LF-0,5%,1/16W,EMPTY,CS00002JB13",0,5%,R0402,7005.00,5093.62,90.000,NO,,,
R192,"Q_RES_0402LF-0,5%,1/16W,EMPTY,CS00002JB13",0,5%,R0402,6965.00,5093.62,90.000,NO,,,
R193,"Q_RES_0402LF-0,5%,1/16W,CHIP,CS00002JB13",0,5%,R0402,7376.10,5136.54,270.000,YES,,,
R194,"Q_RES_0402LF-0,5%,1/16W,CHIP,CS00002JB13",0,5%,R0402,7429.56,5380.24,90.000,YES,,,
R195,"Q_RES_0402LF-33,5%,1/16W,CHIP,CS03302JB10",33,5%,R0402,8224.19,4553.44,0.000,NO,,,
R196,"Q_RES_0402LF-0,5%,1/16W,CHIP,CS00002JB13",0,5%,R0402,7230.32,5258.15,270.000,NO,,,
R197,"Q_RES_0402LF-0,5%,1/16W,CHIP,CS00002JB13",0,5%,R0402,7005.00,5258.62,270.000,NO,,,
R198,"Q_RES_0402LF-0,5%,1/16W,CHIP,CS00002JB13",0,5%,R0402,7045.00,5418.62,270.000,NO,,,
R199,"Q_RES_0402LF-33,5%,1/16W,CHIP,CS03302JB10",33,5%,R0402,7766.52,4513.44,180.000,NO,,,
R200,"Q_RES_0402LF-4.7K,5%,1/16W,EMPTY,CS24702JB10",4.7K,5%,R0402,9635.00,8590.00,270.000,YES,,,
R201,"Q_RES_0402LF-4.7K,5%,1/16W,EMPTY,CS24702JB10",4.7K,5%,R0402,9038.43,8982.02,90.000,YES,,,
R202,"Q_RES_0402LF-0,5%,1/16W,CHIP,CS00002JB13",0,5%,R0402,9105.00,8585.00,90.000,YES,,,
R203,"Q_RES_0402LF-0,5%,1/16W,CHIP,CS00002JB13",0,5%,R0402,7113.44,5238.32,90.000,YES,,,
R204,"Q_RES_0402LF-0,5%,1/16W,CHIP,CS00002JB13",0,5%,R0402,6915.00,3948.62,270.000,YES,,,
R205,"Q_RES_0402LF-0,5%,1/16W,CHIP,CS00002JB13",0,5%,R0402,6740.12,4138.63,180.000,YES,,,
R206,"Q_RES_0402LF-0,5%,1/16W,CHIP,CS00002JB13",0,5%,R0402,9055.00,8585.00,90.000,YES,,,
R207,"Q_RES_0402LF-2.2K,5%,1/16W,CHIP,CS22202JB07",2.2K,5%,R0402,13541.77,12079.88,180.000,YES,,,
R208,"Q_RES_0402LF-33,5%,1/16W,CHIP,CS03302JB10",33,5%,R0402,7911.02,4233.44,180.000,NO,,,
R209,"Q_RES_0402LF-0,5%,1/16W,CHIP,CS00002JB13",0,5%,R0402,7911.02,4273.44,180.000,NO,,,
R210,"Q_RES_0402LF-0,5%,1/16W,CHIP,CS00002JB13",0,5%,R0402,6740.00,4618.62,0.000,NO,,,
R211,"Q_RES_0402LF-0,5%,1/16W,CHIP,CS00002JB13",0,5%,R0402,6740.00,4658.62,0.000,NO,,,
R212,"Q_RES_0402LF-33,5%,1/16W,CHIP,CS03302JB10",33,5%,R0402,15486.77,12861.88,0.000,NO,,,
R213,"Q_RES_0402LF-0,5%,1/16W,CHIP,CS00002JB13",0,5%,R0402,15486.77,12821.88,0.000,NO,,,
R214,"Q_RES_0402LF-33,5%,1/16W,CHIP,CS03302JB10",33,5%,R0402,8477.57,5071.06,0.000,NO,,,
R215,"Q_RES_0402LF-33,5%,1/16W,CHIP,CS03302JB10",33,5%,R0402,7245.00,5093.62,270.000,NO,,,
R216,"Q_RES_0402LF-33,5%,1/16W,CHIP,CS03302JB10",33,5%,R0402,7045.00,5258.62,270.000,NO,,,
R217,"Q_RES_0402LF-33,5%,1/16W,CHIP,CS03302JB10",33,5%,R0402,7124.84,5245.51,270.000,NO,,,
R218,"Q_RES_0402LF-33,5%,1/16W,CHIP,CS03302JB10",33,5%,R0402,7911.02,4433.44,180.000,NO,,,
R219,"Q_RES_0402LF-33,5%,1/16W,CHIP,CS03302JB10",33,5%,R0402,7303.10,5257.83,270.000,NO,,,
R220,"Q_RES_0402LF-33,5%,1/16W,CHIP,CS03302JB10",33,5%,R0402,7595.00,3948.62,90.000,YES,,,
R221,"Q_RES_0402LF-33,5%,1/16W,CHIP,CS03302JB10",33,5%,R0402,7475.00,3948.62,90.000,YES,,,
R222,"Q_RES_0402LF-0,5%,1/16W,CHIP,CS00002JB13",0,5%,R0402,7595.00,3948.62,90.000,NO,,,
R223,"Q_RES_0402LF-0,5%,1/16W,CHIP,CS00002JB13",0,5%,R0402,7635.00,3948.62,270.000,NO,,,
R224,"Q_RES_0402LF-33,5%,1/16W,CHIP,CS03302JB10",33,5%,R0402,7812.52,4385.04,0.000,YES,,,
R225,"Q_RES_0402LF-33,5%,1/16W,CHIP,CS03302JB10",33,5%,R0402,7766.52,4233.44,180.000,NO,,,
R226,"Q_RES_0402LF-0,5%,1/16W,CHIP,CS00002JB13",0,5%,R0402,7155.00,3948.62,90.000,YES,,,
R227,"Q_RES_0402LF-33,5%,1/16W,CHIP,CS03302JB10",33,5%,R0402,7911.02,4153.44,0.000,NO,,,
R228,"Q_RES_0402LF-0,5%,1/16W,CHIP,CS00002JB13",0,5%,R0402,7911.02,4193.44,180.000,NO,,,
R229,"Q_RES_0402LF-33,5%,1/16W,CHIP,CS03302JB10",33,5%,R0402,7776.52,4153.44,0.000,YES,,,
R230,"Q_RES_0402LF-0,5%,1/16W,CHIP,CS00002JB13",0,5%,R0402,7776.52,4113.44,0.000,YES,,,
R231,"Q_RES_0402LF-0,5%,1/16W,CHIP,CS00002JB13",0,5%,R0402,7155.00,3948.62,90.000,NO,,,
R232,"Q_RES_0402LF-33,5%,1/16W,CHIP,CS03302JB10",33,5%,R0402,7435.00,3948.62,270.000,YES,,,
R233,"Q_RES_0402LF-0,5%,1/16W,CHIP,CS00002JB13",0,5%,R0402,7776.52,4073.44,0.000,YES,,,
R234,"Q_RES_0402LF-0,5%,1/16W,CHIP,CS00002JB13",0,5%,R0402,6740.72,4220.00,180.000,YES,,,
R235,"Q_RES_0402LF-0,5%,1/16W,CHIP,CS00002JB13",0,5%,R0402,7043.00,3783.62,90.000,NO,,,
R236,"Q_RES_0402LF-0,5%,1/16W,CHIP,CS00002JB13",0,5%,R0402,6995.00,3948.62,90.000,NO,,,
R237,"Q_RES_0402LF-0,5%,1/16W,CHIP,CS00002JB13",0,5%,R0402,6955.00,3948.62,90.000,NO,,,
R238,"Q_RES_0402LF-0,5%,1/16W,CHIP,CS00002JB13",0,5%,R0402,6908.00,3783.62,90.000,NO,,,
R239,"Q_RES_0402LF-0,5%,1/16W,CHIP,CS00002JB13",0,5%,R0402,7003.00,3783.62,90.000,NO,,,
R240,"Q_RES_0402LF-100,1%,1/16W,CHIP,CS11002FB07",100,1%,R0402,885.00,14305.00,180.000,YES,,,
R241,"Q_RES_0402LF-0,5%,1/16W,CHIP,CS00002JB13",0,5%,R0402,7205.00,5093.62,270.000,NO,,,
R242,"Q_RES_0402LF-0,5%,1/16W,CHIP,CS00002JB13",0,5%,R0402,7086.52,4993.44,90.000,YES,,,
R243,"Q_RES_0402LF-0,5%,1/16W,CHIP,CS00002JB13",0,5%,R0402,7035.00,3948.62,90.000,NO,,,
R244,"Q_RES_0402LF-0,5%,1/16W,CHIP,CS00002JB13",0,5%,R0402,6875.60,3948.62,270.000,YES,,,
R245,"Q_RES_0402LF-0,5%,1/16W,CHIP,CS00002JB13",0,5%,R0402,7270.00,3808.62,0.000,YES,,,
R246,"Q_RES_0402LF-0,5%,1/16W,CHIP,CS00002JB13",0,5%,R0402,7123.00,3783.62,90.000,NO,,,
R247,"Q_RES_0402LF-33,5%,1/16W,CHIP,CS03302JB10",33,5%,R0402,12816.77,7634.88,270.000,NO,,,
R248,"Q_RES_0402LF-33,5%,1/16W,CHIP,CS03302JB10",33,5%,R0402,6885.00,5418.62,90.000,NO,,,
R249,"Q_RES_0402LF-33,5%,1/16W,CHIP,CS03302JB10",33,5%,R0402,6925.00,5093.62,90.000,NO,,,
R250,"Q_RES_0402LF-0,5%,1/16W,CHIP,CS00002JB13",0,5%,R0402,7325.00,5093.62,90.000,NO,,,
R251,"Q_RES_0402LF-0,5%,1/16W,CHIP,CS00002JB13",0,5%,R0402,7519.72,4994.56,270.000,YES,,,
R252,"Q_RES_0402LF-0,5%,1/16W,CHIP,CS00002JB13",0,5%,R0402,7650.00,5418.62,90.000,NO,,,
R253,"Q_RES_0402LF-0,5%,1/16W,CHIP,CS00002JB13",0,5%,R0402,7126.52,4993.44,90.000,YES,,,
R254,"Q_RES_0402LF-0,5%,1/16W,CHIP,CS00002JB13",0,5%,R0402,7006.52,4993.44,90.000,YES,,,
R255,"Q_RES_0402LF-0,5%,1/16W,CHIP,CS00002JB13",0,5%,R0402,6950.52,5025.34,180.000,YES,,,
R256,"Q_RES_0402LF-0,5%,1/16W,EMPTY,CS00002JB13",0,5%,R0402,9256.50,8471.91,0.000,YES,,,
R257,"Q_RES_0402LF-0,5%,1/16W,EMPTY,CS00002JB13",0,5%,R0402,9255.37,8396.01,0.000,YES,,,
R258,"Q_RES_0402LF-0,5%,1/16W,CHIP,CS00002JB13",0,5%,R0402,7445.00,5093.62,90.000,NO,,,
R259,"Q_RES_0402LF-33,5%,1/16W,CHIP,CS03302JB10",33,5%,R0402,8080.35,4273.44,180.000,NO,,,
R260,"Q_RES_0402LF-0,5%,1/16W,CHIP,CS00002JB13",0,5%,R0402,7515.00,3823.62,270.000,YES,,,
R261,"Q_RES_0402LF-0,5%,1/16W,CHIP,CS00002JB13",0,5%,R0402,7434.57,3822.28,270.000,YES,,,
R262,"Q_RES_0402LF-0,5%,1/16W,CHIP,CS00002JB13",0,5%,R0402,7394.57,3822.28,270.000,YES,,,
R263,"Q_RES_0402LF-0,5%,1/16W,CHIP,CS00002JB13",0,5%,R0402,7515.00,3948.62,90.000,NO,,,
R264,"Q_RES_0402LF-0,5%,1/16W,CHIP,CS00002JB13",0,5%,R0402,7555.00,3948.62,90.000,NO,,,
R265,"Q_RES_0402LF-33,5%,1/16W,CHIP,CS03302JB10",33,5%,R0402,7766.52,4993.44,180.000,YES,,,
R266,"Q_RES_0402LF-33,5%,1/16W,CHIP,CS03302JB10",33,5%,R0402,7635.00,3823.62,90.000,YES,,,
R267,"Q_RES_0402LF-33,5%,1/16W,CHIP,CS03302JB10",33,5%,R0402,7675.00,3948.62,270.000,YES,,,
R268,"Q_RES_0402LF-0,5%,1/16W,CHIP,CS00002JB13",0,5%,R0402,7555.00,3948.62,270.000,YES,,,
R269,"Q_RES_0402LF-0,5%,1/16W,CHIP,CS00002JB13",0,5%,R0402,7515.00,3948.62,270.000,YES,,,
R270,"Q_RES_0402LF-33,5%,1/16W,CHIP,CS03302JB10",33,5%,R0402,7235.00,3948.62,270.000,NO,,,
R271,"Q_RES_0402LF-0,5%,1/16W,CHIP,CS00002JB13",0,5%,R0402,7635.00,3783.62,270.000,NO,,,
R272,"Q_RES_0402LF-0,5%,1/16W,EMPTY,CS00002JB13",0,5%,R0402,7125.00,5093.62,270.000,NO,,,
R273,"Q_RES_0402LF-33,5%,1/16W,CHIP,CS03302JB10",33,5%,R0402,7085.00,5093.62,270.000,NO,,,
R274,"Q_RES_0402LF-0,5%,1/16W,CHIP,CS00002JB13",0,5%,R0402,9225.00,8471.91,180.000,YES,,,
R275,"Q_RES_0402LF-33,5%,1/16W,CHIP,CS03302JB10",33,5%,R0402,7396.52,3948.44,270.000,YES,,,
R276,"Q_RES_0402LF-4.7K,5%,1/16W,CHIP,CS24702JB10",4.7K,5%,R0402,15831.77,12637.88,90.000,NO,,,
R277,"Q_RES_0402LF-33,5%,1/16W,CHIP,CS03302JB10",33,5%,R0402,7565.00,5093.62,90.000,NO,,,
R278,"Q_RES_0402LF-0,5%,1/16W,CHIP,CS00002JB13",0,5%,R0402,7115.00,3948.62,90.000,YES,,,
R279,"Q_RES_0402LF-33,5%,1/16W,CHIP,CS03302JB10",33,5%,R0402,7766.52,4273.44,180.000,NO,,,
R280,"Q_RES_0402LF-0,5%,1/16W,CHIP,CS00002JB13",0,5%,R0402,7766.52,4313.44,180.000,NO,,,
R281,"Q_RES_0402LF-0,5%,1/16W,CHIP,CS00002JB13",0,5%,R0402,9223.87,8396.01,180.000,YES,,,
R282,"Q_RES_0402LF-33,5%,1/16W,CHIP,CS03302JB10",33,5%,R0402,7766.52,4433.44,180.000,NO,,,
R283,"Q_RES_0402LF-0,5%,1/16W,CHIP,CS00002JB13",0,5%,R0402,7766.52,4473.44,180.000,NO,,,
R284,"Q_RES_0402LF-0,5%,1/16W,CHIP,CS00002JB13",0,5%,R0402,7195.00,3948.62,270.000,NO,,,
R285,"Q_RES_0402LF-33,5%,1/16W,CHIP,CS03302JB10",33,5%,R0402,7766.52,4233.44,180.000,YES,,,
R286,"Q_RES_0402LF-0,5%,1/16W,CHIP,CS00002JB13",0,5%,R0402,7766.52,4273.44,0.000,YES,,,
R287,"Q_RES_0402LF-4.7K,5%,1/16W,EMPTY,CS24702JB10",4.7K,5%,R0402,15791.77,12637.88,270.000,NO,,,
R288,"Q_RES_0402LF-4.7K,5%,1/16W,EMPTY,CS24702JB10",4.7K,5%,R0402,16011.77,12909.88,180.000,YES,,,
R289,"Q_RES_0402LF-33,5%,1/16W,CHIP,CS03302JB10",33,5%,R0402,7766.52,4193.44,0.000,YES,,,
R290,"Q_RES_0402LF-1K,1%,1/16W,EMPTY,CS21002FB06",1K,1%,R0402,9040.00,8530.00,180.000,YES,,,
R291,"Q_RES_0402LF-1K,1%,1/16W,CHIP,CS21002FB06",1K,1%,R0402,11823.01,7512.65,0.000,YES,,,
R292,"Q_RES_0402LF-1K,1%,1/16W,CHIP,CS21002FB06",1K,1%,R0402,11633.01,7517.65,180.000,YES,,,
R293,"Q_RES_0402LF-1K,1%,1/16W,CHIP,CS21002FB06",1K,1%,R0402,11338.01,7517.65,180.000,YES,,,
R294,"Q_RES_0402LF-1K,1%,1/16W,CHIP,CS21002FB06",1K,1%,R0402,11043.01,7517.65,180.000,YES,,,
R295,"Q_RES_0402LF-1K,1%,1/16W,CHIP,CS21002FB06",1K,1%,R0402,10758.01,7517.65,180.000,YES,,,
R296,"Q_RES_0402LF-1K,1%,1/16W,CHIP,CS21002FB06",1K,1%,R0402,10453.01,7512.65,180.000,YES,,,
R297,"Q_RES_0402LF-1K,1%,1/16W,CHIP,CS21002FB06",1K,1%,R0402,16228.01,7527.65,180.000,YES,,,
R298,"Q_RES_0402LF-1K,1%,1/16W,CHIP,CS21002FB06",1K,1%,R0402,16523.01,7532.65,180.000,YES,,,
R299,"Q_RES_0402LF-1K,1%,1/16W,CHIP,CS21002FB06",1K,1%,R0402,16833.01,7532.65,180.000,YES,,,
R300,"Q_RES_0402LF-1K,1%,1/16W,CHIP,CS21002FB06",1K,1%,R0402,17118.01,7527.65,180.000,YES,,,
R301,"Q_RES_0402LF-1K,1%,1/16W,CHIP,CS21002FB06",1K,1%,R0402,17413.01,7527.65,180.000,YES,,,
R302,"Q_RES_0402LF-1K,1%,1/16W,CHIP,CS21002FB06",1K,1%,R0402,17713.01,7532.65,180.000,YES,,,
R303,"Q_RES_0402LF-1K,1%,1/16W,CHIP,CS21002FB06",1K,1%,R0402,2061.59,7512.66,0.000,YES,,,
R304,"Q_RES_0402LF-1K,1%,1/16W,CHIP,CS21002FB06",1K,1%,R0402,1871.59,7517.66,180.000,YES,,,
R305,"Q_RES_0402LF-1K,1%,1/16W,CHIP,CS21002FB06",1K,1%,R0402,1576.59,7517.66,180.000,YES,,,
R306,"Q_RES_0402LF-1K,1%,1/16W,CHIP,CS21002FB06",1K,1%,R0402,1281.59,7517.66,180.000,YES,,,
R307,"Q_RES_0402LF-1K,1%,1/16W,CHIP,CS21002FB06",1K,1%,R0402,996.59,7517.66,180.000,YES,,,
R308,"Q_RES_0402LF-33,5%,1/16W,CHIP,CS03302JB10",33,5%,R0402,3678.00,5440.00,0.000,YES,,,
R309,"Q_RES_0402LF-33,5%,1/16W,CHIP,CS03302JB10",33,5%,R0402,3678.00,5480.00,0.000,YES,,,
R310,"Q_RES_0402LF-1K,1%,1/16W,CHIP,CS21002FB06",1K,1%,R0402,6764.90,7517.66,180.000,YES,,,
R311,"Q_RES_0402LF-1K,1%,1/16W,CHIP,CS21002FB06",1K,1%,R0402,7059.90,7517.66,180.000,YES,,,
R312,"Q_RES_0402LF-1K,1%,1/16W,CHIP,CS21002FB06",1K,1%,R0402,7354.90,7517.66,180.000,YES,,,
R313,"Q_RES_0402LF-1K,1%,1/16W,CHIP,CS21002FB06",1K,1%,R0402,7544.90,7512.66,0.000,YES,,,
R314,"Q_RES_0402LF-1K,1%,1/16W,CHIP,CS21002FB06",1K,1%,R0402,7958.95,7517.65,180.000,YES,,,
R315,"Q_RES_0402LF-49.9,1%,1/16W,CHIP,CS04992FB07",49.9,1%,R0402,14682.57,5569.77,180.000,YES,,,
R316,"Q_RES_0402LF-10K,1%,1/16W,EMPTY,CS31002FB08",10K,1%,R0402,11712.06,4816.91,180.000,NO,,,
R317,"Q_RES_0402LF-1K,1%,1/16W,CHIP,CS21002FB06",1K,1%,R0402,11591.38,4816.91,0.000,NO,,,
R318,"Q_RES_0402LF-10K,1%,1/16W,EMPTY,CS31002FB08",10K,1%,R0402,10919.38,4896.41,0.000,NO,,,
R319,"Q_RES_0402LF-1K,1%,1/16W,CHIP,CS21002FB06",1K,1%,R0402,11004.48,4843.91,180.000,NO,,,
R320,"Q_RES_0402LF-10K,1%,1/16W,EMPTY,CS31002FB08",10K,1%,R0402,10919.38,4946.41,0.000,NO,,,
R321,"Q_RES_0402LF-0,5%,1/16W,CHIP,CS00002JB13",0,5%,R0402,5351.17,355.35,270.000,YES,,,
R322,"Q_RES_0402LF-1K,1%,1/16W,EMPTY,CS21002FB06",1K,1%,R0402,9125.00,8530.00,0.000,YES,,,
R323,"Q_RES_0402LF-0,5%,1/16W,EMPTY,CS00002JB13",0,5%,R0402,9075.00,9545.00,90.000,YES,,,
R324,"Q_RES_0402LF-0,5%,1/16W,EMPTY,CS00002JB13",0,5%,R0402,9125.00,9545.00,90.000,YES,,,
R325,"Q_RES_0402LF-0,5%,1/16W,CHIP,CS00002JB13",0,5%,R0402,9125.00,9576.50,270.000,YES,,,
R326,"Q_RES_0402LF-0,5%,1/16W,CHIP,CS00002JB13",0,5%,R0402,9075.00,9576.50,270.000,YES,,,
R327,"Q_RES_0402LF-0,5%,1/16W,CHIP,CS00002JB13",0,5%,R0402,9323.50,9825.00,180.000,YES,,,
R328,"Q_RES_0402LF-0,5%,1/16W,CHIP,CS00002JB13",0,5%,R0402,9323.50,9775.00,180.000,YES,,,
R329,"Q_RES_0402LF-2K,1%,1/16W,EMPTY,CS22002FB07",2K,1%,R0402,6494.07,685.72,180.000,YES,,,
R330,"Q_RES_0402LF-2.2K,5%,1/16W,EMPTY,CS22202JB07",2.2K,5%,R0402,6205.45,556.82,180.000,YES,,,
R331,"Q_RES_0402LF-2.2K,5%,1/16W,EMPTY,CS22202JB07",2.2K,5%,R0402,6237.82,651.73,180.000,YES,,,
R332,"Q_RES_0402LF-2.2K,5%,1/16W,EMPTY,CS22202JB07",2.2K,5%,R0402,6862.91,541.82,270.000,YES,,,
R333,"Q_RES_0402LF-0,5%,1/16W,CHIP,CS00002JB13",0,5%,R0402,5846.23,4279.49,180.000,NO,,,
R334,"Q_RES_0402LF-100K,1%,1/16W,CHIP,CS41002FB09",100K,1%,R0402,5846.23,4239.49,0.000,NO,,,
R335,"Q_RES_0402LF-10K,1%,1/16W,CHIP,CS31002FB08",10K,1%,R0402,15740.00,5670.00,270.000,YES,,,
R336,"Q_RES_0402LF-100K,1%,1/16W,CHIP,CS41002FB09",100K,1%,R0402,5546.73,4239.49,0.000,NO,,,
R337,"Q_RES_0402LF-0,5%,1/16W,CHIP,CS00002JB13",0,5%,R0402,9285.00,9496.50,90.000,YES,,,
R338,"Q_RES_0402LF-0,5%,1/16W,CHIP,CS00002JB13",0,5%,R0402,9235.00,9496.50,90.000,YES,,,
R339,"Q_RES_0201LF-49.9,1%,1/20W,EMPTY,CS04991FE06",49.9,1%,R0201,5127.20,1073.20,180.000,NO,,,
R340,"Q_RES_0201LF-49.9,1%,1/20W,EMPTY,CS04991FE06",49.9,1%,R0201,5193.20,1073.20,0.000,NO,,,
R341,"Q_RES_0402LF-51,5%,1/16W,EMPTY,CS05102JB04",51,5%,R0402,5749.35,1227.85,0.000,NO,,,
R342,"Q_RES_0402LF-51,5%,1/16W,EMPTY,CS05102JB04",51,5%,R0402,5667.85,1227.85,180.000,NO,,,
R343,"Q_RES_0201LF-49.9,1%,1/20W,EMPTY,CS04991FE06",49.9,1%,R0201,4094.43,1306.51,90.000,NO,,,
R344,"Q_RES_0201LF-49.9,1%,1/20W,EMPTY,CS04991FE06",49.9,1%,R0201,4062.43,1174.01,90.000,NO,,,
R345,"Q_RES_0201LF-49.9,1%,1/20W,EMPTY,CS04991FE06",49.9,1%,R0201,4094.43,1251.51,270.000,NO,,,
R346,"Q_RES_0201LF-49.9,1%,1/20W,EMPTY,CS04991FE06",49.9,1%,R0201,4062.43,1119.01,270.000,NO,,,
R347,"Q_RES_0402LF-33.2,1%,1/16W,CHIP,CS03322FB03",33.2,1%,R0402,7007.28,16230.62,180.000,NO,,,
R348,"Q_RES_0402LF-33.2,1%,1/16W,CHIP,CS03322FB03",33.2,1%,R0402,7041.41,16166.56,0.000,NO,,,
R349,"Q_RES_0402LF-33,5%,1/16W,CHIP,CS03302JB10",33,5%,R0402,6300.00,14030.00,90.000,NO,,,
R350,"Q_RES_0402LF-33,5%,1/16W,CHIP,CS03302JB10",33,5%,R0402,6350.00,14030.00,90.000,NO,,,
R351,"Q_RES_0402LF-33,5%,1/16W,CHIP,CS03302JB10",33,5%,R0402,12831.00,14340.00,0.000,NO,,,
R352,"Q_RES_0402LF-33,5%,1/16W,CHIP,CS03302JB10",33,5%,R0402,12831.00,14300.00,0.000,NO,,,
R353,"Q_RES_0402LF-0,5%,1/16W,CHIP,CS00002JB13",0,5%,R0402,11150.05,15810.51,90.000,NO,,,
R354,"Q_RES_0402LF-10.5K,1%,1/16W,CHIP,CS31052FB03",10.5K,1%,R0402,11150.27,15947.51,270.000,NO,,,
R355,"Q_RES_0402LF-10.5K,1%,1/16W,CHIP,CS31052FB03",10.5K,1%,R0402,11095.58,15460.86,90.000,NO,,,
R356,"Q_RES_0402LF-0,5%,1/16W,CHIP,CS00002JB13",0,5%,R0402,12926.77,7639.88,270.000,NO,,,
R357,"Q_RES_0402LF-0,5%,1/16W,CHIP,CS00002JB13",0,5%,R0402,12966.77,7639.88,270.000,NO,,,
R358,"Q_RES_0402LF-0,5%,1/16W,EMPTY,CS00002JB13",0,5%,R0402,9345.00,9215.00,270.000,YES,,,
R359,"Q_RES_0402LF-1K,1%,1/16W,CHIP,CS21002FB06",1K,1%,R0402,9195.00,9465.00,270.000,YES,,,
R360,"Q_RES_0402LF-1K,1%,1/16W,CHIP,CS21002FB06",1K,1%,R0402,9355.00,9735.00,0.000,YES,,,
R361,"Q_RES_0402LF-4.7K,5%,1/16W,EMPTY,CS24702JB10",4.7K,5%,R0402,9365.00,8505.00,180.000,YES,,,
R362,"Q_RES_0402LF-1K,1%,1/16W,CHIP,CS21002FB06",1K,1%,R0402,9325.00,9465.00,270.000,YES,,,
R363,"Q_RES_0402LF-1K,1%,1/16W,CHIP,CS21002FB06",1K,1%,R0402,9355.00,9865.00,0.000,YES,,,
R364,"Q_RES_0402LF-0,5%,1/16W,CHIP,CS00002JB13",0,5%,R0402,5863.94,916.73,270.000,NO,,,
R365,"Q_RES_0402LF-4.7K,5%,1/16W,EMPTY,CS24702JB10",4.7K,5%,R0402,9445.00,8505.00,0.000,YES,,,
R366,"Q_RES_0402LF-1K,1%,1/16W,CHIP,CS21002FB06",1K,1%,R0402,9385.00,9120.00,270.000,YES,,,
R367,"Q_RES_0402LF-1K,1%,1/16W,CHIP,CS21002FB06",1K,1%,R0402,9545.00,9120.00,270.000,YES,,,
R368,"Q_RES_0402LF-4.7K,5%,1/16W,EMPTY,CS24702JB10",4.7K,5%,R0402,9555.00,9035.00,180.000,YES,,,
R369,"Q_RES_0402LF-1K,1%,1/16W,CHIP,CS21002FB06",1K,1%,R0402,9255.00,9120.00,270.000,YES,,,
R370,"Q_RES_0402LF-1K,1%,1/16W,CHIP,CS21002FB06",1K,1%,R0402,9465.00,9120.00,270.000,YES,,,
R371,"Q_RES_0402LF-33,5%,1/16W,CHIP,CS03302JB10",33,5%,R0402,7085.00,5418.62,270.000,NO,,,
R372,"Q_RES_0402LF-33,5%,1/16W,CHIP,CS03302JB10",33,5%,R0402,7605.00,5258.62,90.000,NO,,,
R373,"Q_RES_0402LF-0,5%,1/16W,EMPTY,CS00002JB13",0,5%,R0402,5891.71,12666.68,180.000,NO,,,
R374,"Q_RES_0402LF-0,5%,1/16W,CHIP,CS00002JB13",0,5%,R0402,5891.71,12626.68,180.000,NO,,,
R375,"Q_RES_0402LF-15,1%,1/16W,CHIP,CS01502FB03",15,1%,R0402,12052.57,9609.65,0.000,YES,,,
R376,"Q_RES_0402LF-15,1%,1/16W,CHIP,CS01502FB03",15,1%,R0402,11843.35,9609.65,180.000,YES,,,
R377,"Q_RES_0402LF-15,1%,1/16W,CHIP,CS01502FB03",15,1%,R0402,11546.34,9609.65,180.000,YES,,,
R378,"Q_RES_0402LF-15,1%,1/16W,CHIP,CS01502FB03",15,1%,R0402,11249.33,9609.65,180.000,YES,,,
R379,"Q_RES_0402LF-15,1%,1/16W,CHIP,CS01502FB03",15,1%,R0402,10952.33,9609.65,180.000,YES,,,
R380,"Q_RES_0402LF-15,1%,1/16W,CHIP,CS01502FB03",15,1%,R0402,10655.32,9609.65,180.000,YES,,,
R381,"Q_RES_0402LF-15,1%,1/16W,CHIP,CS01502FB03",15,1%,R0402,16357.13,9609.65,0.000,YES,,,
R382,"Q_RES_0402LF-15,1%,1/16W,CHIP,CS01502FB03",15,1%,R0402,16654.14,9609.65,0.000,YES,,,
R383,"Q_RES_0402LF-15,1%,1/16W,CHIP,CS01502FB03",15,1%,R0402,16951.15,9609.65,0.000,YES,,,
R384,"Q_RES_0402LF-15,1%,1/16W,CHIP,CS01502FB03",15,1%,R0402,17248.16,9609.65,0.000,YES,,,
R385,"Q_RES_0402LF-15,1%,1/16W,CHIP,CS01502FB03",15,1%,R0402,17545.17,9609.65,0.000,YES,,,
R386,"Q_RES_0402LF-15,1%,1/16W,CHIP,CS01502FB03",15,1%,R0402,17842.17,9609.65,0.000,YES,,,
R387,"Q_RES_0402LF-2.2K,5%,1/16W,CHIP,CS22202JB07",2.2K,5%,R0402,12641.77,8028.24,270.000,YES,,,
R388,"Q_RES_0402LF-2.2K,5%,1/16W,CHIP,CS22202JB07",2.2K,5%,R0402,12571.77,8028.24,270.000,YES,,,
R389,"Q_RES_0402LF-2.2K,5%,1/16W,CHIP,CS22202JB07",2.2K,5%,R0402,15486.77,12701.88,180.000,NO,,,
R390,"Q_RES_0402LF-2.2K,5%,1/16W,CHIP,CS22202JB07",2.2K,5%,R0402,12531.77,8028.24,270.000,YES,,,
R391,"Q_RES_0402LF-2.2K,5%,1/16W,CHIP,CS22202JB07",2.2K,5%,R0402,7595.00,3783.62,90.000,NO,,,
R392,"Q_RES_0402LF-2.2K,5%,1/16W,EMPTY,CS22202JB07",2.2K,5%,R0402,13339.77,12173.78,90.000,YES,,,
R393,"Q_RES_0402LF-2.2K,5%,1/16W,CHIP,CS22202JB07",2.2K,5%,R0402,13379.77,12173.78,270.000,YES,,,
R394,"Q_RES_0402LF-2.2K,5%,1/16W,CHIP,CS22202JB07",2.2K,5%,R0402,13294.77,12173.78,270.000,YES,,,
R395,"Q_RES_0402LF-0,5%,1/16W,CHIP,CS00002JB13",0,5%,R0402,7606.52,4993.44,270.000,YES,,,
R396,"Q_RES_0402LF-2.2K,5%,1/16W,CHIP,CS22202JB07",2.2K,5%,R0402,12731.77,8028.24,270.000,YES,,,
R397,"Q_RES_0402LF-2.2K,5%,1/16W,CHIP,CS22202JB07",2.2K,5%,R0402,7354.49,3735.28,270.000,NO,,,
R398,"Q_RES_0402LF-1K,1%,1/16W,CHIP,CS21002FB06",1K,1%,R0402,14811.77,8074.88,270.000,YES,,,
R399,"Q_RES_0402LF-1K,1%,1/16W,CHIP,CS21002FB06",1K,1%,R0402,15021.77,8209.88,270.000,YES,,,
R400,"Q_RES_0402LF-1K,1%,1/16W,CHIP,CS21002FB06",1K,1%,R0402,14741.77,8209.88,270.000,YES,,,
R401,"Q_RES_0402LF-1K,1%,1/16W,CHIP,CS21002FB06",1K,1%,R0402,14861.77,8209.88,270.000,YES,,,
R402,"Q_RES_0402LF-1K,1%,1/16W,CHIP,CS21002FB06",1K,1%,R0402,14901.77,8209.88,270.000,YES,,,
R403,"Q_RES_0402LF-1K,1%,1/16W,CHIP,CS21002FB06",1K,1%,R0402,14851.77,8074.88,270.000,YES,,,
R404,"Q_RES_0402LF-0,5%,1/16W,CHIP,CS00002JB13",0,5%,R0402,14731.77,8074.88,90.000,YES,,,
R405,"Q_RES_0402LF-0,5%,1/16W,CHIP,CS00002JB13",0,5%,R0402,13623.11,12146.37,0.000,YES,,,
R406,"Q_RES_0402LF-4.7K,5%,1/16W,EMPTY,CS24702JB10",4.7K,5%,R0402,9625.00,9035.00,0.000,YES,,,
R407,"Q_RES_0402LF-0,5%,1/16W,CHIP,CS00002JB13",0,5%,R0402,6446.70,4619.30,180.000,YES,,,
R408,"Q_RES_0402LF-2.2K,5%,1/16W,CHIP,CS22202JB07",2.2K,5%,R0402,12631.77,7818.24,0.000,YES,,,
R409,"Q_RES_0402LF-2.2K,5%,1/16W,CHIP,CS22202JB07",2.2K,5%,R0402,12631.77,7778.24,0.000,YES,,,
R410,"Q_RES_0402LF-2.2K,5%,1/16W,CHIP,CS22202JB07",2.2K,5%,R0402,12711.77,7743.24,0.000,YES,,,
R411,"Q_RES_0402LF-2.2K,5%,1/16W,CHIP,CS22202JB07",2.2K,5%,R0402,12711.77,7703.24,0.000,YES,,,
R412,"Q_RES_0402LF-2.2K,5%,1/16W,CHIP,CS22202JB07",2.2K,5%,R0402,12736.77,7634.88,270.000,NO,,,
R413,"Q_RES_0402LF-2.2K,5%,1/16W,CHIP,CS22202JB07",2.2K,5%,R0402,12826.77,7957.24,90.000,YES,,,
R414,"Q_RES_0402LF-2.2K,5%,1/16W,CHIP,CS22202JB07",2.2K,5%,R0402,12866.77,7957.24,90.000,YES,,,
R415,"Q_RES_0402LF-2.2K,5%,1/16W,CHIP,CS22202JB07",2.2K,5%,R0402,12886.77,7604.88,270.000,NO,,,
R416,"Q_RES_0402LF-2.2K,5%,1/16W,CHIP,CS22202JB07",2.2K,5%,R0402,13006.77,7604.88,270.000,NO,,,
R417,"Q_RES_0402LF-2.2K,5%,1/16W,CHIP,CS22202JB07",2.2K,5%,R0402,15601.57,12643.63,90.000,NO,,,
R418,"Q_RES_0402LF-2.2K,5%,1/16W,CHIP,CS22202JB07",2.2K,5%,R0402,12776.77,7634.88,270.000,NO,,,
R419,"Q_RES_0402LF-0,5%,1/16W,CHIP,CS00002JB13",0,5%,R0402,6520.65,4869.41,0.000,NO,,,
R420,"Q_RES_0402LF-1K,1%,1/16W,EMPTY,CS21002FB06",1K,1%,R0402,15040.00,8074.88,270.000,YES,,,
R421,"Q_RES_0402LF-1K,1%,1/16W,EMPTY,CS21002FB06",1K,1%,R0402,14931.77,8074.88,270.000,YES,,,
R422,"Q_RES_0402LF-2.2K,5%,1/16W,CHIP,CS22202JB07",2.2K,5%,R0402,11536.93,2048.35,0.000,NO,,,
R423,"Q_RES_0402LF-1K,1%,1/16W,EMPTY,CS21002FB06",1K,1%,R0402,12575.00,7650.00,0.000,NO,,,
R424,"Q_RES_0402LF-2.2K,5%,1/16W,CHIP,CS22202JB07",2.2K,5%,R0402,11536.93,2098.35,0.000,NO,,,
R425,"Q_RES_0402LF-1K,1%,1/16W,EMPTY,CS21002FB06",1K,1%,R0402,12645.00,7650.00,180.000,NO,,,
R426,"Q_RES_0402LF-0,5%,1/16W,CHIP,CS00002JB13",0,5%,R0402,12637.06,7594.40,270.000,NO,,,
R427,"Q_RES_0402LF-0,5%,1/16W,CHIP,CS00002JB13",0,5%,R0402,12567.85,7594.40,270.000,NO,,,
R428,"Q_RES_0402LF-0,5%,1/16W,CHIP,CS00002JB13",0,5%,R0402,14971.77,8074.88,270.000,YES,,,
R429,"Q_RES_0402LF-0,5%,1/16W,CHIP,CS00002JB13",0,5%,R0402,15081.77,8074.88,270.000,YES,,,
R430,"Q_RES_0402LF-0,5%,1/16W,CHIP,CS00002JB13",0,5%,R0402,15908.27,12588.54,270.000,YES,,,
R431,"Q_RES_0402LF-0,5%,1/16W,CHIP,CS00002JB13",0,5%,R0402,15948.27,12588.54,270.000,YES,,,
R432,"Q_RES_0402LF-10M,1%,1/16W,CHIP,CS61002FB02",10M,1%,R0402,15596.77,12341.62,180.000,YES,,,
R433,"Q_RES_0402LF-20M,1%,1/16W,CHIP,CS62002FB01",20M,1%,R0402,15778.03,12353.66,180.000,YES,,,
R434,"Q_RES_0402LF-33,5%,1/16W,CHIP,CS03302JB10",33,5%,R0402,16011.77,12829.88,180.000,YES,,,
R435,"Q_RES_0402LF-0,5%,1/16W,CHIP,CS00002JB13",0,5%,R0402,13368.77,8459.88,90.000,YES,,,
R436,"Q_RES_0402LF-0,5%,1/16W,CHIP,CS00002JB13",0,5%,R0402,13328.77,8459.88,90.000,YES,,,
R437,"Q_RES_0402LF-2.2K,5%,1/16W,CHIP,CS22202JB07",2.2K,5%,R0402,15486.77,12741.88,180.000,NO,,,
R438,"Q_RES_0402LF-4.7K,5%,1/16W,EMPTY,CS24702JB10",4.7K,5%,R0402,12731.77,7833.24,0.000,YES,,,
R439,"Q_RES_0402LF-0,5%,1/16W,CHIP,CS00002JB13",0,5%,R0402,6445.00,4880.00,180.000,NO,,,
R440,"Q_RES_0402LF-4.7K,5%,1/16W,EMPTY,CS24702JB10",4.7K,5%,R0402,16011.77,12869.88,0.000,YES,,,
R441,"Q_RES_0402LF-2.2K,5%,1/16W,CHIP,CS22202JB07",2.2K,5%,R0402,15792.05,13045.69,90.000,YES,,,
R442,"Q_RES_0402LF-1K,1%,1/16W,CHIP,CS21002FB06",1K,1%,R0402,12691.77,8028.24,90.000,YES,,,
R443,"Q_RES_0402LF-1K,1%,1/16W,CHIP,CS21002FB06",1K,1%,R0402,12606.77,8028.24,90.000,YES,,,
R444,"Q_RES_0402LF-4.7K,5%,1/16W,CHIP,CS24702JB10",4.7K,5%,R0402,16011.77,12989.88,180.000,YES,,,
R445,"Q_RES_0402LF-4.7K,5%,1/16W,CHIP,CS24702JB10",4.7K,5%,R0402,16011.77,12949.88,180.000,YES,,,
R446,"Q_RES_0402LF-4.7K,5%,1/16W,CHIP,CS24702JB10",4.7K,5%,R0402,15839.47,12644.88,180.000,YES,,,
R447,"Q_RES_0402LF-4.7K,5%,1/16W,CHIP,CS24702JB10",4.7K,5%,R0402,15839.47,12605.88,180.000,YES,,,
R448,"Q_RES_0402LF-4.7K,5%,1/16W,EMPTY,CS24702JB10",4.7K,5%,R0402,15911.77,12637.88,90.000,NO,,,
R449,"Q_RES_0402LF-4.7K,5%,1/16W,EMPTY,CS24702JB10",4.7K,5%,R0402,15871.77,12637.88,90.000,NO,,,
R450,"Q_RES_0402LF-4.7K,5%,1/16W,CHIP,CS24702JB10",4.7K,5%,R0402,15486.77,12781.88,0.000,NO,,,
R451,"Q_RES_0402LF-4.7K,5%,1/16W,CHIP,CS24702JB10",4.7K,5%,R0402,15928.52,13025.58,90.000,YES,,,
R452,"Q_RES_0402LF-4.7K,5%,1/16W,CHIP,CS24702JB10",4.7K,5%,R0402,12731.77,7873.24,0.000,YES,,,
R453,"Q_RES_0402LF-10K,5%,1/16W,CHIP,CS31002JB08",10K,5%,R0402,7958.75,13459.23,180.000,YES,,,
R454,"Q_RES_0402LF-10K,5%,1/16W,CHIP,CS31002JB08",10K,5%,R0402,15660.98,7965.52,0.000,YES,,,
R455,"Q_RES_0402LF-4.7K,5%,1/16W,EMPTY,CS24702JB10",4.7K,5%,R0402,16011.77,12789.88,0.000,YES,,,
R456,"Q_RES_0402LF-4.7K,5%,1/16W,EMPTY,CS24702JB10",4.7K,5%,R0402,3718.91,12075.38,0.000,YES,,,
R457,"Q_RES_0402LF-4.7K,5%,1/16W,EMPTY,CS24702JB10",4.7K,5%,R0402,15780.02,12995.68,0.000,YES,,,
R458,"Q_RES_0402LF-30K,1%,1/16W,EMPTY,CS33002FB02",30K,1%,R0402,16011.77,12749.88,0.000,YES,,,
R459,"Q_RES_0402LF-33,5%,1/16W,CHIP,CS03302JB10",33,5%,R0402,15756.80,13014.79,90.000,NO,,,
R460,"Q_RES_0402LF-33,5%,1/16W,CHIP,CS03302JB10",33,5%,R0402,15489.77,12899.38,0.000,YES,,,
R461,"Q_RES_0402LF-33,5%,1/16W,CHIP,CS03302JB10",33,5%,R0402,15836.77,12789.88,180.000,NO,,,
R462,"Q_RES_0402LF-33,5%,1/16W,EMPTY,CS03302JB10",33,5%,R0402,15664.57,12787.88,0.000,YES,,,
R463,"Q_RES_0402LF-33,5%,1/16W,CHIP,CS03302JB10",33,5%,R0402,15612.07,12939.18,180.000,YES,,,
R464,"Q_RES_0402LF-33,5%,1/16W,CHIP,CS03302JB10",33,5%,R0402,15595.48,13026.09,180.000,NO,,,
R465,"Q_RES_0402LF-49.9,1%,1/16W,CHIP,CS04992FB07",49.9,1%,R0402,15722.92,12713.78,180.000,NO,,,
R466,"Q_RES_0402LF-33,5%,1/16W,CHIP,CS03302JB10",33,5%,R0402,15764.07,12889.58,180.000,NO,,,
R467,"Q_RES_0402LF-33,5%,1/16W,CHIP,CS03302JB10",33,5%,R0402,15836.77,12929.88,180.000,NO,,,
R468,"Q_RES_0402LF-33,5%,1/16W,CHIP,CS03302JB10",33,5%,R0402,15496.17,12743.78,0.000,YES,,,
R469,"Q_RES_0402LF-33,5%,1/16W,CHIP,CS03302JB10",33,5%,R0402,15343.77,12644.88,0.000,YES,,,
R470,"Q_RES_0402LF-33,5%,1/16W,CHIP,CS03302JB10",33,5%,R0402,15496.77,12789.88,0.000,YES,,,
R471,"Q_RES_0402LF-33,5%,1/16W,CHIP,CS03302JB10",33,5%,R0402,15496.77,12829.88,0.000,YES,,,
R472,"Q_RES_0402LF-33,5%,1/16W,EMPTY,CS03302JB10",33,5%,R0402,15878.57,12751.68,0.000,YES,,,
R473,"Q_RES_0402LF-0,5%,1/16W,CHIP,CS00002JB13",0,5%,R0402,15416.77,12644.88,0.000,YES,,,
R474,"Q_RES_0402LF-0,5%,1/16W,CHIP,CS00002JB13",0,5%,R0402,15710.02,12995.68,0.000,YES,,,
R475,"Q_RES_0402LF-33,5%,1/16W,CHIP,CS03302JB10",33,5%,R0402,15767.05,12754.54,180.000,NO,,,
R476,"Q_RES_0402LF-33,5%,1/16W,CHIP,CS03302JB10",33,5%,R0402,15893.03,2342.50,180.000,NO,,,
R477,"Q_RES_0402LF-33,5%,1/16W,CHIP,CS03302JB10",33,5%,R0402,15893.03,2392.50,180.000,NO,,,
R478,"Q_RES_0402LF-33,5%,1/16W,CHIP,CS03302JB10",33,5%,R0402,15893.03,2442.50,180.000,NO,,,
R479,"Q_RES_0402LF-10K,1%,1/16W,CHIP,CS31002FB08",10K,1%,R0402,6670.00,5335.00,180.000,NO,,,
R480,"Q_RES_0402LF-100K,1%,1/16W,CHIP,CS41002FB09",100K,1%,R0402,6670.00,5295.00,0.000,NO,,,
R481,"Q_RES_0402LF-0,5%,1/16W,CHIP,CS00002JB13",0,5%,R0402,13797.15,2365.94,180.000,NO,,,
R482,"Q_RES_0402LF-0,5%,1/16W,CHIP,CS00002JB13",0,5%,R0402,6485.00,5195.00,180.000,NO,,,
R483,"Q_RES_0402LF-0,5%,1/16W,CHIP,CS00002JB13",0,5%,R0402,13797.15,2415.94,180.000,NO,,,
R484,"Q_RES_0402LF-0,5%,1/16W,CHIP,CS00002JB13",0,5%,R0402,13797.15,2465.94,180.000,NO,,,
R485,"Q_RES_0402LF-0,5%,1/16W,CHIP,CS00002JB13",0,5%,R0402,13797.15,2515.94,180.000,NO,,,
R486,"Q_RES_0402LF-0,5%,1/16W,CHIP,CS00002JB13",0,5%,R0402,3633.13,8164.75,90.000,YES,,,
R487,"Q_RES_0402LF-0,5%,1/16W,CHIP,CS00002JB13",0,5%,R0402,8080.00,5120.00,0.000,NO,,,
R488,"Q_RES_0402LF-33,5%,1/16W,CHIP,CS03302JB10",33,5%,R0402,7203.00,3783.62,90.000,NO,,,
R489,"Q_RES_0402LF-33,5%,1/16W,CHIP,CS03302JB10",33,5%,R0402,7147.03,3823.76,270.000,YES,,,
R490,"Q_RES_0402LF-0,5%,1/16W,EMPTY,CS00002JB13",0,5%,R0402,8080.00,5160.00,0.000,NO,,,
R491,"Q_RES_0402LF-4.7K,5%,1/16W,EMPTY,CS24702JB10",4.7K,5%,R0402,3718.91,12115.38,180.000,YES,,,
R492,"Q_RES_0402LF-4.7K,5%,1/16W,CHIP,CS24702JB10",4.7K,5%,R0402,6560.00,5195.00,270.000,NO,,,
R493,"Q_RES_0402LF-0,5%,1/16W,CHIP,CS00002JB13",0,5%,R0402,6949.96,5790.81,90.000,NO,,,
R494,"Q_RES_0402LF-0,5%,1/16W,CHIP,CS00002JB13",0,5%,R0402,6560.00,5115.00,270.000,NO,,,
R495,"Q_RES_0402LF-4.7K,5%,1/16W,CHIP,CS24702JB10",4.7K,5%,R0402,7026.45,6201.11,270.000,NO,,,
R496,"Q_RES_0402LF-10K,1%,1/16W,EMPTY,CS31002FB08",10K,1%,R0402,8080.00,5080.00,180.000,NO,,,
R497,"Q_RES_0402LF-33,5%,1/16W,CHIP,CS03302JB10",33,5%,R0402,7296.24,5258.94,90.000,YES,,,
R498,"Q_RES_0402LF-2.2K,5%,1/16W,CHIP,CS22202JB07",2.2K,5%,R0402,6986.45,6201.11,270.000,NO,,,
R499,"Q_RES_0402LF-4.7K,5%,1/16W,CHIP,CS24702JB10",4.7K,5%,R0402,7040.56,5790.81,90.000,NO,,,
R500,"Q_RES_0402LF-15,1%,1/16W,CHIP,CS01502FB03",15,1%,R0402,2291.15,9609.66,0.000,YES,,,
R501,"Q_RES_0402LF-15,1%,1/16W,CHIP,CS01502FB03",15,1%,R0402,2081.93,9609.66,180.000,YES,,,
R502,"Q_RES_0402LF-15,1%,1/16W,CHIP,CS01502FB03",15,1%,R0402,1784.92,9609.66,180.000,YES,,,
R503,"Q_RES_0402LF-15,1%,1/16W,CHIP,CS01502FB03",15,1%,R0402,1487.91,9609.66,180.000,YES,,,
R504,"Q_RES_0402LF-15,1%,1/16W,CHIP,CS01502FB03",15,1%,R0402,1190.91,9609.66,180.000,YES,,,
R505,"Q_RES_0402LF-15,1%,1/16W,CHIP,CS01502FB03",15,1%,R0402,893.90,9609.66,180.000,YES,,,
R506,"Q_RES_0402LF-15,1%,1/16W,CHIP,CS01502FB03",15,1%,R0402,6595.71,9609.66,0.000,YES,,,
R507,"Q_RES_0402LF-15,1%,1/16W,CHIP,CS01502FB03",15,1%,R0402,6892.72,9609.66,0.000,YES,,,
R508,"Q_RES_0402LF-15,1%,1/16W,CHIP,CS01502FB03",15,1%,R0402,7189.73,9609.66,0.000,YES,,,
R509,"Q_RES_0402LF-15,1%,1/16W,CHIP,CS01502FB03",15,1%,R0402,7486.74,9609.66,0.000,YES,,,
R510,"Q_RES_0402LF-15,1%,1/16W,CHIP,CS01502FB03",15,1%,R0402,7783.75,9609.66,0.000,YES,,,
R511,"Q_RES_0402LF-15,1%,1/16W,CHIP,CS01502FB03",15,1%,R0402,8080.75,9609.66,0.000,YES,,,
R512,"Q_RES_0402LF-2.2K,5%,1/16W,CHIP,CS22202JB07",2.2K,5%,R0402,2689.71,8011.88,270.000,YES,,,
R513,"Q_RES_0402LF-2.2K,5%,1/16W,CHIP,CS22202JB07",2.2K,5%,R0402,6147.71,12629.88,0.000,YES,,,
R514,"Q_RES_0402LF-2.2K,5%,1/16W,CHIP,CS22202JB07",2.2K,5%,R0402,2504.71,7723.88,180.000,YES,,,
R515,"Q_RES_0402LF-2.2K,5%,1/16W,CHIP,CS22202JB07",2.2K,5%,R0402,3602.71,12023.88,180.000,YES,,,
R516,"Q_RES_0402LF-2.2K,5%,1/16W,CHIP,CS22202JB07",2.2K,5%,R0402,2504.71,7763.88,180.000,YES,,,
R517,"Q_RES_0402LF-2.2K,5%,1/16W,CHIP,CS22202JB07",2.2K,5%,R0402,2762.71,8018.88,180.000,YES,,,
R518,"Q_RES_0402LF-2.2K,5%,1/16W,CHIP,CS22202JB07",2.2K,5%,R0402,3593.38,11981.31,0.000,YES,,,
R519,"Q_RES_0402LF-2.2K,5%,1/16W,EMPTY,CS22202JB07",2.2K,5%,R0402,3602.11,11939.18,180.000,YES,,,
R520,"Q_RES_0402LF-2.2K,5%,1/16W,CHIP,CS22202JB07",2.2K,5%,R0402,2332.03,7505.80,270.000,YES,,,
R521,"Q_RES_0402LF-2.2K,5%,1/16W,CHIP,CS22202JB07",2.2K,5%,R0402,3602.11,11878.62,180.000,YES,,,
R522,"Q_RES_0402LF-2.2K,5%,1/16W,CHIP,CS22202JB07",2.2K,5%,R0402,5721.71,8018.88,90.000,YES,,,
R523,"Q_RES_0402LF-1K,1%,1/16W,CHIP,CS21002FB06",1K,1%,R0402,6037.71,7843.88,90.000,YES,,,
R524,"Q_RES_0402LF-1K,1%,1/16W,CHIP,CS21002FB06",1K,1%,R0402,6155.71,7843.88,90.000,YES,,,
R525,"Q_RES_0402LF-1K,1%,1/16W,CHIP,CS21002FB06",1K,1%,R0402,5915.71,7951.88,90.000,YES,,,
R526,"Q_RES_0402LF-1K,1%,1/16W,CHIP,CS21002FB06",1K,1%,R0402,6032.61,7989.40,90.000,YES,,,
R527,"Q_RES_0402LF-1K,1%,1/16W,CHIP,CS21002FB06",1K,1%,R0402,5756.71,8018.88,90.000,YES,,,
R528,"Q_RES_0402LF-1K,1%,1/16W,CHIP,CS21002FB06",1K,1%,R0402,5875.71,8019.88,90.000,YES,,,
R529,"Q_RES_0402LF-0,5%,1/16W,CHIP,CS00002JB13",0,5%,R0402,5180.75,8393.82,90.000,YES,,,
R530,"Q_RES_0402LF-0,5%,1/16W,CHIP,CS00002JB13",0,5%,R0402,2762.71,7939.88,0.000,YES,,,
R531,"Q_RES_0402LF-2.2K,5%,1/16W,CHIP,CS22202JB07",2.2K,5%,R0402,3773.13,8076.75,90.000,YES,,,
R532,"Q_RES_0402LF-2.2K,5%,1/16W,CHIP,CS22202JB07",2.2K,5%,R0402,3738.13,8076.75,90.000,YES,,,
R533,"Q_RES_0402LF-2.2K,5%,1/16W,CHIP,CS22202JB07",2.2K,5%,R0402,3703.13,8076.75,90.000,YES,,,
R534,"Q_RES_0402LF-2.2K,5%,1/16W,CHIP,CS22202JB07",2.2K,5%,R0402,3668.13,8076.75,90.000,YES,,,
R535,"Q_RES_0402LF-2.2K,5%,1/16W,CHIP,CS22202JB07",2.2K,5%,R0402,2762.71,7979.88,0.000,YES,,,
R536,"Q_RES_0402LF-2.2K,5%,1/16W,EMPTY,CS22202JB07",2.2K,5%,R0402,5705.61,12340.75,180.000,YES,,,
R537,"Q_RES_0402LF-2.2K,5%,1/16W,CHIP,CS22202JB07",2.2K,5%,R0402,3633.13,8076.75,90.000,YES,,,
R538,"Q_RES_0402LF-2.2K,5%,1/16W,CHIP,CS22202JB07",2.2K,5%,R0402,3598.13,8076.75,90.000,YES,,,
R539,"Q_RES_0402LF-2.2K,5%,1/16W,CHIP,CS22202JB07",2.2K,5%,R0402,3563.13,8076.75,90.000,YES,,,
R540,"Q_RES_0402LF-2.2K,5%,1/16W,CHIP,CS22202JB07",2.2K,5%,R0402,3528.13,8076.75,90.000,YES,,,
R541,"Q_RES_0402LF-1K,1%,1/16W,EMPTY,CS21002FB06",1K,1%,R0402,6328.00,7526.00,270.000,YES,,,
R542,"Q_RES_0402LF-1K,1%,1/16W,EMPTY,CS21002FB06",1K,1%,R0402,6288.00,7526.00,270.000,YES,,,
R543,"Q_RES_0402LF-1K,1%,1/16W,EMPTY,CS21002FB06",1K,1%,R0402,1780.00,6765.00,180.000,NO,,,
R544,"Q_RES_0402LF-4.7K,5%,1/16W,CHIP,CS24702JB10",4.7K,5%,R0402,3719.31,11921.48,0.000,YES,,,
R545,"Q_RES_0402LF-4.7K,5%,1/16W,CHIP,CS24702JB10",4.7K,5%,R0402,3720.00,11958.62,0.000,YES,,,
R546,"Q_RES_0402LF-4.7K,5%,1/16W,CHIP,CS24702JB10",4.7K,5%,R0402,5706.01,12459.65,180.000,YES,,,
R547,"Q_RES_0402LF-4.7K,5%,1/16W,CHIP,CS24702JB10",4.7K,5%,R0402,5706.01,12421.05,180.000,YES,,,
R548,"Q_RES_0402LF-4.7K,5%,1/16W,EMPTY,CS24702JB10",4.7K,5%,R0402,6147.71,12669.88,180.000,YES,,,
R549,"Q_RES_0402LF-4.7K,5%,1/16W,EMPTY,CS24702JB10",4.7K,5%,R0402,6147.81,12786.68,180.000,YES,,,
R550,"Q_RES_0402LF-4.7K,5%,1/16W,CHIP,CS24702JB10",4.7K,5%,R0402,5705.81,12381.65,180.000,YES,,,
R551,"Q_RES_0402LF-4.7K,5%,1/16W,CHIP,CS24702JB10",4.7K,5%,R0402,5684.51,12665.18,270.000,NO,,,
R552,"Q_RES_0402LF-4.7K,5%,1/16W,CHIP,CS24702JB10",4.7K,5%,R0402,6342.44,5090.38,270.000,NO,,,
R553,"Q_RES_0402LF-4.7K,5%,1/16W,CHIP,CS24702JB10",4.7K,5%,R0402,2645.71,7847.88,0.000,YES,,,
R554,"Q_RES_0402LF-100K,1%,1/16W,CHIP,CS41002FB09",100K,1%,R0402,8100.00,5345.00,0.000,NO,,,
R555,"Q_RES_0603LF-1,1%,1/10W,CHIP,CS-1003F900",1,1%,R0603_H24,4270.00,16445.00,180.000,NO,,,
R556,"Q_RES_0402LF-1K,1%,1/16W,EMPTY,CS21002FB06",1K,1%,R0402,2698.71,7934.88,90.000,YES,,,
R557,"Q_RES_0402LF-1K,1%,1/16W,EMPTY,CS21002FB06",1K,1%,R0402,2837.51,8040.48,180.000,YES,,,
R558,"Q_RES_0402LF-4.7K,5%,1/16W,EMPTY,CS24702JB10",4.7K,5%,R0402,2645.71,7805.88,0.000,YES,,,
R559,"Q_RES_0402LF-2.2K,5%,1/16W,CHIP,CS22202JB07",2.2K,5%,R0402,6147.81,12708.88,0.000,YES,,,
R560,"Q_RES_0402LF-10K,1%,1/16W,CHIP,CS31002FB08",10K,1%,R0402,4285.00,16355.00,270.000,NO,,,
R561,"Q_RES_0402LF-0,5%,1/16W,CHIP,CS00002JB13",0,5%,R0402,18462.61,1702.87,180.000,NO,,,
R562,"Q_RES_0402LF-2.2K,5%,1/16W,CHIP,CS22202JB07",2.2K,5%,R0402,6147.81,12747.98,0.000,YES,,,
R563,"Q_RES_0402LF-1K,1%,1/16W,EMPTY,CS21002FB06",1K,1%,R0402,1780.00,6725.00,180.000,NO,,,
R564,"Q_RES_0402LF-0,5%,1/16W,CHIP,CS00002JB13",0,5%,R0402,1680.00,6705.00,0.000,NO,,,
R565,"Q_RES_0402LF-0,5%,1/16W,CHIP,CS00002JB13",0,5%,R0402,1680.00,6765.00,0.000,NO,,,
R566,"Q_RES_0402LF-0,5%,1/16W,CHIP,CS00002JB13",0,5%,R0402,6284.08,7604.29,270.000,YES,,,
R567,"Q_RES_0402LF-0,5%,1/16W,CHIP,CS00002JB13",0,5%,R0402,6349.46,7594.78,270.000,YES,,,
R568,"Q_RES_0402LF-10K,1%,1/16W,CHIP,CS31002FB08",10K,1%,R0402,8310.00,5100.00,270.000,NO,,,
R569,"Q_RES_0402LF-1K,1%,1/16W,CHIP,CS21002FB06",1K,1%,R0402,8205.00,5100.00,90.000,NO,,,
R570,"Q_RES_0402LF-0,5%,1/16W,CHIP,CS00002JB13",0,5%,R0402,5645.09,12665.14,270.000,NO,,,
R571,"Q_RES_0402LF-10M,1%,1/16W,CHIP,CS61002FB02",10M,1%,R0402,5831.59,12340.75,180.000,YES,,,
R572,"Q_RES_0402LF-20M,1%,1/16W,CHIP,CS62002FB01",20M,1%,R0402,6041.59,12415.75,180.000,YES,,,
R573,"Q_RES_0402LF-0,5%,1/16W,CHIP,CS00002JB13",0,5%,R0402,15355.12,12369.31,270.000,YES,,,
R574,"Q_RES_0402LF-0,5%,1/16W,EMPTY,CS00002JB13",0,5%,R0402,6022.01,12360.75,90.000,YES,,,
R575,"Q_RES_0402LF-0,5%,1/16W,EMPTY,CS00002JB13",0,5%,R0402,6062.01,12360.75,90.000,YES,,,
R576,"Q_RES_0402LF-0,5%,1/16W,CHIP,CS00002JB13",0,5%,R0402,18172.92,4316.78,0.000,NO,,,
R577,"Q_RES_0402LF-10K,1%,1/16W,CHIP,CS31002FB08",10K,1%,R0402,18242.92,4316.78,180.000,NO,,,
R578,"Q_RES_0402LF-4.75K,1%,1/16W,EMPTY,CS24752FB03",4.75K,1%,R0402,4105.00,16370.00,0.000,NO,,,
R579,"Q_RES_0402LF-4.75K,1%,1/16W,CHIP,CS24752FB03",4.75K,1%,R0402,4105.00,16410.00,180.000,NO,,,
R580,"Q_RES_0402LF-10K,1%,1/16W,CHIP,CS31002FB08",10K,1%,R0402,4405.00,16300.00,0.000,YES,,,
R581,"Q_RES_0402LF-4.7K,5%,1/16W,EMPTY,CS24702JB10",4.7K,5%,R0402,15561.78,12643.63,90.000,NO,,,
R582,"Q_RES_0402LF-4.7K,5%,1/16W,EMPTY,CS24702JB10",4.7K,5%,R0402,15486.74,12662.71,0.000,NO,,,
R583,"Q_RES_0402LF-4.7K,5%,1/16W,EMPTY,CS24702JB10",4.7K,5%,R0402,6017.71,12625.98,0.000,NO,,,
R584,"Q_RES_0402LF-4.7K,5%,1/16W,EMPTY,CS24702JB10",4.7K,5%,R0402,6017.71,12705.98,180.000,NO,,,
R585,"Q_RES_0402LF-10K,1%,1/16W,CHIP,CS31002FB08",10K,1%,R0402,4375.00,16260.00,0.000,YES,,,
R586,"Q_RES_0603LF-1,1%,1/10W,CHIP,CS-1003F900",1,1%,R0603_H24,4390.00,16275.00,0.000,NO,,,
R587,"Q_RES_0402LF-1K,1%,1/16W,CHIP,CS21002FB06",1K,1%,R0402,11004.48,4893.91,180.000,NO,,,
R588,"Q_RES_0402LF-33,5%,1/16W,CHIP,CS03302JB10",33,5%,R0402,7525.00,5258.62,90.000,NO,,,
R589,"Q_RES_0402LF-0,5%,1/16W,CHIP,CS00002JB13",0,5%,R0402,15660.98,7925.52,0.000,YES,,,
R590,"Q_RES_0402LF-4.7K,5%,1/16W,CHIP,CS24702JB10",4.7K,5%,R0402,6989.96,5790.81,90.000,NO,,,
R591,"Q_RES_0402LF-0,5%,1/16W,CHIP,CS00002JB13",0,5%,R0402,17573.22,1266.71,270.000,NO,,,
R592,"Q_RES_0402LF-10K,1%,1/16W,CHIP,CS31002FB08",10K,1%,R0402,4400.00,16002.00,0.000,NO,,,
R593,"Q_RES_0402LF-10K,1%,1/16W,CHIP,CS31002FB08",10K,1%,R0402,3956.05,15990.22,180.000,NO,,,
R594,"Q_RES_0402LF-10K,1%,1/16W,CHIP,CS31002FB08",10K,1%,R0402,3956.05,16030.22,180.000,NO,,,
R595,"Q_RES_0201LF-0,5%,1/20W,CHIP,CS00001JE10",0,5%,R0201,11753.06,15596.31,0.000,NO,,,
R596,"Q_RES_0201LF-0,5%,1/20W,CHIP,CS00001JE10",0,5%,R0201,11753.06,15564.31,0.000,NO,,,
R597,"Q_RES_0201LF-0,5%,1/20W,CHIP,CS00001JE10",0,5%,R0201,2954.95,15266.31,0.000,NO,,,
R598,"Q_RES_0201LF-0,5%,1/20W,CHIP,CS00001JE10",0,5%,R0201,2954.95,15234.31,0.000,NO,,,
R599,"Q_RES_0201LF-0,5%,1/20W,CHIP,CS00001JE10",0,5%,R0201,1674.33,15266.31,0.000,NO,,,
R600,"Q_RES_0402LF-0,5%,1/16W,CHIP,CS00002JB13",0,5%,R0402,9980.56,5260.74,180.000,NO,,,
R601,"Q_RES_0402LF-1K,1%,1/16W,CHIP,CS21002FB06",1K,1%,R0402,10412.54,5260.74,180.000,NO,,,
R602,"Q_RES_0402LF-33,5%,1/16W,CHIP,CS03302JB10",33,5%,R0402,9980.56,5210.14,180.000,NO,,,
R603,"Q_RES_0402LF-0,5%,1/16W,CHIP,CS00002JB13",0,5%,R0402,9980.56,5160.14,180.000,NO,,,
R604,"Q_RES_0402LF-33.2,1%,1/16W,CHIP,CS03322FB03",33.2,1%,R0402,10199.61,5589.32,90.000,NO,,,
R605,"Q_RES_0402LF-49.9,1%,1/16W,CHIP,CS04992FB07",49.9,1%,R0402,10249.61,5589.32,90.000,NO,,,
R606,"Q_RES_0402LF-0,5%,1/16W,CHIP,CS00002JB13",0,5%,R0402,10137.86,5500.74,180.000,NO,,,
R607,"Q_RES_0402LF-0,5%,1/16W,CHIP,CS00002JB13",0,5%,R0402,10137.86,5450.74,180.000,NO,,,
R608,"Q_RES_0402LF-33,5%,1/16W,CHIP,CS03302JB10",33,5%,R0402,9980.56,5310.74,180.000,NO,,,
R609,"Q_RES_0201LF-0,5%,1/20W,CHIP,CS00001JE10",0,5%,R0201,1674.33,15234.31,0.000,NO,,,
R610,"Q_RES_0402LF-1K,1%,1/16W,EMPTY,CS21002FB06",1K,1%,R0402,9900.56,5160.14,0.000,NO,,,
R611,"Q_RES_0201LF-0,5%,1/20W,CHIP,CS00001JE10",0,5%,R0201,13033.68,15596.31,0.000,NO,,,
R612,"Q_RES_0201LF-0,5%,1/20W,CHIP,CS00001JE10",0,5%,R0201,13033.68,15564.31,0.000,NO,,,
R613,"Q_RES_0201LF-0,5%,1/20W,CHIP,CS00001JE10",0,5%,R0201,15675.42,15596.31,0.000,NO,,,
R614,"Q_RES_0201LF-0,5%,1/20W,CHIP,CS00001JE10",0,5%,R0201,15675.42,15564.31,0.000,NO,,,
R615,"Q_RES_0201LF-0,5%,1/20W,CHIP,CS00001JE10",0,5%,R0201,14394.80,15596.31,0.000,NO,,,
R616,"Q_RES_0201LF-0,5%,1/20W,CHIP,CS00001JE10",0,5%,R0201,14394.80,15564.31,0.000,NO,,,
R617,"Q_RES_0402LF-4.7K,5%,1/16W,CHIP,CS24702JB10",4.7K,5%,R0402,4847.53,2068.27,0.000,NO,,,
R618,"Q_RES_0402LF-0,5%,1/16W,CHIP,CS00002JB13",0,5%,R0402,3598.13,8165.75,90.000,YES,,,
R619,"Q_RES_0201LF-0,5%,1/20W,CHIP,CS00001JE10",0,5%,R0201,5596.68,15266.31,0.000,NO,,,
R620,"Q_RES_0201LF-0,5%,1/20W,CHIP,CS00001JE10",0,5%,R0201,5596.68,15234.31,0.000,NO,,,
R621,"Q_RES_0201LF-0,5%,1/20W,CHIP,CS00001JE10",0,5%,R0201,4316.06,15266.31,0.000,NO,,,
R622,"Q_RES_0201LF-0,5%,1/20W,CHIP,CS00001JE10",0,5%,R0201,4316.06,15234.31,0.000,NO,,,
R623,"Q_RES_0201LF-51.1,1%,1/20W,EMPTY,CS05111FE00",51.1,1%,R0201,11793.06,15553.81,270.000,NO,,,
R624,"Q_RES_0201LF-51.1,1%,1/20W,EMPTY,CS05111FE00",51.1,1%,R0201,11793.06,15606.81,90.000,NO,,,
R625,"Q_RES_0201LF-51.1,1%,1/20W,EMPTY,CS05111FE00",51.1,1%,R0201,2994.95,15223.81,270.000,NO,,,
R626,"Q_RES_0201LF-51.1,1%,1/20W,EMPTY,CS05111FE00",51.1,1%,R0201,2994.95,15276.81,90.000,NO,,,
R627,"Q_RES_0201LF-51.1,1%,1/20W,EMPTY,CS05111FE00",51.1,1%,R0201,1714.33,15223.81,270.000,NO,,,
R628,"Q_RES_0201LF-51.1,1%,1/20W,EMPTY,CS05111FE00",51.1,1%,R0201,1714.33,15276.81,90.000,NO,,,
R629,"Q_RES_0201LF-51.1,1%,1/20W,EMPTY,CS05111FE00",51.1,1%,R0201,13073.68,15553.81,270.000,NO,,,
R630,"Q_RES_0201LF-51.1,1%,1/20W,EMPTY,CS05111FE00",51.1,1%,R0201,13073.68,15606.81,90.000,NO,,,
R631,"Q_RES_0201LF-51.1,1%,1/20W,EMPTY,CS05111FE00",51.1,1%,R0201,15715.42,15553.81,270.000,NO,,,
R632,"Q_RES_0402LF-2.2K,5%,1/16W,CHIP,CS22202JB07",2.2K,5%,R0402,7484.82,5530.10,90.000,YES,,,
R633,"Q_RES_0402LF-2.2K,5%,1/16W,CHIP,CS22202JB07",2.2K,5%,R0402,7605.17,5528.84,90.000,YES,,,
R634,"Q_RES_0201LF-51.1,1%,1/20W,EMPTY,CS05111FE00",51.1,1%,R0201,15715.42,15606.81,90.000,NO,,,
R635,"Q_RES_0201LF-51.1,1%,1/20W,EMPTY,CS05111FE00",51.1,1%,R0201,14434.80,15553.81,270.000,NO,,,
R636,"Q_RES_0201LF-51.1,1%,1/20W,EMPTY,CS05111FE00",51.1,1%,R0201,14434.80,15606.81,90.000,NO,,,
R637,"Q_RES_0201LF-51.1,1%,1/20W,EMPTY,CS05111FE00",51.1,1%,R0201,5636.68,15223.81,270.000,NO,,,
R638,"Q_RES_0402LF-1K,1%,1/16W,CHIP,CS21002FB06",1K,1%,R0402,6580.00,4698.62,180.000,NO,,,
R639,"Q_RES_0402LF-1K,1%,1/16W,CHIP,CS21002FB06",1K,1%,R0402,6580.00,4738.62,180.000,NO,,,
R640,"Q_RES_0201LF-51.1,1%,1/20W,EMPTY,CS05111FE00",51.1,1%,R0201,5636.68,15276.81,90.000,NO,,,
R641,"Q_RES_0201LF-51.1,1%,1/20W,EMPTY,CS05111FE00",51.1,1%,R0201,4356.06,15223.81,270.000,NO,,,
R642,"Q_RES_0201LF-51.1,1%,1/20W,EMPTY,CS05111FE00",51.1,1%,R0201,4356.06,15276.81,90.000,NO,,,
R643,"Q_RES_0402LF-1K,1%,1/16W,EMPTY,CS21002FB06",1K,1%,R0402,17284.29,16814.56,180.000,YES,,,
R644,"Q_RES_0402LF-10K,5%,1/16W,CHIP,CS31002JB08",10K,5%,R0402,8912.07,11450.58,180.000,YES,,,
R645,"Q_RES_0402LF-33,5%,1/16W,CHIP,CS03302JB10",33,5%,R0402,8997.07,11380.58,90.000,YES,,,
R646,"Q_RES_0402LF-0,5%,1/16W,CHIP,CS00002JB13",0,5%,R0402,17404.63,16904.65,270.000,NO,,,
R647,"Q_RES_0402LF-0,5%,1/16W,CHIP,CS00002JB13",0,5%,R0402,17454.63,16904.65,270.000,NO,,,
R648,"Q_RES_0402LF-33,5%,1/16W,CHIP,CS03302JB10",33,5%,R0402,7911.52,4753.44,0.000,YES,,,
R649,"Q_RES_0402LF-4.7K,1%,1/16W,EMPTY,CS24702FB06",4.7K,1%,R0402,17354.63,16904.65,270.000,NO,,,
R650,"Q_RES_0402LF-0,5%,1/16W,CHIP,CS00002JB13",0,5%,R0402,17294.36,16886.65,270.000,NO,,,
R651,"Q_RES_0402LF-0,5%,1/16W,CHIP,CS00002JB13",0,5%,R0402,17208.45,16753.34,90.000,NO,,,
R652,"Q_RES_0402LF-1K,1%,1/16W,CHIP,CS21002FB06",1K,1%,R0402,17694.63,16574.65,180.000,NO,,,
R653,"Q_RES_0402LF-0,5%,1/16W,EMPTY,CS00002JB13",0,5%,R0402,4031.11,15122.20,180.000,NO,,,
R654,"Q_RES_0402LF-4.7K,5%,1/16W,CHIP,CS24702JB10",4.7K,5%,R0402,15953.55,7987.84,270.000,YES,,,
R655,"Q_RES_0402LF-1K,1%,1/16W,CHIP,CS21002FB06",1K,1%,R0402,17284.63,16724.65,0.000,NO,,,
R656,"Q_RES_0402LF-1K,1%,1/16W,EMPTY,CS21002FB06",1K,1%,R0402,668.71,16027.90,270.000,YES,,,
R657,"Q_RES_0402LF-0,5%,1/16W,CHIP,CS00002JB13",0,5%,R0402,636.33,15918.96,90.000,NO,,,
R658,"Q_RES_0402LF-0,5%,1/16W,CHIP,CS00002JB13",0,5%,R0402,586.33,15918.96,90.000,NO,,,
R659,"Q_RES_0402LF-1K,1%,1/16W,CHIP,CS21002FB06",1K,1%,R0402,10412.54,5340.74,180.000,NO,,,
R660,"Q_RES_0402LF-4.7K,1%,1/16W,EMPTY,CS24702FB06",4.7K,1%,R0402,681.33,15918.96,90.000,NO,,,
R661,"Q_RES_0402LF-0,5%,1/16W,CHIP,CS00002JB13",0,5%,R0402,726.60,15918.96,90.000,NO,,,
R662,"Q_RES_0402LF-0,5%,1/16W,CHIP,CS00002JB13",0,5%,R0402,826.06,16062.07,90.000,NO,,,
R663,"Q_RES_0402LF-1K,1%,1/16W,CHIP,CS21002FB06",1K,1%,R0402,396.33,16268.96,0.000,NO,,,
R664,"Q_RES_0402LF-0,5%,1/16W,EMPTY,CS00002JB13",0,5%,R0402,4031.11,15161.20,180.000,NO,,,
R665,"Q_RES_0402LF-1K,1%,1/16W,CHIP,CS21002FB06",1K,1%,R0402,806.33,16118.96,180.000,NO,,,
R666,"Q_RES_0201LF-49.9,1%,1/20W,CHIP,CS04991FE06",49.9,1%,R0201,11865.26,16791.28,180.000,YES,,,
R667,"Q_RES_0201LF-49.9,1%,1/20W,CHIP,CS04991FE06",49.9,1%,R0201,11865.68,16751.92,180.000,YES,,,
R668,"Q_RES_0201LF-33.2,1%,1/20W,CHIP,CS03321FE09",33.2,1%,R0201,11596.88,16621.02,90.000,NO,,,
R669,"Q_RES_0201LF-33.2,1%,1/20W,CHIP,CS03321FE09",33.2,1%,R0201,11636.88,16621.02,90.000,NO,,,
R670,"Q_RES_0201LF-49.9,1%,1/20W,CHIP,CS04991FE06",49.9,1%,R0201,4170.40,15573.10,180.000,NO,,,
R671,"Q_RES_0201LF-49.9,1%,1/20W,CHIP,CS04991FE06",49.9,1%,R0201,4113.20,15542.00,270.000,NO,,,
R672,"Q_RES_0201LF-33.2,1%,1/20W,CHIP,CS03321FE09",33.2,1%,R0201,4076.00,15618.00,90.000,NO,,,
R673,"Q_RES_0201LF-33.2,1%,1/20W,CHIP,CS03321FE09",33.2,1%,R0201,4042.00,15618.00,90.000,NO,,,
R674,"Q_RES_0201LF-49.9,1%,1/20W,CHIP,CS04991FE06",49.9,1%,R0201,1668.00,14910.10,0.000,NO,,,
R675,"Q_RES_0201LF-49.9,1%,1/20W,CHIP,CS04991FE06",49.9,1%,R0201,1666.90,14943.40,0.000,NO,,,
R676,"Q_RES_0201LF-49.9,1%,1/20W,CHIP,CS04991FE06",49.9,1%,R0201,13028.84,15250.01,0.000,NO,,,
R677,"Q_RES_0201LF-49.9,1%,1/20W,CHIP,CS04991FE06",49.9,1%,R0201,13028.84,15281.47,0.000,NO,,,
R678,"Q_RES_0201LF-33.2,1%,1/20W,CHIP,CS03321FE09",33.2,1%,R0201,11429.59,15693.44,90.000,NO,,,
R679,"Q_RES_0201LF-33.2,1%,1/20W,CHIP,CS03321FE09",33.2,1%,R0201,11466.89,15693.25,90.000,NO,,,
R680,"Q_RES_0201LF-49.9,1%,1/20W,CHIP,CS04991FE06",49.9,1%,R0201,16573.56,16556.48,0.000,YES,,,
R681,"Q_RES_0201LF-49.9,1%,1/20W,CHIP,CS04991FE06",49.9,1%,R0201,16612.55,16625.55,0.000,YES,,,
R682,"Q_RES_0201LF-33.2,1%,1/20W,CHIP,CS03321FE09",33.2,1%,R0201,16561.36,16682.86,90.000,NO,,,
R683,"Q_RES_0201LF-33.2,1%,1/20W,CHIP,CS03321FE09",33.2,1%,R0201,16511.46,16684.16,90.000,NO,,,
R684,"Q_RES_0201LF-49.9,1%,1/20W,CHIP,CS04991FE06",49.9,1%,R0201,14401.37,16861.65,180.000,NO,,,
R685,"Q_RES_0402LF-33,5%,1/16W,CHIP,CS03302JB10",33,5%,R0402,7766.52,4633.44,0.000,NO,,,
R686,"Q_RES_0201LF-49.9,1%,1/20W,CHIP,CS04991FE06",49.9,1%,R0201,14401.37,16826.65,180.000,NO,,,
R687,"Q_RES_0201LF-33.2,1%,1/20W,CHIP,CS03321FE09",33.2,1%,R0201,14501.37,16707.59,180.000,YES,,,
R688,"Q_RES_0201LF-33.2,1%,1/20W,CHIP,CS03321FE09",33.2,1%,R0201,14452.82,16676.25,180.000,YES,,,
R689,"Q_RES_0201LF-33.2,1%,1/20W,CHIP,CS03321FE09",33.2,1%,R0201,4300.00,15631.20,90.000,NO,,,
R690,"Q_RES_0201LF-33.2,1%,1/20W,CHIP,CS03321FE09",33.2,1%,R0201,4266.00,15631.20,90.000,NO,,,
R691,"Q_RES_0201LF-49.9,1%,1/20W,CHIP,CS04991FE06",49.9,1%,R0201,6435.80,16281.00,90.000,YES,,,
R692,"Q_RES_0201LF-49.9,1%,1/20W,CHIP,CS04991FE06",49.9,1%,R0201,6434.00,16227.90,90.000,YES,,,
R693,"Q_RES_0201LF-33.2,1%,1/20W,CHIP,CS03321FE09",33.2,1%,R0201,6445.49,16498.00,90.000,NO,,,
R694,"Q_RES_0201LF-33.2,1%,1/20W,CHIP,CS03321FE09",33.2,1%,R0201,6398.00,16498.00,90.000,NO,,,
R695,"Q_RES_0201LF-49.9,1%,1/20W,CHIP,CS04991FE06",49.9,1%,R0201,4455.70,16087.34,90.000,YES,,,
R696,"Q_RES_0201LF-49.9,1%,1/20W,CHIP,CS04991FE06",49.9,1%,R0201,4423.40,16088.64,90.000,YES,,,
R697,"Q_RES_0201LF-33.2,1%,1/20W,CHIP,CS03321FE09",33.2,1%,R0201,6679.85,16500.64,90.000,NO,,,
R698,"Q_RES_0201LF-33.2,1%,1/20W,CHIP,CS03321FE09",33.2,1%,R0201,6630.03,16502.00,90.000,NO,,,
R699,"Q_RES_0201LF-1K,1%,1/20W,EMPTY,CS21001FE07",1K,1%,R0201,2615.30,15542.70,90.000,NO,,,
R700,"Q_RES_0402LF-30K,1%,1/16W,EMPTY,CS33002FB02",30K,1%,R0402,1698.50,3950.40,180.000,NO,,,
R701,"Q_RES_0201LF-200,1%,1/20W,CHIP,CS12001FE12",200,1%,R0201,2544.70,15542.90,270.000,NO,,,
R702,"Q_RES_0402LF-10K,5%,1/16W,EMPTY,CS31002JB08",10K,5%,R0402,15396.93,5396.13,270.000,NO,,,
R703,"Q_RES_0402LF-10K,5%,1/16W,EMPTY,CS31002JB08",10K,5%,R0402,3273.91,5455.21,0.000,NO,,,
R704,"Q_RES_0402LF-0,5%,1/16W,EMPTY,CS00002JB13",0,5%,R0402,4062.61,15122.20,180.000,NO,,,
R705,"Q_RES_0603LF-0,5%,1/4W,EMPTY,CS00006J900",0,5%,R0603,2851.04,15481.99,180.000,YES,,,
R706,"Q_RES_0201LF-4.7K,5%,1/20W,EMPTY,CS24701JE04",4.7K,5%,R0201,1653.38,15180.40,0.000,NO,,,
R707,"Q_RES_0201LF-10K,1%,1/20W,CHIP,CS31001FE17",10K,1%,R0201,1703.38,15180.40,0.000,NO,,,
R708,"Q_RES_0402LF-33,5%,1/16W,CHIP,CS03302JB10",33,5%,R0402,7485.00,5258.62,90.000,NO,,,
R709,"Q_RES_0201LF-0,5%,1/20W,CHIP,CS00001JE10",0,5%,R0201,2758.00,15074.00,180.000,YES,,,
R710,"Q_RES_0402LF-1K,1%,1/16W,CHIP,CS21002FB06",1K,1%,R0402,12564.47,4643.72,0.000,NO,,,
R711,"Q_RES_0201LF-0,5%,1/20W,CHIP,CS00001JE10",0,5%,R0201,2715.80,15533.00,270.000,NO,,,
R712,"Q_RES_0603LF-0,5%,1/4W,CHIP,CS00006J900",0,5%,R0603,2909.04,15481.99,180.000,YES,,,
R713,"Q_RES_0402LF-10K,1%,1/16W,EMPTY,CS31002FB08",10K,1%,R0402,12014.27,4602.02,0.000,NO,,,
R714,"Q_RES_0402LF-1K,1%,1/16W,CHIP,CS21002FB06",1K,1%,R0402,11899.27,4602.02,180.000,NO,,,
R715,"Q_RES_0201LF-10K,1%,1/20W,CHIP,CS31001FE17",10K,1%,R0201,1703.38,15144.20,0.000,NO,,,
R716,"Q_RES_0201LF-4.7K,5%,1/20W,EMPTY,CS24701JE04",4.7K,5%,R0201,1703.38,15225.40,180.000,YES,,,
R717,"Q_RES_0402LF-10K,1%,1/16W,EMPTY,CS31002FB08",10K,1%,R0402,12014.87,4652.72,0.000,NO,,,
R718,"Q_RES_0402LF-1K,1%,1/16W,CHIP,CS21002FB06",1K,1%,R0402,11899.87,4652.72,180.000,NO,,,
R719,"Q_RES_0201LF-4.7K,5%,1/20W,CHIP,CS24701JE04",4.7K,5%,R0201,1703.38,15193.40,180.000,YES,,,
R720,"Q_RES_0201LF-4.7K,5%,1/20W,EMPTY,CS24701JE04",4.7K,5%,R0201,1703.38,15161.40,180.000,YES,,,
R721,"Q_RES_0402LF-10K,1%,1/16W,CHIP,CS31002FB08",10K,1%,R0402,12015.63,4703.76,0.000,NO,,,
R722,"Q_RES_0402LF-1K,1%,1/16W,EMPTY,CS21002FB06",1K,1%,R0402,11900.47,4703.92,180.000,NO,,,
R723,"Q_RES_0201LF-4.7K,5%,1/20W,CHIP,CS24701JE04",4.7K,5%,R0201,1703.38,15129.40,180.000,YES,,,
R724,"Q_RES_0201LF-4.7K,5%,1/20W,EMPTY,CS24701JE04",4.7K,5%,R0201,1643.38,15108.00,0.000,NO,,,
R725,"Q_RES_0201LF-4.7K,5%,1/20W,CHIP,CS24701JE04",4.7K,5%,R0201,1703.38,15108.00,0.000,NO,,,
R726,"Q_RES_0201LF-4.7K,5%,1/20W,CHIP,CS24701JE04",4.7K,5%,R0201,1636.00,15425.00,0.000,NO,,,
R727,"Q_RES_0201LF-4.7K,5%,1/20W,CHIP,CS24701JE04",4.7K,5%,R0201,1590.00,15370.00,90.000,NO,,,
R728,"Q_RES_0201LF-4.7K,5%,1/20W,EMPTY,CS24701JE04",4.7K,5%,R0201,1636.00,15380.00,0.000,NO,,,
R729,"Q_RES_0402LF-10K,5%,1/16W,EMPTY,CS31002JB08",10K,5%,R0402,13351.77,12079.88,180.000,YES,,,
R730,"Q_RES_0402LF-10K,5%,1/16W,CHIP,CS31002JB08",10K,5%,R0402,6017.71,12712.73,270.000,YES,,,
R731,"Q_RES_0201LF-0,5%,1/20W,CHIP,CS00001JE10",0,5%,R0201,3964.42,15576.00,270.000,NO,,,
R732,"Q_RES_0201LF-0,5%,1/20W,CHIP,CS00001JE10",0,5%,R0201,3001.99,15547.38,90.000,NO,,,
R733,"Q_RES_0402LF-100,1%,1/16W,EMPTY,CS11002FB07",100,1%,R0402,16619.28,2261.72,270.000,NO,,,
R734,"Q_RES_0402LF-0,5%,1/16W,CHIP,CS00002JB13",0,5%,R0402,16792.75,1367.62,180.000,YES,,,
R735,"Q_RES_0201LF-1K,1%,1/20W,CHIP,CS21001FE07",1K,1%,R0201,4110.62,15178.00,90.000,NO,,,
R736,"Q_RES_0402LF-10K,5%,1/16W,EMPTY,CS31002JB08",10K,5%,R0402,6017.71,12785.98,180.000,NO,,,
R737,"Q_RES_0402LF-10K,5%,1/16W,CHIP,CS31002JB08",10K,5%,R0402,15904.77,12912.88,0.000,YES,,,
R738,"Q_RES_0402LF-33,5%,1/16W,CHIP,CS03302JB10",33,5%,R0402,5717.21,12681.18,0.000,YES,,,
R739,"Q_RES_0402LF-10K,5%,1/16W,EMPTY,CS31002JB08",10K,5%,R0402,15497.52,12684.88,0.000,YES,,,
R740,"Q_RES_0402LF-10K,5%,1/16W,EMPTY,CS31002JB08",10K,5%,R0402,15437.72,12369.01,90.000,YES,,,
R741,"Q_RES_0201LF-1K,1%,1/20W,EMPTY,CS21001FE07",1K,1%,R0201,4110.62,15228.00,90.000,NO,,,
R742,"Q_RES_0402LF-10K,5%,1/16W,EMPTY,CS31002JB08",10K,5%,R0402,15756.37,12860.88,0.000,YES,,,
R743,"Q_RES_0402LF-10K,5%,1/16W,CHIP,CS31002JB08",10K,5%,R0402,15901.77,12789.88,180.000,NO,,,
R744,"Q_RES_0402LF-0,5%,1/16W,CHIP,CS00002JB13",0,5%,R0402,16792.75,1317.62,180.000,YES,,,
R745,"Q_RES_0201LF-1K,1%,1/20W,EMPTY,CS21001FE07",1K,1%,R0201,4142.62,15178.00,90.000,NO,,,
R746,"Q_RES_0201LF-20K,1%,1/20W,CHIP,CS32001FE00",20K,1%,R0201,4142.62,15228.00,90.000,NO,,,
R747,"Q_RES_0402LF-1K,1%,1/16W,CHIP,CS21002FB06",1K,1%,R0402,13351.77,12114.88,180.000,YES,,,
R748,"Q_RES_0402LF-10K,5%,1/16W,EMPTY,CS31002JB08",10K,5%,R0402,15904.77,12952.88,0.000,YES,,,
R749,"Q_RES_0201LF-10K,1%,1/20W,CHIP,CS31001FE17",10K,1%,R0201,3964.42,15526.00,270.000,NO,,,
R750,"Q_RES_0402LF-30K,1%,1/16W,CHIP,CS33002FB02",30K,1%,R0402,15497.52,12644.88,0.000,YES,,,
R751,"Q_RES_0402LF-10K,5%,1/16W,CHIP,CS31002JB08",10K,5%,R0402,15397.82,12369.31,90.000,YES,,,
R752,"Q_RES_0201LF-10K,1%,1/20W,CHIP,CS31001FE17",10K,1%,R0201,3039.99,15518.38,270.000,NO,,,
R753,"Q_RES_0402LF-10K,5%,1/16W,CHIP,CS31002JB08",10K,5%,R0402,15686.77,12861.08,180.000,YES,,,
R754,"Q_RES_0402LF-10K,5%,1/16W,EMPTY,CS31002JB08",10K,5%,R0402,6057.71,12712.73,270.000,YES,,,
R755,"Q_RES_0201LF-4.7K,5%,1/20W,EMPTY,CS24701JE04",4.7K,5%,R0201,2934.00,15108.00,180.000,YES,,,
R756,"Q_RES_0201LF-200,1%,1/20W,CHIP,CS12001FE12",200,1%,R0201,2984.00,15108.00,180.000,YES,,,
R757,"Q_RES_0402LF-4.7K,5%,1/16W,EMPTY,CS24702JB10",4.7K,5%,R0402,8218.44,4761.59,180.000,YES,,,
R758,"Q_RES_0201LF-4.7K,5%,1/20W,EMPTY,CS24701JE04",4.7K,5%,R0201,3039.99,15568.38,270.000,NO,,,
R759,"Q_RES_0201LF-4.7K,5%,1/20W,EMPTY,CS24701JE04",4.7K,5%,R0201,3114.76,15609.89,270.000,NO,,,
R760,"Q_RES_0402LF-10K,5%,1/16W,CHIP,CS31002JB08",10K,5%,R0402,6017.71,12745.98,180.000,NO,,,
R761,"Q_RES_0402LF-15.4K,1%,1/16W,CHIP,CS31542FB02",15.4K,1%,R0402,11672.43,7672.65,180.000,YES,,,
R762,"Q_RES_0402LF-23.2K,1%,1/16W,CHIP,CS32322FB03",23.2K,1%,R0402,11375.42,7672.65,180.000,YES,,,
R763,"Q_RES_0402LF-35.7K,1%,1/16W,CHIP,CS33572FB01",35.7K,1%,R0402,11078.41,7672.65,180.000,YES,,,
R764,"Q_RES_0402LF-84.5K,1%,1/16W,CHIP,CS38452FB05",84.5K,1%,R0402,10484.40,7672.65,180.000,YES,,,
R765,"Q_RES_0402LF-15.4K,1%,1/16W,CHIP,CS31542FB02",15.4K,1%,R0402,16561.72,7672.65,180.000,YES,,,
R766,"Q_RES_0402LF-23.2K,1%,1/16W,CHIP,CS32322FB03",23.2K,1%,R0402,16858.73,7672.65,180.000,YES,,,
R767,"Q_RES_0402LF-35.7K,1%,1/16W,CHIP,CS33572FB01",35.7K,1%,R0402,17155.74,7672.65,180.000,YES,,,
R768,"Q_RES_0402LF-54.9K,1%,1/16W,CHIP,CS35492FB03",54.9K,1%,R0402,17452.75,7672.65,180.000,YES,,,
R769,"Q_RES_0402LF-84.5K,1%,1/16W,CHIP,CS38452FB05",84.5K,1%,R0402,17749.75,7672.65,180.000,YES,,,
R770,"Q_RES_0402LF-15.4K,1%,1/16W,CHIP,CS31542FB02",15.4K,1%,R0402,1911.62,7672.66,180.000,YES,,,
R771,"Q_RES_0402LF-23.2K,1%,1/16W,CHIP,CS32322FB03",23.2K,1%,R0402,1614.00,7672.66,180.000,YES,,,
R772,"Q_RES_0402LF-35.7K,1%,1/16W,CHIP,CS33572FB01",35.7K,1%,R0402,1317.61,7672.66,180.000,YES,,,
R773,"Q_RES_0402LF-84.5K,1%,1/16W,CHIP,CS38452FB05",84.5K,1%,R0402,651.59,7754.04,270.000,YES,,,
R774,"Q_RES_0402LF-15.4K,1%,1/16W,CHIP,CS31542FB02",15.4K,1%,R0402,6800.30,7672.66,180.000,YES,,,
R775,"Q_RES_0402LF-23.2K,1%,1/16W,CHIP,CS32322FB03",23.2K,1%,R0402,7097.31,7672.66,180.000,YES,,,
R776,"Q_RES_0402LF-35.7K,1%,1/16W,CHIP,CS33572FB01",35.7K,1%,R0402,7394.32,7672.66,180.000,YES,,,
R777,"Q_RES_0402LF-54.9K,1%,1/16W,CHIP,CS35492FB03",54.9K,1%,R0402,7691.33,7672.66,180.000,YES,,,
R778,"Q_RES_0402LF-84.5K,1%,1/16W,CHIP,CS38452FB05",84.5K,1%,R0402,7988.33,7672.66,180.000,YES,,,
R779,"Q_RES_0201LF-0,5%,1/20W,CHIP,CS00001JE10",0,5%,R0201,8467.00,13280.00,0.000,YES,,,
R780,"Q_RES_0201LF-0,5%,1/20W,CHIP,CS00001JE10",0,5%,R0201,8467.00,13240.00,0.000,YES,,,
R781,"Q_RES_0201LF-4.7K,5%,1/20W,EMPTY,CS24701JE04",4.7K,5%,R0201,2934.00,15176.40,0.000,NO,,,
R782,"Q_RES_0201LF-10K,1%,1/20W,CHIP,CS31001FE17",10K,1%,R0201,2984.00,15180.40,0.000,NO,,,
R783,"Q_RES_0201LF-10K,1%,1/20W,CHIP,CS31001FE17",10K,1%,R0201,2984.00,15144.20,0.000,NO,,,
R784,"Q_RES_0201LF-4.7K,5%,1/20W,EMPTY,CS24701JE04",4.7K,5%,R0201,2934.00,15180.40,180.000,YES,,,
R785,"Q_RES_0201LF-4.7K,5%,1/20W,CHIP,CS24701JE04",4.7K,5%,R0201,2984.00,15180.40,180.000,YES,,,
R786,"Q_RES_0201LF-4.7K,5%,1/20W,EMPTY,CS24701JE04",4.7K,5%,R0201,2934.00,15144.20,180.000,YES,,,
R787,"Q_RES_0201LF-4.7K,5%,1/20W,CHIP,CS24701JE04",4.7K,5%,R0201,2984.00,15144.20,180.000,YES,,,
R788,"Q_RES_0201LF-4.7K,5%,1/20W,EMPTY,CS24701JE04",4.7K,5%,R0201,2924.00,15108.00,0.000,NO,,,
R789,"Q_RES_0402LF-0,5%,1/16W,EMPTY,CS00002JB13",0,5%,R0402,9365.00,8945.00,0.000,YES,,,
R790,"Q_RES_0402LF-0,5%,1/16W,EMPTY,CS00002JB13",0,5%,R0402,9435.00,8945.00,180.000,YES,,,
R791,"Q_RES_0201LF-4.7K,5%,1/20W,CHIP,CS24701JE04",4.7K,5%,R0201,2984.00,15108.00,0.000,NO,,,
R792,"Q_RES_0201LF-4.7K,5%,1/20W,CHIP,CS24701JE04",4.7K,5%,R0201,3114.76,15559.89,270.000,NO,,,
R793,"Q_RES_0201LF-4.7K,5%,1/20W,CHIP,CS24701JE04",4.7K,5%,R0201,3071.99,15568.38,270.000,NO,,,
R794,"Q_RES_0201LF-4.7K,5%,1/20W,EMPTY,CS24701JE04",4.7K,5%,R0201,3071.99,15518.38,270.000,NO,,,
R795,"Q_RES_0201LF-1K,1%,1/20W,EMPTY,CS21001FE07",1K,1%,R0201,4074.62,15066.00,180.000,NO,,,
R796,"Q_RES_0201LF-1K,1%,1/20W,CHIP,CS21001FE07",1K,1%,R0201,4126.62,15050.00,0.000,NO,,,
R797,"Q_RES_0201LF-0,5%,1/20W,CHIP,CS00001JE10",0,5%,R0201,10075.00,13460.00,180.000,YES,,,
R798,"Q_RES_0402LF-33,5%,1/16W,CHIP,CS03302JB10",33,5%,R0402,7766.52,4723.44,0.000,NO,,,
R799,"Q_RES_0201LF-0,5%,1/20W,CHIP,CS00001JE10",0,5%,R0201,10075.00,13415.80,180.000,YES,,,
R800,"Q_RES_0402LF-10K,1%,1/16W,CHIP,CS31002FB08",10K,1%,R0402,7911.52,4593.44,0.000,NO,,,
R801,"Q_RES_0201LF-0,5%,1/20W,CHIP,CS00001JE10",0,5%,R0201,9395.00,13145.00,180.000,YES,,,
R802,"Q_RES_0201LF-0,5%,1/20W,CHIP,CS00001JE10",0,5%,R0201,9395.00,13190.00,180.000,YES,,,
R803,"Q_RES_0201LF-0,5%,1/20W,CHIP,CS00001JE10",0,5%,R0201,9395.00,13235.00,180.000,YES,,,
R804,"Q_RES_0402LF-10K,1%,1/16W,CHIP,CS31002FB08",10K,1%,R0402,7911.52,4713.44,0.000,NO,,,
R805,"Q_RES_0201LF-0,5%,1/20W,CHIP,CS00001JE10",0,5%,R0201,9395.00,13280.00,180.000,YES,,,
R806,"Q_RES_0201LF-0,5%,1/20W,CHIP,CS00001JE10",0,5%,R0201,9395.00,13325.00,180.000,YES,,,
R807,"Q_RES_0201LF-0,5%,1/20W,CHIP,CS00001JE10",0,5%,R0201,9395.00,13370.00,180.000,YES,,,
R808,"Q_RES_0201LF-0,5%,1/20W,CHIP,CS00001JE10",0,5%,R0201,9395.00,13415.00,180.000,YES,,,
R809,"Q_RES_0201LF-0,5%,1/20W,CHIP,CS00001JE10",0,5%,R0201,9395.00,13460.00,180.000,YES,,,
R810,"Q_RES_0201LF-1K,1%,1/20W,CHIP,CS21001FE07",1K,1%,R0201,6634.39,16414.54,90.000,NO,,,
R811,"Q_RES_0402LF-1K,1%,1/16W,CHIP,CS21002FB06",1K,1%,R0402,10412.54,5160.14,180.000,NO,,,
R812,"Q_RES_0201LF-1K,1%,1/20W,CHIP,CS21001FE07",1K,1%,R0201,6667.29,16414.54,90.000,NO,,,
R813,"Q_RES_0402LF-10K,5%,1/16W,CHIP,CS31002JB08",10K,5%,R0402,14397.69,1782.17,270.000,NO,,,
R814,"Q_RES_0402LF-10K,5%,1/16W,EMPTY,CS31002JB08",10K,5%,R0402,14447.69,1702.17,270.000,NO,,,
R815,"Q_RES_0402LF-10K,5%,1/16W,EMPTY,CS31002JB08",10K,5%,R0402,14547.69,1702.17,270.000,NO,,,
R816,"Q_RES_0402LF-10K,5%,1/16W,CHIP,CS31002JB08",10K,5%,R0402,14497.69,1782.17,270.000,NO,,,
R817,"Q_RES_0402LF-0,5%,1/16W,CHIP,CS00002JB13",0,5%,R0402,14397.69,1702.17,270.000,NO,,,
R818,"Q_RES_0402LF-0,5%,1/16W,CHIP,CS00002JB13",0,5%,R0402,14430.49,1184.43,270.000,NO,,,
R819,"Q_RES_0402LF-0,5%,1/16W,CHIP,CS00002JB13",0,5%,R0402,14390.49,1184.43,270.000,NO,,,
R820,"Q_RES_0402LF-10K,5%,1/16W,EMPTY,CS31002JB08",10K,5%,R0402,14382.62,568.92,270.000,NO,,,
R821,"Q_RES_0402LF-10K,5%,1/16W,CHIP,CS31002JB08",10K,5%,R0402,14342.62,568.92,90.000,NO,,,
R822,"Q_RES_0402LF-10K,5%,1/16W,CHIP,CS31002JB08",10K,5%,R0402,14545.49,1114.43,90.000,NO,,,
R823,"Q_RES_0402LF-10K,5%,1/16W,EMPTY,CS31002JB08",10K,5%,R0402,14485.49,1186.43,90.000,NO,,,
R824,"Q_RES_0402LF-10K,5%,1/16W,CHIP,CS31002JB08",10K,5%,R0402,14430.49,1114.43,90.000,NO,,,
R825,"Q_RES_0402LF-10K,5%,1/16W,EMPTY,CS31002JB08",10K,5%,R0402,14390.49,1114.43,90.000,NO,,,
R826,"Q_RES_0201LF-1K,1%,1/20W,CHIP,CS21001FE07",1K,1%,R0201,6460.92,16542.71,90.000,YES,,,
R827,"Q_RES_0201LF-1K,1%,1/20W,CHIP,CS21001FE07",1K,1%,R0201,6492.16,16542.71,90.000,YES,,,
R828,"Q_RES_0201LF-0,5%,1/20W,CHIP,CS00001JE10",0,5%,R0201,10075.00,13371.60,180.000,YES,,,
R829,"Q_RES_0201LF-0,5%,1/20W,CHIP,CS00001JE10",0,5%,R0201,10075.00,13327.40,180.000,YES,,,
R830,"Q_RES_0201LF-0,5%,1/20W,CHIP,CS00001JE10",0,5%,R0201,10075.00,13282.60,180.000,YES,,,
R831,"Q_RES_0201LF-0,5%,1/20W,CHIP,CS00001JE10",0,5%,R0201,10075.00,13238.40,180.000,YES,,,
R832,"Q_RES_0201LF-0,5%,1/20W,CHIP,CS00001JE10",0,5%,R0201,10075.00,13194.20,180.000,YES,,,
R833,"Q_RES_0201LF-0,5%,1/20W,CHIP,CS00001JE10",0,5%,R0201,10075.00,13150.00,180.000,YES,,,
R834,"Q_RES_0201LF-1K,1%,1/20W,CHIP,CS21001FE07",1K,1%,R0201,11630.00,16730.00,180.000,YES,,,
R835,"Q_RES_0201LF-1K,1%,1/20W,CHIP,CS21001FE07",1K,1%,R0201,11630.00,16785.00,180.000,YES,,,
R836,"Q_RES_0201LF-1K,1%,1/20W,CHIP,CS21001FE07",1K,1%,R0201,11476.77,15653.15,180.000,NO,,,
R837,"Q_RES_0201LF-1K,1%,1/20W,CHIP,CS21001FE07",1K,1%,R0201,11423.60,15653.12,0.000,NO,,,
R838,"Q_RES_0201LF-1K,1%,1/20W,CHIP,CS21001FE07",1K,1%,R0201,14403.42,16654.44,180.000,YES,,,
R839,"Q_RES_0201LF-1K,1%,1/20W,CHIP,CS21001FE07",1K,1%,R0201,14509.80,16762.83,90.000,YES,,,
R840,"Q_RES_0201LF-1K,1%,1/20W,CHIP,CS21001FE07",1K,1%,R0201,16501.16,16803.12,180.000,YES,,,
R841,"Q_RES_0201LF-1K,1%,1/20W,CHIP,CS21001FE07",1K,1%,R0201,16501.61,16834.41,180.000,YES,,,
R842,"Q_RES_0201LF-4.7K,5%,1/20W,EMPTY,CS24701JE04",4.7K,5%,R0201,10025.00,13105.00,180.000,YES,,,
R843,"Q_RES_0201LF-4.7K,5%,1/20W,EMPTY,CS24701JE04",4.7K,5%,R0201,9493.72,13055.00,180.000,YES,,,
R844,"Q_RES_0201LF-4.7K,5%,1/20W,EMPTY,CS24701JE04",4.7K,5%,R0201,9493.72,13015.00,180.000,YES,,,
R845,"Q_RES_0201LF-4.7K,5%,1/20W,CHIP,CS24701JE04",4.7K,5%,R0201,10075.00,13105.00,180.000,YES,,,
R846,"Q_RES_0201LF-4.7K,5%,1/20W,CHIP,CS24701JE04",4.7K,5%,R0201,9415.00,13050.00,0.000,YES,,,
R847,"Q_RES_0201LF-4.7K,5%,1/20W,CHIP,CS24701JE04",4.7K,5%,R0201,9415.00,13015.00,0.000,YES,,,
R848,"Q_RES_0201LF-0,5%,1/20W,CHIP,CS00001JE10",0,5%,R0201,9493.72,13095.00,180.000,YES,,,
R849,"Q_RES_0201LF-10K,1%,1/20W,CHIP,CS31001FE17",10K,1%,R0201,9415.00,13095.00,0.000,YES,,,
R850,"Q_RES_0201LF-0,5%,1/20W,CHIP,CS00001JE10",0,5%,R0201,10025.00,13030.00,180.000,YES,,,
R851,"Q_RES_0201LF-0,5%,1/20W,CHIP,CS00001JE10",0,5%,R0201,10025.00,13070.00,180.000,YES,,,
R852,"Q_RES_0402LF-0,5%,1/16W,EMPTY,CS00002JB13",0,5%,R0402,6711.40,15266.26,180.000,NO,,,
R853,"Q_RES_0402LF-0,5%,1/16W,EMPTY,CS00002JB13",0,5%,R0402,6711.40,15305.26,180.000,NO,,,
R854,"Q_RES_0201LF-0,5%,1/20W,CHIP,CS00001JE10",0,5%,R0201,6606.15,15576.00,270.000,NO,,,
R855,"Q_RES_0402LF-11.5K,1%,1/16W,EMPTY,CS31152FB03",11.5K,1%,R0402,1698.60,4005.60,0.000,NO,,,
R856,"Q_RES_0402LF-0,5%,1/16W,CHIP,CS00002JB13",0,5%,R0402,7445.00,5258.62,90.000,NO,,,
R857,"Q_RES_0402LF-0,5%,1/16W,EMPTY,CS00002JB13",0,5%,R0402,6742.90,15266.26,180.000,NO,,,
R858,"Q_RES_0603LF-0,5%,1/4W,EMPTY,CS00006J900",0,5%,R0603,5492.77,15481.99,180.000,YES,,,
R859,"Q_RES_0603LF-0,5%,1/4W,CHIP,CS00006J900",0,5%,R0603,5550.77,15481.99,180.000,YES,,,
R860,"Q_RES_0201LF-0,5%,1/20W,CHIP,CS00001JE10",0,5%,R0201,5643.72,15547.38,90.000,NO,,,
R861,"Q_RES_0201LF-1K,1%,1/20W,CHIP,CS21001FE07",1K,1%,R0201,6901.61,15375.20,180.000,NO,,,
R862,"Q_RES_0402LF-0,5%,1/16W,CHIP,CS00002JB13",0,5%,R0402,3563.13,8165.75,90.000,YES,,,
R863,"Q_RES_0201LF-1K,1%,1/20W,EMPTY,CS21001FE07",1K,1%,R0201,6851.61,15375.20,180.000,NO,,,
R864,"Q_RES_0201LF-1K,1%,1/20W,EMPTY,CS21001FE07",1K,1%,R0201,6901.61,15407.20,180.000,NO,,,
R865,"Q_RES_0201LF-20K,1%,1/20W,CHIP,CS32001FE00",20K,1%,R0201,6851.61,15407.20,180.000,NO,,,
R866,"Q_RES_0201LF-10K,1%,1/20W,CHIP,CS31001FE17",10K,1%,R0201,6606.15,15526.00,270.000,NO,,,
R867,"Q_RES_0201LF-10K,1%,1/20W,CHIP,CS31001FE17",10K,1%,R0201,5681.72,15518.38,270.000,NO,,,
R868,"Q_RES_0201LF-4.7K,5%,1/20W,EMPTY,CS24701JE04",4.7K,5%,R0201,5575.73,15108.00,180.000,YES,,,
R869,"Q_RES_0201LF-200,1%,1/20W,CHIP,CS12001FE12",200,1%,R0201,5625.73,15108.00,180.000,YES,,,
R870,"Q_RES_0201LF-4.7K,5%,1/20W,EMPTY,CS24701JE04",4.7K,5%,R0201,5681.72,15568.38,270.000,NO,,,
R871,"Q_RES_0201LF-4.7K,5%,1/20W,EMPTY,CS24701JE04",4.7K,5%,R0201,5756.49,15609.89,270.000,NO,,,
R872,"Q_RES_0201LF-0,5%,1/20W,CHIP,CS00001JE10",0,5%,R0201,8467.00,13460.00,0.000,YES,,,
R873,"Q_RES_0201LF-0,5%,1/20W,CHIP,CS00001JE10",0,5%,R0201,8467.00,13420.00,0.000,YES,,,
R874,"Q_RES_0201LF-4.7K,5%,1/20W,EMPTY,CS24701JE04",4.7K,5%,R0201,5575.73,15176.40,0.000,NO,,,
R875,"Q_RES_0201LF-10K,1%,1/20W,CHIP,CS31001FE17",10K,1%,R0201,5625.73,15180.40,0.000,NO,,,
R876,"Q_RES_0201LF-10K,1%,1/20W,CHIP,CS31001FE17",10K,1%,R0201,5625.73,15144.20,0.000,NO,,,
R877,"Q_RES_0402LF-0,5%,1/16W,CHIP,CS00002JB13",0,5%,R0402,8422.37,4864.78,0.000,NO,,,
R878,"Q_RES_0201LF-4.7K,5%,1/20W,EMPTY,CS24701JE04",4.7K,5%,R0201,5575.73,15180.40,180.000,YES,,,
R879,"Q_RES_0201LF-4.7K,5%,1/20W,CHIP,CS24701JE04",4.7K,5%,R0201,5625.73,15180.40,180.000,YES,,,
R880,"Q_RES_0201LF-4.7K,5%,1/20W,EMPTY,CS24701JE04",4.7K,5%,R0201,5575.73,15144.20,180.000,YES,,,
R881,"Q_RES_0201LF-4.7K,5%,1/20W,CHIP,CS24701JE04",4.7K,5%,R0201,5625.73,15144.20,180.000,YES,,,
R882,"Q_RES_0201LF-4.7K,5%,1/20W,EMPTY,CS24701JE04",4.7K,5%,R0201,5565.73,15108.00,0.000,NO,,,
R883,"Q_RES_0201LF-4.7K,5%,1/20W,CHIP,CS24701JE04",4.7K,5%,R0201,5625.73,15108.00,0.000,NO,,,
R884,"Q_RES_0201LF-4.7K,5%,1/20W,CHIP,CS24701JE04",4.7K,5%,R0201,5756.49,15559.89,270.000,NO,,,
R885,"Q_RES_0201LF-4.7K,5%,1/20W,CHIP,CS24701JE04",4.7K,5%,R0201,5713.72,15568.38,270.000,NO,,,
R886,"Q_RES_0201LF-4.7K,5%,1/20W,EMPTY,CS24701JE04",4.7K,5%,R0201,5713.72,15518.38,270.000,NO,,,
R887,"Q_RES_0201LF-1K,1%,1/20W,EMPTY,CS21001FE07",1K,1%,R0201,6731.49,15083.35,180.000,NO,,,
R888,"Q_RES_0402LF-10K,5%,1/16W,EMPTY,CS31002JB08",10K,5%,R0402,6580.00,4578.62,180.000,YES,,,
R889,"Q_RES_0402LF-10K,5%,1/16W,EMPTY,CS31002JB08",10K,5%,R0402,6740.00,4578.62,0.000,YES,,,
R890,"Q_RES_0402LF-10K,5%,1/16W,EMPTY,CS31002JB08",10K,5%,R0402,6580.00,4658.62,180.000,YES,,,
R891,"Q_RES_0402LF-10K,5%,1/16W,EMPTY,CS31002JB08",10K,5%,R0402,6740.00,4658.62,0.000,YES,,,
R892,"Q_RES_0201LF-1K,1%,1/20W,CHIP,CS21001FE07",1K,1%,R0201,6731.49,15051.35,0.000,NO,,,
R893,"Q_RES_0402LF-0,5%,1/16W,EMPTY,CS00002JB13",0,5%,R0402,5392.22,15122.20,180.000,NO,,,
R894,"Q_RES_0402LF-0,5%,1/16W,EMPTY,CS00002JB13",0,5%,R0402,5392.22,15161.20,180.000,NO,,,
R895,"Q_RES_0201LF-0,5%,1/20W,CHIP,CS00001JE10",0,5%,R0201,5325.53,15576.00,270.000,NO,,,
R896,"Q_RES_0402LF-30K,1%,1/16W,EMPTY,CS33002FB02",30K,1%,R0402,1838.90,3921.60,90.000,NO,,,
R897,"Q_RES_0402LF-0,5%,1/16W,EMPTY,CS00002JB13",0,5%,R0402,5423.72,15122.20,180.000,NO,,,
R898,"Q_RES_0603LF-0,5%,1/4W,EMPTY,CS00006J900",0,5%,R0603,4212.15,15481.99,180.000,YES,,,
R899,"Q_RES_0402LF-0,5%,1/16W,CHIP,CS00002JB13",0,5%,R0402,8420.86,4946.61,0.000,NO,,,
R900,"Q_RES_0603LF-0,5%,1/4W,CHIP,CS00006J900",0,5%,R0603,4270.15,15481.99,180.000,YES,,,
R901,"Q_RES_0201LF-0,5%,1/20W,CHIP,CS00001JE10",0,5%,R0201,4355.13,15327.44,90.000,NO,,,
R902,"Q_RES_0201LF-1K,1%,1/20W,CHIP,CS21001FE07",1K,1%,R0201,5471.73,15178.00,90.000,NO,,,
R903,"Q_RES_0201LF-1K,1%,1/20W,EMPTY,CS21001FE07",1K,1%,R0201,5471.73,15228.00,90.000,NO,,,
R904,"Q_RES_0201LF-1K,1%,1/20W,EMPTY,CS21001FE07",1K,1%,R0201,5503.73,15178.00,90.000,NO,,,
R905,"Q_RES_0402LF-0,5%,1/16W,CHIP,CS00002JB13",0,5%,R0402,8422.01,4905.67,0.000,NO,,,
R906,"Q_RES_0201LF-20K,1%,1/20W,CHIP,CS32001FE00",20K,1%,R0201,5503.73,15228.00,90.000,NO,,,
R907,"Q_RES_0201LF-10K,1%,1/20W,CHIP,CS31001FE17",10K,1%,R0201,5315.80,15525.70,270.000,NO,,,
R908,"Q_RES_0201LF-10K,1%,1/20W,CHIP,CS31001FE17",10K,1%,R0201,4406.10,15518.38,270.000,NO,,,
R909,"Q_RES_0201LF-4.7K,5%,1/20W,EMPTY,CS24701JE04",4.7K,5%,R0201,4295.11,15108.00,180.000,YES,,,
R910,"Q_RES_0201LF-200,1%,1/20W,CHIP,CS12001FE12",200,1%,R0201,4345.11,15108.00,180.000,YES,,,
R911,"Q_RES_0201LF-4.7K,5%,1/20W,EMPTY,CS24701JE04",4.7K,5%,R0201,4430.40,15568.58,270.000,NO,,,
R912,"Q_RES_0201LF-4.7K,5%,1/20W,EMPTY,CS24701JE04",4.7K,5%,R0201,4573.17,15564.59,270.000,NO,,,
R913,"Q_RES_0201LF-0,5%,1/20W,CHIP,CS00001JE10",0,5%,R0201,8430.00,13370.00,0.000,YES,,,
R914,"Q_RES_0201LF-0,5%,1/20W,CHIP,CS00001JE10",0,5%,R0201,8430.00,13330.00,0.000,YES,,,
R915,"Q_RES_0201LF-4.7K,5%,1/20W,EMPTY,CS24701JE04",4.7K,5%,R0201,4295.11,15176.40,0.000,NO,,,
R916,"Q_RES_0201LF-10K,1%,1/20W,CHIP,CS31001FE17",10K,1%,R0201,4345.11,15180.40,0.000,NO,,,
R917,"Q_RES_0201LF-10K,1%,1/20W,CHIP,CS31001FE17",10K,1%,R0201,4345.11,15144.20,0.000,NO,,,
R918,"Q_RES_0201LF-4.7K,5%,1/20W,EMPTY,CS24701JE04",4.7K,5%,R0201,4295.11,15180.40,180.000,YES,,,
R919,"Q_RES_0201LF-4.7K,5%,1/20W,CHIP,CS24701JE04",4.7K,5%,R0201,4345.11,15180.40,180.000,YES,,,
R920,"Q_RES_0201LF-4.7K,5%,1/20W,EMPTY,CS24701JE04",4.7K,5%,R0201,4295.11,15144.20,180.000,YES,,,
R921,"Q_RES_0201LF-4.7K,5%,1/20W,CHIP,CS24701JE04",4.7K,5%,R0201,4345.11,15144.20,180.000,YES,,,
R922,"Q_RES_0201LF-4.7K,5%,1/20W,EMPTY,CS24701JE04",4.7K,5%,R0201,4285.11,15108.00,0.000,NO,,,
R923,"Q_RES_0201LF-4.7K,5%,1/20W,CHIP,CS24701JE04",4.7K,5%,R0201,4345.11,15108.00,0.000,NO,,,
R924,"Q_RES_0201LF-4.7K,5%,1/20W,CHIP,CS24701JE04",4.7K,5%,R0201,4495.97,15559.89,270.000,NO,,,
R925,"Q_RES_0201LF-4.7K,5%,1/20W,CHIP,CS24701JE04",4.7K,5%,R0201,4462.40,15568.58,270.000,NO,,,
R926,"Q_RES_0201LF-4.7K,5%,1/20W,EMPTY,CS24701JE04",4.7K,5%,R0201,4438.10,15518.38,270.000,NO,,,
R927,"Q_RES_0201LF-1K,1%,1/20W,EMPTY,CS21001FE07",1K,1%,R0201,5435.73,15066.00,180.000,NO,,,
R928,"Q_RES_0402LF-0,5%,1/16W,CHIP,CS00002JB13",0,5%,R0402,3528.13,8165.75,90.000,YES,,,
R929,"Q_RES_0402LF-0,5%,1/16W,CHIP,CS00002JB13",0,5%,R0402,173.63,2317.48,270.000,NO,,,
R930,"Q_RES_0402LF-0,5%,1/16W,CHIP,CS00002JB13",0,5%,R0402,105.43,2317.92,270.000,NO,,,
R931,"Q_RES_0402LF-0,5%,1/16W,CHIP,CS00002JB13",0,5%,R0402,117.82,1734.76,90.000,NO,,,
R932,"Q_RES_0402LF-0,5%,1/16W,CHIP,CS00002JB13",0,5%,R0402,186.91,1736.48,90.000,NO,,,
R933,"Q_RES_0402LF-33,5%,1/16W,CHIP,CS03302JB10",33,5%,R0402,7285.00,5093.62,90.000,NO,,,
R934,"Q_RES_0402LF-0,5%,1/16W,CHIP,CS00002JB13",0,5%,R0402,15691.48,13431.98,90.000,YES,,,
R935,"Q_RES_0402LF-0,5%,1/16W,CHIP,CS00002JB13",0,5%,R0402,13373.99,940.84,270.000,NO,,,
R936,"Q_RES_0402LF-0,5%,1/16W,CHIP,CS00002JB13",0,5%,R0402,13561.99,940.50,270.000,NO,,,
R937,"Q_RES_0402LF-0,5%,1/16W,CHIP,CS00002JB13",0,5%,R0402,7525.00,5418.62,90.000,NO,,,
R938,"Q_RES_0402LF-4.7K,5%,1/16W,CHIP,CS24702JB10",4.7K,5%,R0402,15832.72,12982.78,180.000,NO,,,
R939,"Q_RES_0402LF-0,5%,1/16W,CHIP,CS00002JB13",0,5%,R0402,15054.77,12723.88,90.000,NO,,,
R940,"Q_RES_0402LF-0,5%,1/16W,CHIP,CS00002JB13",0,5%,R0402,15832.72,13022.78,0.000,NO,,,
R941,"Q_RES_0402LF-0,5%,1/16W,EMPTY,CS00002JB13",0,5%,R0402,15729.24,13431.98,90.000,YES,,,
R942,"Q_RES_0402LF-4.7K,5%,1/16W,CHIP,CS24702JB10",4.7K,5%,R0402,15655.02,13431.84,270.000,YES,,,
R943,"Q_RES_0402LF-4.7K,5%,1/16W,CHIP,CS24702JB10",4.7K,5%,R0402,15809.24,13501.98,270.000,YES,,,
R944,"Q_RES_0402LF-4.7K,5%,1/16W,CHIP,CS24702JB10",4.7K,5%,R0402,13413.99,940.84,270.000,NO,,,
R945,"Q_RES_0402LF-4.7K,5%,1/16W,CHIP,CS24702JB10",4.7K,5%,R0402,13521.99,940.50,270.000,NO,,,
R946,"Q_RES_0402LF-4.7K,5%,1/16W,CHIP,CS24702JB10",4.7K,5%,R0402,13481.99,940.84,270.000,NO,,,
R947,"Q_RES_0402LF-4.7K,5%,1/16W,CHIP,CS24702JB10",4.7K,5%,R0402,13601.09,940.50,270.000,NO,,,
R948,"Q_RES_0402LF-130,1%,1/16W,CHIP,CS11302FB03",130,1%,R0402,13319.30,629.45,90.000,NO,,,
R949,"Q_RES_0201LF-1K,1%,1/20W,CHIP,CS21001FE07",1K,1%,R0201,5493.88,15039.60,0.000,NO,,,
R950,"Q_RES_0402LF-249,1%,1/16W,CHIP,CS12492FB02",249,1%,R0402,13438.40,629.11,90.000,NO,,,
R951,"Q_RES_0402LF-0,5%,1/16W,EMPTY,CS00002JB13",0,5%,R0402,12829.22,15491.20,180.000,NO,,,
R952,"Q_RES_0402LF-0,5%,1/16W,EMPTY,CS00002JB13",0,5%,R0402,12829.22,15452.20,180.000,NO,,,
R953,"Q_RES_0201LF-0,5%,1/20W,CHIP,CS00001JE10",0,5%,R0201,12762.53,15906.00,270.000,NO,,,
R954,"Q_RES_0402LF-11.5K,1%,1/16W,EMPTY,CS31152FB03",11.5K,1%,R0402,1894.10,3921.60,270.000,NO,,,
R955,"Q_RES_0402LF-0,5%,1/16W,CHIP,CS00002JB13",0,5%,R0402,9492.63,2761.56,270.000,NO,,,
R956,"Q_RES_0402LF-0,5%,1/16W,CHIP,CS00002JB13",0,5%,R0402,8422.00,4821.28,0.000,NO,,,
R957,"Q_RES_0402LF-33,5%,1/16W,CHIP,CS03302JB10",33,5%,R0402,7766.52,4593.44,0.000,NO,,,
R958,"Q_RES_0402LF-33,5%,1/16W,CHIP,CS03302JB10",33,5%,R0402,7315.00,3948.62,270.000,YES,,,
R959,"Q_RES_0402LF-33,5%,1/16W,CHIP,CS03302JB10",33,5%,R0402,7235.00,3948.62,270.000,YES,,,
R960,"Q_RES_0402LF-0,5%,1/16W,EMPTY,CS00002JB13",0,5%,R0402,12860.72,15452.20,180.000,NO,,,
R961,"Q_RES_0603LF-0,5%,1/4W,EMPTY,CS00006J900",0,5%,R0603,11835.55,16054.90,0.000,NO,,,
R962,"Q_RES_0603LF-0,5%,1/4W,CHIP,CS00006J900",0,5%,R0603,11893.55,16054.90,0.000,NO,,,
R963,"Q_RES_0201LF-0,5%,1/20W,CHIP,CS00001JE10",0,5%,R0201,11714.73,15678.00,180.000,NO,,,
R964,"Q_RES_0201LF-1K,1%,1/20W,CHIP,CS21001FE07",1K,1%,R0201,12908.73,15508.00,90.000,NO,,,
R965,"Q_RES_0201LF-1K,1%,1/20W,EMPTY,CS21001FE07",1K,1%,R0201,12908.73,15558.00,90.000,NO,,,
R966,"Q_RES_0201LF-1K,1%,1/20W,EMPTY,CS21001FE07",1K,1%,R0201,12940.73,15508.00,90.000,NO,,,
R967,"Q_RES_0201LF-20K,1%,1/20W,CHIP,CS32001FE00",20K,1%,R0201,12940.73,15558.00,90.000,NO,,,
R968,"Q_RES_0201LF-1K,1%,1/20W,EMPTY,CS21001FE07",1K,1%,R0201,12872.73,15396.00,180.000,NO,,,
R969,"Q_RES_0201LF-1K,1%,1/20W,CHIP,CS21001FE07",1K,1%,R0201,12924.73,15380.00,0.000,NO,,,
R970,"Q_RES_0201LF-10K,1%,1/20W,CHIP,CS31001FE17",10K,1%,R0201,12762.53,15856.00,270.000,NO,,,
R971,"Q_RES_0201LF-10K,1%,1/20W,CHIP,CS31001FE17",10K,1%,R0201,11714.73,15646.00,0.000,NO,,,
R972,"Q_RES_0201LF-4.7K,5%,1/20W,EMPTY,CS24701JE04",4.7K,5%,R0201,11782.11,15396.40,180.000,YES,,,
R973,"Q_RES_0201LF-200,1%,1/20W,CHIP,CS12001FE12",200,1%,R0201,11782.11,15428.40,180.000,YES,,,
R974,"Q_RES_0201LF-4.7K,5%,1/20W,EMPTY,CS24701JE04",4.7K,5%,R0201,11668.73,15646.00,270.000,NO,,,
R975,"Q_RES_0201LF-4.7K,5%,1/20W,EMPTY,CS24701JE04",4.7K,5%,R0201,11668.73,15754.00,270.000,NO,,,
R976,"Q_RES_0201LF-0,5%,1/20W,CHIP,CS00001JE10",0,5%,R0201,9180.00,13420.00,180.000,YES,,,
R977,"Q_RES_0201LF-0,5%,1/20W,CHIP,CS00001JE10",0,5%,R0201,9180.00,13460.00,180.000,YES,,,
R978,"Q_RES_0201LF-4.7K,5%,1/20W,EMPTY,CS24701JE04",4.7K,5%,R0201,11732.11,15510.40,0.000,NO,,,
R979,"Q_RES_0201LF-10K,1%,1/20W,CHIP,CS31001FE17",10K,1%,R0201,11782.11,15510.40,0.000,NO,,,
R980,"Q_RES_0201LF-10K,1%,1/20W,CHIP,CS31001FE17",10K,1%,R0201,11782.11,15474.20,0.000,NO,,,
R981,"Q_RES_0201LF-4.7K,5%,1/20W,EMPTY,CS24701JE04",4.7K,5%,R0201,11782.11,15555.40,180.000,YES,,,
R982,"Q_RES_0201LF-4.7K,5%,1/20W,CHIP,CS24701JE04",4.7K,5%,R0201,11782.11,15523.40,180.000,YES,,,
R983,"Q_RES_0201LF-4.7K,5%,1/20W,EMPTY,CS24701JE04",4.7K,5%,R0201,11782.11,15491.40,180.000,YES,,,
R984,"Q_RES_0201LF-4.7K,5%,1/20W,CHIP,CS24701JE04",4.7K,5%,R0201,11782.11,15459.40,180.000,YES,,,
R985,"Q_RES_0201LF-4.7K,5%,1/20W,EMPTY,CS24701JE04",4.7K,5%,R0201,11722.11,15438.00,0.000,NO,,,
R986,"Q_RES_0402LF-0,5%,1/16W,EMPTY,CS00002JB13",0,5%,R0402,14971.77,8106.38,270.000,YES,,,
R987,"Q_RES_0402LF-0,5%,1/16W,EMPTY,CS00002JB13",0,5%,R0402,15081.77,8106.38,270.000,YES,,,
R988,"Q_RES_0402LF-0,5%,1/16W,EMPTY,CS00002JB13",0,5%,R0402,1711.50,6705.00,0.000,NO,,,
R989,"Q_RES_0402LF-0,5%,1/16W,EMPTY,CS00002JB13",0,5%,R0402,1711.50,6765.00,0.000,NO,,,
R990,"Q_RES_0402LF-0,5%,1/16W,EMPTY,CS00002JB13",0,5%,R0402,6284.08,7635.79,270.000,YES,,,
R991,"Q_RES_0402LF-0,5%,1/16W,EMPTY,CS00002JB13",0,5%,R0402,6349.46,7626.28,270.000,YES,,,
R992,"Q_RES_0402LF-33,5%,1/16W,CHIP,CS03302JB10",33,5%,R0402,6740.00,4538.62,0.000,YES,,,
R993,"Q_RES_0402LF-1K,1%,1/16W,CHIP,CS21002FB06",1K,1%,R0402,6579.38,4538.80,0.000,YES,,,
R994,"Q_RES_0402LF-10K,1%,1/16W,CHIP,CS31002FB08",10K,1%,R0402,6267.05,3013.05,270.000,NO,,,
R995,"Q_RES_0201LF-4.7K,5%,1/20W,CHIP,CS24701JE04",4.7K,5%,R0201,11782.11,15438.00,0.000,NO,,,
R996,"Q_RES_0402LF-4.7K,5%,1/16W,CHIP,CS24702JB10",4.7K,5%,R0402,5846.23,4359.49,0.000,NO,,,
R997,"Q_RES_0201LF-4.7K,5%,1/20W,CHIP,CS24701JE04",4.7K,5%,R0201,11714.73,15755.00,0.000,NO,,,
R998,"Q_RES_0201LF-4.7K,5%,1/20W,CHIP,CS24701JE04",4.7K,5%,R0201,11668.73,15700.00,90.000,NO,,,
R999,"Q_RES_0402LF-4.7K,5%,1/16W,CHIP,CS24702JB10",4.7K,5%,R0402,9452.63,2761.56,90.000,NO,,,
R1000,"Q_RES_0402LF-4.7K,5%,1/16W,CHIP,CS24702JB10",4.7K,5%,R0402,9162.68,2738.59,90.000,NO,,,
R1001,"Q_RES_0201LF-4.7K,5%,1/20W,EMPTY,CS24701JE04",4.7K,5%,R0201,11714.73,15710.00,0.000,NO,,,
R1002,"Q_RES_0402LF-0,5%,1/16W,EMPTY,CS00002JB13",0,5%,R0402,14109.84,15491.20,180.000,NO,,,
R1003,"Q_RES_0402LF-0,5%,1/16W,EMPTY,CS00002JB13",0,5%,R0402,14109.84,15452.20,180.000,NO,,,
R1004,"Q_RES_0201LF-0,5%,1/20W,CHIP,CS00001JE10",0,5%,R0201,14043.15,15906.00,270.000,NO,,,
R1005,"Q_RES_0402LF-33,5%,1/16W,CHIP,CS03302JB10",33,5%,R0402,6227.05,2943.05,90.000,NO,,,
R1006,"Q_RES_0201LF-4.7K,5%,1/20W,EMPTY,CS24701JE04",4.7K,5%,R0201,13150.72,15848.38,270.000,NO,,,
R1007,"Q_RES_0402LF-2K,1%,1/16W,EMPTY,CS22002FB07",2K,1%,R0402,1403.60,4255.80,270.000,NO,,,
R1008,"Q_RES_0402LF-0,5%,1/16W,EMPTY,CS00002JB13",0,5%,R0402,14141.34,15452.20,180.000,NO,,,
R1009,"Q_RES_0402LF-10K,1%,1/16W,CHIP,CS31002FB08",10K,1%,R0402,6501.60,3070.89,180.000,NO,,,
R1010,"Q_RES_0603LF-0,5%,1/4W,EMPTY,CS00006J900",0,5%,R0603,12929.77,15811.99,180.000,YES,,,
R1011,"Q_RES_0603LF-0,5%,1/4W,CHIP,CS00006J900",0,5%,R0603,12987.77,15811.99,180.000,YES,,,
R1012,"Q_RES_0201LF-0,5%,1/20W,CHIP,CS00001JE10",0,5%,R0201,13080.72,15877.38,90.000,NO,,,
R1013,"Q_RES_0201LF-1K,1%,1/20W,CHIP,CS21001FE07",1K,1%,R0201,14189.35,15508.00,90.000,NO,,,
R1014,"Q_RES_0201LF-1K,1%,1/20W,EMPTY,CS21001FE07",1K,1%,R0201,14189.35,15558.00,90.000,NO,,,
R1015,"Q_RES_0201LF-1K,1%,1/20W,EMPTY,CS21001FE07",1K,1%,R0201,14221.35,15508.00,90.000,NO,,,
R1016,"Q_RES_0201LF-20K,1%,1/20W,CHIP,CS32001FE00",20K,1%,R0201,14221.35,15558.00,90.000,NO,,,
R1017,"Q_RES_0201LF-1K,1%,1/20W,EMPTY,CS21001FE07",1K,1%,R0201,14153.35,15396.00,180.000,NO,,,
R1018,"Q_RES_0201LF-1K,1%,1/20W,CHIP,CS21001FE07",1K,1%,R0201,14205.35,15380.00,0.000,NO,,,
R1019,"Q_RES_0201LF-10K,1%,1/20W,CHIP,CS31001FE17",10K,1%,R0201,14043.15,15856.00,270.000,NO,,,
R1020,"Q_RES_0201LF-10K,1%,1/20W,CHIP,CS31001FE17",10K,1%,R0201,13118.72,15848.38,270.000,NO,,,
R1021,"Q_RES_0201LF-4.7K,5%,1/20W,EMPTY,CS24701JE04",4.7K,5%,R0201,13012.73,15438.00,180.000,YES,,,
R1022,"Q_RES_0201LF-200,1%,1/20W,CHIP,CS12001FE12",200,1%,R0201,13062.73,15438.00,180.000,YES,,,
R1023,"Q_RES_0201LF-4.7K,5%,1/20W,EMPTY,CS24701JE04",4.7K,5%,R0201,13118.72,15898.38,270.000,NO,,,
R1024,"Q_RES_0201LF-4.7K,5%,1/20W,EMPTY,CS24701JE04",4.7K,5%,R0201,13193.49,15939.89,270.000,NO,,,
R1025,"Q_RES_0201LF-0,5%,1/20W,CHIP,CS00001JE10",0,5%,R0201,9205.00,13330.00,180.000,YES,,,
R1026,"Q_RES_0201LF-0,5%,1/20W,CHIP,CS00001JE10",0,5%,R0201,9205.00,13370.00,180.000,YES,,,
R1027,"Q_RES_0201LF-4.7K,5%,1/20W,EMPTY,CS24701JE04",4.7K,5%,R0201,13012.73,15506.40,0.000,NO,,,
R1028,"Q_RES_0201LF-10K,1%,1/20W,CHIP,CS31001FE17",10K,1%,R0201,13062.73,15510.40,0.000,NO,,,
R1029,"Q_RES_0201LF-10K,1%,1/20W,CHIP,CS31001FE17",10K,1%,R0201,13062.73,15474.20,0.000,NO,,,
R1030,"Q_RES_0201LF-4.7K,5%,1/20W,EMPTY,CS24701JE04",4.7K,5%,R0201,13012.73,15510.40,180.000,YES,,,
R1031,"Q_RES_0201LF-4.7K,5%,1/20W,CHIP,CS24701JE04",4.7K,5%,R0201,13062.73,15510.40,180.000,YES,,,
R1032,"Q_RES_0201LF-4.7K,5%,1/20W,EMPTY,CS24701JE04",4.7K,5%,R0201,13012.73,15474.20,180.000,YES,,,
R1033,"Q_RES_0201LF-4.7K,5%,1/20W,CHIP,CS24701JE04",4.7K,5%,R0201,13062.73,15474.20,180.000,YES,,,
R1034,"Q_RES_0201LF-4.7K,5%,1/20W,EMPTY,CS24701JE04",4.7K,5%,R0201,13002.73,15438.00,0.000,NO,,,
R1035,"Q_RES_0201LF-4.7K,5%,1/20W,CHIP,CS24701JE04",4.7K,5%,R0201,13062.73,15438.00,0.000,NO,,,
R1036,"Q_RES_0402LF-0,5%,1/16W,CHIP,CS00002JB13",0,5%,R0402,7395.00,3783.62,270.000,NO,,,
R1037,"Q_RES_0201LF-4.7K,5%,1/20W,CHIP,CS24701JE04",4.7K,5%,R0201,13193.49,15889.89,270.000,NO,,,
R1038,"Q_RES_0402LF-0,5%,1/16W,CHIP,CS00002JB13",0,5%,R0402,9202.68,2738.59,270.000,NO,,,
R1039,"Q_RES_0201LF-4.7K,5%,1/20W,CHIP,CS24701JE04",4.7K,5%,R0201,13150.72,15898.38,270.000,NO,,,
R1040,"Q_RES_0201LF-1K,1%,1/20W,EMPTY,CS21001FE07",1K,1%,R0201,13979.55,15906.00,270.000,NO,,,
R1041,"Q_RES_0201LF-200,1%,1/20W,CHIP,CS12001FE12",200,1%,R0201,13979.55,15856.00,270.000,NO,,,
R1042,"Q_RES_0201LF-0,5%,1/20W,CHIP,CS00001JE10",0,5%,R0201,14117.35,15404.00,180.000,YES,,,
R1043,"Q_RES_0201LF-0,5%,1/20W,CHIP,CS00001JE10",0,5%,R0201,14075.15,15856.00,270.000,NO,,,
R1044,"Q_RES_0201LF-1K,1%,1/20W,CHIP,CS21001FE07",1K,1%,R0201,11384.80,15730.46,270.000,NO,,,
R1045,"Q_RES_0402LF-0,5%,1/16W,EMPTY,CS00002JB13",0,5%,R0402,16790.14,15596.26,180.000,NO,,,
R1046,"Q_RES_0402LF-0,5%,1/16W,EMPTY,CS00002JB13",0,5%,R0402,16790.14,15635.26,180.000,NO,,,
R1047,"Q_RES_0201LF-0,5%,1/20W,CHIP,CS00001JE10",0,5%,R0201,16684.89,15906.00,270.000,NO,,,
R1048,"Q_RES_0201LF-4.7K,5%,1/20W,EMPTY,CS24701JE04",4.7K,5%,R0201,15792.46,15848.38,270.000,NO,,,
R1049,"Q_RES_0402LF-1K,1%,1/16W,EMPTY,CS21002FB06",1K,1%,R0402,1446.10,4255.80,90.000,NO,,,
R1050,"Q_RES_0402LF-0,5%,1/16W,EMPTY,CS00002JB13",0,5%,R0402,16821.64,15596.26,180.000,NO,,,
R1051,"Q_RES_0603LF-0,5%,1/4W,EMPTY,CS00006J900",0,5%,R0603,15571.51,15811.99,180.000,YES,,,
R1052,"Q_RES_0402LF-1K,1%,1/16W,EMPTY,CS21002FB06",1K,1%,R0402,1761.00,4123.50,0.000,NO,,,
R1053,"Q_RES_0603LF-0,5%,1/4W,CHIP,CS00006J900",0,5%,R0603,15629.51,15811.99,180.000,YES,,,
R1054,"Q_RES_0201LF-0,5%,1/20W,CHIP,CS00001JE10",0,5%,R0201,15722.46,15877.38,90.000,NO,,,
R1055,"Q_RES_0201LF-1K,1%,1/20W,CHIP,CS21001FE07",1K,1%,R0201,16938.50,15786.92,270.000,NO,,,
R1056,"Q_RES_0201LF-1K,1%,1/20W,EMPTY,CS21001FE07",1K,1%,R0201,16930.25,15705.20,180.000,NO,,,
R1057,"Q_RES_0201LF-1K,1%,1/20W,EMPTY,CS21001FE07",1K,1%,R0201,16906.50,15786.92,270.000,NO,,,
R1058,"Q_RES_0201LF-20K,1%,1/20W,CHIP,CS32001FE00",20K,1%,R0201,16930.25,15737.20,180.000,NO,,,
R1059,"Q_RES_0201LF-1K,1%,1/20W,EMPTY,CS21001FE07",1K,1%,R0201,16810.22,15413.35,180.000,NO,,,
R1060,"Q_RES_0201LF-1K,1%,1/20W,CHIP,CS21001FE07",1K,1%,R0201,16810.22,15381.35,0.000,NO,,,
R1061,"Q_RES_0201LF-10K,1%,1/20W,CHIP,CS31001FE17",10K,1%,R0201,16684.89,15856.00,270.000,NO,,,
R1062,"Q_RES_0201LF-10K,1%,1/20W,CHIP,CS31001FE17",10K,1%,R0201,15760.46,15848.38,270.000,NO,,,
R1063,"Q_RES_0201LF-4.7K,5%,1/20W,EMPTY,CS24701JE04",4.7K,5%,R0201,15654.47,15438.00,180.000,YES,,,
R1064,"Q_RES_0201LF-200,1%,1/20W,CHIP,CS12001FE12",200,1%,R0201,15704.47,15438.00,180.000,YES,,,
R1065,"Q_RES_0201LF-4.7K,5%,1/20W,EMPTY,CS24701JE04",4.7K,5%,R0201,15760.46,15898.38,270.000,NO,,,
R1066,"Q_RES_0201LF-4.7K,5%,1/20W,EMPTY,CS24701JE04",4.7K,5%,R0201,15835.23,15939.89,270.000,NO,,,
R1067,"Q_RES_0201LF-0,5%,1/20W,CHIP,CS00001JE10",0,5%,R0201,9205.00,13150.00,180.000,YES,,,
R1068,"Q_RES_0201LF-0,5%,1/20W,CHIP,CS00001JE10",0,5%,R0201,9205.00,13190.00,180.000,YES,,,
R1069,"Q_RES_0201LF-4.7K,5%,1/20W,EMPTY,CS24701JE04",4.7K,5%,R0201,15654.47,15506.40,0.000,NO,,,
R1070,"Q_RES_0201LF-10K,1%,1/20W,CHIP,CS31001FE17",10K,1%,R0201,15704.47,15510.40,0.000,NO,,,
R1071,"Q_RES_0402LF-4.7K,5%,1/16W,EMPTY,CS24702JB10",4.7K,5%,R0402,6445.00,4423.62,180.000,NO,,,
R1072,"Q_RES_0201LF-10K,1%,1/20W,CHIP,CS31001FE17",10K,1%,R0201,15704.47,15474.20,0.000,NO,,,
R1073,"Q_RES_0201LF-4.7K,5%,1/20W,EMPTY,CS24701JE04",4.7K,5%,R0201,15654.47,15510.40,180.000,YES,,,
R1074,"Q_RES_0201LF-4.7K,5%,1/20W,CHIP,CS24701JE04",4.7K,5%,R0201,15704.47,15510.40,180.000,YES,,,
R1075,"Q_RES_0201LF-4.7K,5%,1/20W,EMPTY,CS24701JE04",4.7K,5%,R0201,15654.47,15474.20,180.000,YES,,,
R1076,"Q_RES_0201LF-4.7K,5%,1/20W,CHIP,CS24701JE04",4.7K,5%,R0201,15704.47,15474.20,180.000,YES,,,
R1077,"Q_RES_0201LF-4.7K,5%,1/20W,EMPTY,CS24701JE04",4.7K,5%,R0201,15644.47,15438.00,0.000,NO,,,
R1078,"Q_RES_0201LF-4.7K,5%,1/20W,CHIP,CS24701JE04",4.7K,5%,R0201,15704.47,15438.00,0.000,NO,,,
R1079,"Q_RES_0201LF-4.7K,5%,1/20W,CHIP,CS24701JE04",4.7K,5%,R0201,15835.23,15889.89,270.000,NO,,,
R1080,"Q_RES_0201LF-4.7K,5%,1/20W,CHIP,CS24701JE04",4.7K,5%,R0201,15792.46,15898.38,270.000,NO,,,
R1081,"Q_RES_0201LF-1K,1%,1/20W,EMPTY,CS21001FE07",1K,1%,R0201,16621.29,15906.00,270.000,NO,,,
R1082,"Q_RES_0201LF-200,1%,1/20W,CHIP,CS12001FE12",200,1%,R0201,16621.29,15856.00,270.000,NO,,,
R1083,"Q_RES_0201LF-0,5%,1/20W,CHIP,CS00001JE10",0,5%,R0201,16723.77,15420.72,180.000,YES,,,
R1084,"Q_RES_0201LF-0,5%,1/20W,CHIP,CS00001JE10",0,5%,R0201,16716.89,15856.00,270.000,NO,,,
R1085,"Q_RES_0201LF-1K,1%,1/20W,CHIP,CS21001FE07",1K,1%,R0201,16571.39,17042.37,0.000,NO,,,
R1086,"Q_RES_0402LF-0,5%,1/16W,EMPTY,CS00002JB13",0,5%,R0402,15470.96,15452.20,180.000,NO,,,
R1087,"Q_RES_0402LF-0,5%,1/16W,EMPTY,CS00002JB13",0,5%,R0402,15470.96,15491.20,180.000,NO,,,
R1088,"Q_RES_0201LF-0,5%,1/20W,CHIP,CS00001JE10",0,5%,R0201,15404.27,15906.00,270.000,NO,,,
R1089,"Q_RES_0402LF-2.2K,5%,1/16W,CHIP,CS22202JB07",2.2K,5%,R0402,10919.38,4516.05,0.000,NO,,,
R1090,"Q_RES_0402LF-2.2K,5%,1/16W,CHIP,CS22202JB07",2.2K,5%,R0402,10919.38,4571.05,0.000,NO,,,
R1091,"Q_RES_0201LF-4.7K,5%,1/20W,EMPTY,CS24701JE04",4.7K,5%,R0201,14511.84,15848.38,270.000,NO,,,
R1092,"Q_RES_0402LF-10M,1%,1/16W,EMPTY,CS61002FB02",10M,1%,R0402,1761.00,4166.00,180.000,NO,,,
R1093,"Q_RES_0402LF-0,5%,1/16W,EMPTY,CS00002JB13",0,5%,R0402,15502.46,15452.20,180.000,NO,,,
R1094,"Q_RES_0603LF-0,5%,1/4W,EMPTY,CS00006J900",0,5%,R0603,14290.89,15811.99,180.000,YES,,,
R1095,"Q_RES_0603LF-0,5%,1/4W,CHIP,CS00006J900",0,5%,R0603,14348.89,15811.99,180.000,YES,,,
R1096,"Q_RES_0201LF-0,5%,1/20W,CHIP,CS00001JE10",0,5%,R0201,14441.84,15877.38,90.000,NO,,,
R1097,"Q_RES_0201LF-1K,1%,1/20W,CHIP,CS21001FE07",1K,1%,R0201,15550.47,15508.00,90.000,NO,,,
R1098,"Q_RES_0201LF-1K,1%,1/20W,EMPTY,CS21001FE07",1K,1%,R0201,15550.47,15558.00,90.000,NO,,,
R1099,"Q_RES_0201LF-1K,1%,1/20W,EMPTY,CS21001FE07",1K,1%,R0201,15582.47,15508.00,90.000,NO,,,
R1100,"Q_RES_0201LF-20K,1%,1/20W,CHIP,CS32001FE00",20K,1%,R0201,15582.47,15558.00,90.000,NO,,,
R1101,"Q_RES_0201LF-1K,1%,1/20W,EMPTY,CS21001FE07",1K,1%,R0201,15514.46,15396.00,180.000,NO,,,
R1102,"Q_RES_0201LF-1K,1%,1/20W,CHIP,CS21001FE07",1K,1%,R0201,15566.46,15380.00,0.000,NO,,,
R1103,"Q_RES_0201LF-10K,1%,1/20W,CHIP,CS31001FE17",10K,1%,R0201,15404.27,15856.00,270.000,NO,,,
R1104,"Q_RES_0201LF-10K,1%,1/20W,CHIP,CS31001FE17",10K,1%,R0201,14479.84,15848.38,270.000,NO,,,
R1105,"Q_RES_0201LF-4.7K,5%,1/20W,EMPTY,CS24701JE04",4.7K,5%,R0201,14373.85,15438.00,180.000,YES,,,
R1106,"Q_RES_0201LF-200,1%,1/20W,CHIP,CS12001FE12",200,1%,R0201,14423.85,15438.00,180.000,YES,,,
R1107,"Q_RES_0201LF-4.7K,5%,1/20W,EMPTY,CS24701JE04",4.7K,5%,R0201,14479.84,15898.38,270.000,NO,,,
R1108,"Q_RES_0201LF-4.7K,5%,1/20W,EMPTY,CS24701JE04",4.7K,5%,R0201,14554.61,15939.89,270.000,NO,,,
R1109,"Q_RES_0201LF-0,5%,1/20W,CHIP,CS00001JE10",0,5%,R0201,9180.00,13240.00,180.000,YES,,,
R1110,"Q_RES_0201LF-0,5%,1/20W,CHIP,CS00001JE10",0,5%,R0201,9180.00,13280.00,180.000,YES,,,
R1111,"Q_RES_0201LF-4.7K,5%,1/20W,EMPTY,CS24701JE04",4.7K,5%,R0201,14373.85,15506.40,0.000,NO,,,
R1112,"Q_RES_0201LF-10K,1%,1/20W,CHIP,CS31001FE17",10K,1%,R0201,14423.85,15510.40,0.000,NO,,,
R1113,"Q_RES_0201LF-10K,1%,1/20W,CHIP,CS31001FE17",10K,1%,R0201,14423.85,15474.20,0.000,NO,,,
R1114,"Q_RES_0201LF-4.7K,5%,1/20W,EMPTY,CS24701JE04",4.7K,5%,R0201,14373.85,15510.40,180.000,YES,,,
R1115,"Q_RES_0201LF-4.7K,5%,1/20W,CHIP,CS24701JE04",4.7K,5%,R0201,14423.85,15510.40,180.000,YES,,,
R1116,"Q_RES_0201LF-4.7K,5%,1/20W,EMPTY,CS24701JE04",4.7K,5%,R0201,14373.85,15474.20,180.000,YES,,,
R1117,"Q_RES_0402LF-6.19K,1%,1/16W,CHIP,CS26192FB03",6.19K,1%,R0402,7035.00,16045.00,180.000,NO,,,
R1118,"Q_RES_0201LF-4.7K,5%,1/20W,CHIP,CS24701JE04",4.7K,5%,R0201,14423.85,15474.20,180.000,YES,,,
R1119,"Q_RES_0201LF-4.7K,5%,1/20W,EMPTY,CS24701JE04",4.7K,5%,R0201,14363.85,15438.00,0.000,NO,,,
R1120,"Q_RES_0201LF-4.7K,5%,1/20W,CHIP,CS24701JE04",4.7K,5%,R0201,14423.85,15438.00,0.000,NO,,,
R1121,"Q_RES_0201LF-4.7K,5%,1/20W,CHIP,CS24701JE04",4.7K,5%,R0201,14554.61,15889.89,270.000,NO,,,
R1122,"Q_RES_0201LF-4.7K,5%,1/20W,CHIP,CS24701JE04",4.7K,5%,R0201,14511.84,15898.38,270.000,NO,,,
R1123,"Q_RES_0201LF-1K,1%,1/20W,EMPTY,CS21001FE07",1K,1%,R0201,15340.67,15906.00,270.000,NO,,,
R1124,"Q_RES_0201LF-200,1%,1/20W,CHIP,CS12001FE12",200,1%,R0201,15340.67,15856.00,270.000,NO,,,
R1125,"Q_RES_0201LF-0,5%,1/20W,CHIP,CS00001JE10",0,5%,R0201,15478.47,15404.00,180.000,YES,,,
R1126,"Q_RES_0201LF-0,5%,1/20W,CHIP,CS00001JE10",0,5%,R0201,15436.27,15863.00,270.000,NO,,,
R1127,"Q_RES_0201LF-1K,1%,1/20W,CHIP,CS21001FE07",1K,1%,R0201,14816.30,16689.17,180.000,NO,,,
R1128,"Q_RES_0402LF-1K,1%,1/16W,CHIP,CS21002FB06",1K,1%,R0402,6195.00,4405.00,90.000,NO,,,
R1129,"Q_RES_0402LF-0,5%,1/16W,CHIP,CS00002JB13",0,5%,R0402,7814.56,3796.17,90.000,NO,,,
R1130,"Q_RES_0402LF-0,5%,1/16W,EMPTY,CS00002JB13",0,5%,R0402,6168.91,4269.01,180.000,NO,,,
R1131,"Q_RES_0402LF-1K,1%,1/16W,CHIP,CS21002FB06",1K,1%,R0402,6170.00,4180.00,180.000,NO,,,
R1132,"Q_RES_0402LF-0,5%,1/16W,CHIP,CS00002JB13",0,5%,R0402,8070.66,3767.53,0.000,NO,,,
R1133,"Q_RES_0402LF-1K,1%,1/16W,CHIP,CS21002FB06",1K,1%,R0402,8070.66,3810.20,0.000,NO,,,
R1134,"Q_RES_0402LF-0,5%,1/16W,CHIP,CS00002JB13",0,5%,R0402,5937.58,4202.05,270.000,NO,,,
R1135,"Q_RES_0402LF-0,5%,1/16W,EMPTY,CS00002JB13",0,5%,R0402,16239.42,2827.28,0.000,NO,,,
R1136,"Q_RES_0402LF-0,5%,1/16W,EMPTY,CS00002JB13",0,5%,R0402,17841.33,1643.99,90.000,NO,,,
R1137,"Q_RES_0402LF-0,5%,1/16W,EMPTY,CS00002JB13",0,5%,R0402,16575.45,4300.44,270.000,NO,,,
R1138,"Q_RES_0402LF-10K,1%,1/16W,CHIP,CS31002FB08",10K,1%,R0402,8449.36,917.51,90.000,NO,,,
R1139,"Q_RES_0402LF-0,5%,1/16W,CHIP,CS00002JB13",0,5%,R0402,8500.16,917.51,270.000,NO,,,
R1140,"Q_RES_0402LF-27.4,1%,1/16W,CHIP,CS02742FB03",27.4,1%,R0402,8388.26,904.51,180.000,NO,,,
R1141,"Q_RES_0402LF-27.4,1%,1/16W,CHIP,CS02742FB03",27.4,1%,R0402,8315.40,643.43,270.000,NO,,,
R1142,"Q_RES_0402LF-0,5%,1/16W,CHIP,CS00002JB13",0,5%,R0402,6662.23,3632.61,180.000,NO,,,
R1143,"Q_RES_0402LF-0,5%,1/16W,CHIP,CS00002JB13",0,5%,R0402,6610.00,3900.00,180.000,NO,,,
R1144,"Q_RES_0402LF-1K,1%,1/16W,CHIP,CS21002FB06",1K,1%,R0402,6540.00,3900.00,0.000,NO,,,
R1145,"Q_RES_0402LF-10K,5%,1/16W,EMPTY,CS31002JB08",10K,5%,R0402,8500.00,3810.00,180.000,NO,,,
R1146,"Q_RES_0402LF-0,5%,1/16W,EMPTY,CS00002JB13",0,5%,R0402,2785.00,2150.00,180.000,NO,,,
R1147,"Q_RES_0402LF-0,5%,1/16W,EMPTY,CS00002JB13",0,5%,R0402,2715.00,2110.00,180.000,NO,,,
R1148,"Q_RES_0402LF-0,5%,1/16W,CHIP,CS00002JB13",0,5%,R0402,18172.99,4274.32,0.000,NO,,,
R1149,"Q_RES_0402LF-1K,1%,1/16W,CHIP,CS21002FB06",1K,1%,R0402,1955.00,1490.00,0.000,NO,,,
R1150,"Q_RES_0402LF-10K,1%,1/16W,CHIP,CS31002FB08",10K,1%,R0402,18242.99,4274.32,180.000,NO,,,
R1151,"Q_RES_0402LF-0,5%,1/16W,EMPTY,CS00002JB13",0,5%,R0402,9380.00,8570.00,90.000,YES,,,
R1152,"Q_RES_0402LF-0,5%,1/16W,EMPTY,CS00002JB13",0,5%,R0402,9430.00,8570.00,90.000,YES,,,
R1153,"Q_RES_0402LF-0,5%,1/16W,CHIP,CS00002JB13",0,5%,R0402,9565.00,8980.00,270.000,YES,,,
R1154,"Q_RES_0402LF-0,5%,1/16W,CHIP,CS00002JB13",0,5%,R0402,9615.00,8980.00,270.000,YES,,,
R1155,"Q_RES_0402LF-33,5%,1/16W,EMPTY,CS03302JB10",33,5%,R0402,9355.00,9775.00,0.000,YES,,,
R1156,"Q_RES_0402LF-33,5%,1/16W,EMPTY,CS03302JB10",33,5%,R0402,9355.00,9825.00,0.000,YES,,,
R1157,"Q_RES_0402LF-33,5%,1/16W,EMPTY,CS03302JB10",33,5%,R0402,9285.00,9465.00,270.000,YES,,,
R1158,"Q_RES_0402LF-33,5%,1/16W,EMPTY,CS03302JB10",33,5%,R0402,9235.00,9465.00,270.000,YES,,,
R1159,"Q_RES_0402LF-0,5%,1/16W,CHIP,CS00002JB13",0,5%,R0402,9545.00,9215.00,90.000,YES,,,
R1160,"Q_RES_0402LF-0,5%,1/16W,CHIP,CS00002JB13",0,5%,R0402,9465.00,9215.00,90.000,YES,,,
R1161,"Q_RES_0402LF-0,5%,1/16W,CHIP,CS00002JB13",0,5%,R0402,9385.00,9215.00,90.000,YES,,,
R1162,"Q_RES_0402LF-0,5%,1/16W,CHIP,CS00002JB13",0,5%,R0402,9255.00,9215.00,90.000,YES,,,
R1163,"Q_RES_0402LF-0,5%,1/16W,CHIP,CS00002JB13",0,5%,R0402,3595.00,3075.00,0.000,NO,,,
R1164,"Q_RES_0402LF-0,5%,1/16W,EMPTY,CS00002JB13",0,5%,R0402,1971.36,1653.25,180.000,NO,,,
R1165,"Q_RES_0402LF-1K,1%,1/16W,CHIP,CS21002FB06",1K,1%,R0402,1960.00,1565.00,0.000,NO,,,
R1166,"Q_RES_0402LF-0,5%,1/16W,CHIP,CS00002JB13",0,5%,R0402,3955.00,3040.00,0.000,NO,,,
R1167,"Q_RES_0402LF-1K,1%,1/16W,CHIP,CS21002FB06",1K,1%,R0402,4030.00,3040.00,180.000,NO,,,
R1168,"Q_RES_0402LF-0,5%,1/16W,CHIP,CS00002JB13",0,5%,R0402,2238.52,1487.50,0.000,NO,,,
R1169,"Q_RES_0402LF-0,5%,1/16W,CHIP,CS00002JB13",0,5%,R0402,3146.02,2725.91,90.000,NO,,,
R1170,"Q_RES_0402LF-0,5%,1/16W,CHIP,CS00002JB13",0,5%,R0402,3461.53,2718.86,90.000,NO,,,
R1171,"Q_RES_0402LF-1K,1%,1/16W,CHIP,CS21002FB06",1K,1%,R0402,3420.00,2790.00,270.000,NO,,,
R1172,"Q_RES_0402LF-10K,5%,1/16W,EMPTY,CS31002JB08",10K,5%,R0402,2785.00,2070.00,0.000,NO,,,
R1173,"Q_RES_0402LF-33.2,1%,1/16W,CHIP,CS03322FB03",33.2,1%,R0402,2889.49,2479.11,270.000,NO,,,
R1174,"Q_RES_0402LF-33.2,1%,1/16W,CHIP,CS03322FB03",33.2,1%,R0402,2929.49,2479.11,270.000,NO,,,
R1175,"Q_RES_0402LF-33.2,1%,1/16W,CHIP,CS03322FB03",33.2,1%,R0402,2785.00,2110.00,0.000,NO,,,
R1176,"Q_RES_0402LF-10K,1%,1/16W,CHIP,CS31002FB08",10K,1%,R0402,2635.00,2215.00,0.000,NO,,,
R1177,"Q_RES_0402LF-33.2,1%,1/16W,CHIP,CS03322FB03",33.2,1%,R0402,2885.97,2170.19,270.000,NO,,,
R1178,"Q_RES_0402LF-33.2,1%,1/16W,CHIP,CS03322FB03",33.2,1%,R0402,2715.00,2150.00,0.000,NO,,,
R1179,"Q_RES_0402LF-0,5%,1/16W,CHIP,CS00002JB13",0,5%,R0402,2635.00,2175.00,180.000,NO,,,
R1180,"Q_RES_0402LF-0,5%,1/16W,EMPTY,CS00002JB13",0,5%,R0402,6017.67,1364.08,0.000,NO,,,
R1181,"Q_RES_0402LF-0,5%,1/16W,CHIP,CS00002JB13",0,5%,R0402,2686.03,1373.02,180.000,NO,,,
R1182,"Q_RES_0402LF-0,5%,1/16W,EMPTY,CS00002JB13",0,5%,R0402,2295.16,1535.59,90.000,NO,,,
R1183,"Q_RES_0402LF-1K,1%,1/16W,CHIP,CS21002FB06",1K,1%,R0402,595.03,7573.32,90.000,YES,,,
R1184,"Q_RES_0402LF-1K,1%,1/16W,CHIP,CS21002FB06",1K,1%,R0402,6469.90,7512.66,180.000,YES,,,
R1185,"Q_RES_0402LF-1K,1%,1/16W,CHIP,CS21002FB06",1K,1%,R0402,7776.52,4153.44,180.000,NO,,,
R1186,"Q_RES_0402LF-1K,1%,1/16W,CHIP,CS21002FB06",1K,1%,R0402,7275.00,3948.62,90.000,YES,,,
R1187,"Q_RES_0402LF-1K,1%,1/16W,CHIP,CS21002FB06",1K,1%,R0402,7314.06,3783.31,270.000,NO,,,
R1188,"Q_RES_0402LF-1K,1%,1/16W,CHIP,CS21002FB06",1K,1%,R0402,7275.00,3948.62,270.000,NO,,,
R1189,"Q_RES_0402LF-1K,1%,1/16W,CHIP,CS21002FB06",1K,1%,R0402,7301.52,4388.44,270.000,YES,,,
R1190,"Q_RES_0402LF-1K,1%,1/16W,CHIP,CS21002FB06",1K,1%,R0402,7315.00,3948.62,270.000,NO,,,
R1191,"Q_RES_0402LF-0,5%,1/16W,CHIP,CS00002JB13",0,5%,R0402,612.25,2682.23,0.000,NO,,,
R1192,"Q_RES_0402LF-1K,1%,1/16W,CHIP,CS21002FB06",1K,1%,R0402,682.25,2682.23,180.000,NO,,,
R1193,"Q_RES_0402LF-0,5%,1/16W,CHIP,CS00002JB13",0,5%,R0402,2797.83,1255.68,270.000,NO,,,
R1194,"Q_RES_0402LF-200,1%,1/16W,CHIP,CS12002FB06",200,1%,R0402,12962.00,629.11,270.000,NO,,,
R1195,"Q_RES_0402LF-4.7K,5%,1/16W,EMPTY,CS24702JB10",4.7K,5%,R0402,6445.00,4338.62,180.000,NO,,,
R1196,"Q_RES_0402LF-0,5%,1/16W,EMPTY,CS00002JB13",0,5%,R0402,2487.97,1117.43,0.000,YES,,,
R1197,"Q_RES_0402LF-0,5%,1/16W,EMPTY,CS00002JB13",0,5%,R0402,7405.56,5731.71,180.000,YES,,,
R1198,"Q_RES_0201LF-0,5%,1/20W,CHIP,CS00001JE10",0,5%,R0201,6708.30,16734.39,270.000,YES,,,
R1199,"Q_RES_0201LF-0,5%,1/20W,CHIP,CS00001JE10",0,5%,R0201,4466.17,15798.43,0.000,NO,,,
R1200,"Q_RES_0201LF-0,5%,1/20W,CHIP,CS00001JE10",0,5%,R0201,6433.98,16428.96,0.000,YES,,,
R1201,"Q_RES_0201LF-0,5%,1/20W,CHIP,CS00001JE10",0,5%,R0201,3950.09,15862.89,270.000,NO,,,
R1202,"Q_RES_0402LF-0,5%,1/16W,CHIP,CS00002JB13",0,5%,R0402,7645.00,5093.62,90.000,NO,,,
R1203,"Q_RES_0402LF-33,5%,1/16W,CHIP,CS03302JB10",33,5%,R0402,7365.00,5093.62,90.000,NO,,,
R1204,"Q_RES_0402LF-0,5%,1/16W,CHIP,CS00002JB13",0,5%,R0402,14493.34,12734.92,90.000,NO,,,
R1205,"Q_RES_0402LF-0,5%,1/16W,CHIP,CS00002JB13",0,5%,R0402,14533.34,12734.92,90.000,NO,,,
R1206,"Q_RES_0201LF-0,5%,1/20W,CHIP,CS00001JE10",0,5%,R0201,14835.00,16785.00,180.000,NO,,,
R1207,"Q_RES_0402LF-470,1%,1/16W,CHIP,CS14702FB04",470,1%,R0402,13557.50,629.11,90.000,NO,,,
R1208,"Q_RES_0402LF-470,1%,1/16W,CHIP,CS14702FB04",470,1%,R0402,13679.50,629.11,90.000,NO,,,
R1209,"Q_RES_0201LF-0,5%,1/20W,CHIP,CS00001JE10",0,5%,R0201,16496.02,16877.28,180.000,YES,,,
R1210,"Q_RES_0201LF-0,5%,1/20W,CHIP,CS00001JE10",0,5%,R0201,11383.31,15663.45,270.000,NO,,,
R1211,"Q_RES_0201LF-0,5%,1/20W,CHIP,CS00001JE10",0,5%,R0201,11630.00,16820.00,180.000,YES,,,
R1212,"Q_RES_0201LF-1K,1%,1/20W,CHIP,CS21001FE07",1K,1%,R0201,6554.06,16725.26,270.000,YES,,,
R1213,"Q_RES_0201LF-1K,1%,1/20W,CHIP,CS21001FE07",1K,1%,R0201,4462.18,15894.67,270.000,NO,,,
R1214,"Q_RES_0201LF-1K,1%,1/20W,CHIP,CS21001FE07",1K,1%,R0201,6375.60,16506.39,0.000,YES,,,
R1215,"Q_RES_0201LF-1K,1%,1/20W,CHIP,CS21001FE07",1K,1%,R0201,3847.23,15764.48,0.000,NO,,,
R1216,"Q_RES_0201LF-1K,1%,1/20W,CHIP,CS21001FE07",1K,1%,R0201,14655.00,16695.00,90.000,NO,,,
R1217,"Q_RES_0201LF-1K,1%,1/20W,CHIP,CS21001FE07",1K,1%,R0201,16499.59,16764.70,180.000,YES,,,
R1218,"Q_RES_0201LF-1K,1%,1/20W,CHIP,CS21001FE07",1K,1%,R0201,11521.86,15664.74,270.000,NO,,,
R1219,"Q_RES_0201LF-1K,1%,1/20W,CHIP,CS21001FE07",1K,1%,R0201,11630.59,16697.59,180.000,YES,,,
R1220,"Q_RES_0402LF-18K,1%,1/16W,CHIP,CS31802FB04",18K,1%,R0402,9245.82,12787.13,180.000,YES,,,
R1221,"Q_RES_0402LF-18K,1%,1/16W,CHIP,CS31802FB04",18K,1%,R0402,9244.55,12745.91,180.000,YES,,,
R1222,"Q_RES_0402LF-18K,1%,1/16W,CHIP,CS31802FB04",18K,1%,R0402,9245.09,12916.76,180.000,YES,,,
R1223,"Q_RES_0402LF-18K,1%,1/16W,CHIP,CS31802FB04",18K,1%,R0402,9244.30,12830.48,180.000,YES,,,
R1224,"Q_RES_0402LF-4.7K,1%,1/16W,CHIP,CS24702FB06",4.7K,1%,R0402,9245.31,12871.93,180.000,YES,,,
R1225,"Q_RES_0402LF-18K,1%,1/16W,CHIP,CS31802FB04",18K,1%,R0402,9245.86,12959.57,180.000,YES,,,
R1226,"Q_RES_0402LF-9.09K,1%,1/16W,CHIP,CS29092FB05",9.09K,1%,R0402,9243.54,12663.47,180.000,YES,,,
R1227,"Q_RES_0402LF-0,5%,1/16W,EMPTY,CS00002JB13",0,5%,R0402,9595.00,12870.00,180.000,YES,,,
R1228,"Q_RES_0402LF-0,5%,1/16W,EMPTY,CS00002JB13",0,5%,R0402,9595.00,12830.00,180.000,YES,,,
R1229,"Q_RES_0402LF-18K,1%,1/16W,CHIP,CS31802FB04",18K,1%,R0402,9245.04,12704.08,180.000,YES,,,
R1230,"Q_RES_0402LF-2K,1%,1/16W,CHIP,CS22002FB07",2K,1%,R0402,10095.77,12942.68,0.000,YES,,,
R1231,"Q_RES_0402LF-5.11K,1%,1/16W,CHIP,CS25112FB04",5.11K,1%,R0402,9366.83,12780.59,0.000,YES,,,
R1232,"Q_RES_0402LF-5.11K,1%,1/16W,CHIP,CS25112FB04",5.11K,1%,R0402,9367.07,12739.58,0.000,YES,,,
R1233,"Q_RES_0402LF-5.11K,1%,1/16W,CHIP,CS25112FB04",5.11K,1%,R0402,9366.20,12901.52,0.000,YES,,,
R1234,"Q_RES_0402LF-5.11K,1%,1/16W,CHIP,CS25112FB04",5.11K,1%,R0402,9366.36,12821.15,0.000,YES,,,
R1235,"Q_RES_0402LF-5.11K,1%,1/16W,CHIP,CS25112FB04",5.11K,1%,R0402,9366.56,12861.56,0.000,YES,,,
R1236,"Q_RES_0402LF-5.11K,1%,1/16W,CHIP,CS25112FB04",5.11K,1%,R0402,9365.40,12941.91,0.000,YES,,,
R1237,"Q_RES_0402LF-5.11K,1%,1/16W,CHIP,CS25112FB04",5.11K,1%,R0402,9366.01,12697.29,0.000,YES,,,
R1238,"Q_RES_0402LF-18K,1%,1/16W,CHIP,CS31802FB04",18K,1%,R0402,9366.36,12656.36,0.000,YES,,,
R1239,"Q_RES_0402LF-1K,1%,1/16W,EMPTY,CS21002FB06",1K,1%,R0402,8509.20,12959.81,180.000,YES,,,
R1240,"Q_RES_0402LF-1K,1%,1/16W,CHIP,CS21002FB06",1K,1%,R0402,8410.09,12960.68,0.000,YES,,,
R1241,"Q_RES_0402LF-1K,1%,1/16W,EMPTY,CS21002FB06",1K,1%,R0402,8509.56,12914.68,180.000,YES,,,
R1242,"Q_RES_0402LF-1K,1%,1/16W,CHIP,CS21002FB06",1K,1%,R0402,8410.13,12917.72,0.000,YES,,,
R1243,"Q_RES_0402LF-0,5%,1/16W,CHIP,CS00002JB13",0,5%,R0402,8508.81,12739.71,180.000,YES,,,
R1244,"Q_RES_0402LF-0,5%,1/16W,CHIP,CS00002JB13",0,5%,R0402,8507.95,12781.39,180.000,YES,,,
R1245,"Q_RES_0402LF-0,5%,1/16W,EMPTY,CS00002JB13",0,5%,R0402,9128.93,12752.51,180.000,YES,,,
R1246,"Q_RES_0402LF-0,5%,1/16W,EMPTY,CS00002JB13",0,5%,R0402,9129.24,12794.51,180.000,YES,,,
R1247,"Q_RES_0402LF-0,5%,1/16W,EMPTY,CS00002JB13",0,5%,R0402,9127.33,12923.30,180.000,YES,,,
R1248,"Q_RES_0402LF-0,5%,1/16W,EMPTY,CS00002JB13",0,5%,R0402,9128.00,12882.35,180.000,YES,,,
R1249,"Q_RES_0402LF-0,5%,1/16W,EMPTY,CS00002JB13",0,5%,R0402,9127.13,12967.13,180.000,YES,,,
R1250,"Q_RES_0402LF-0,5%,1/16W,EMPTY,CS00002JB13",0,5%,R0402,9128.84,12837.75,180.000,YES,,,
R1251,"Q_RES_0402LF-0,5%,1/16W,CHIP,CS00002JB13",0,5%,R0402,9097.43,12752.51,0.000,YES,,,
R1252,"Q_RES_0402LF-0,5%,1/16W,CHIP,CS00002JB13",0,5%,R0402,9097.74,12794.51,0.000,YES,,,
R1253,"Q_RES_0402LF-33,5%,1/16W,CHIP,CS03302JB10",33,5%,R0402,14336.82,1176.64,180.000,NO,,,
R1254,"Q_RES_0402LF-0,5%,1/16W,CHIP,CS00002JB13",0,5%,R0402,9095.83,12923.30,0.000,YES,,,
R1255,"Q_RES_0402LF-0,5%,1/16W,CHIP,CS00002JB13",0,5%,R0402,9096.50,12882.35,0.000,YES,,,
R1256,"Q_RES_0402LF-0,5%,1/16W,CHIP,CS00002JB13",0,5%,R0402,9095.63,12967.13,0.000,YES,,,
R1257,"Q_RES_0402LF-0,5%,1/16W,CHIP,CS00002JB13",0,5%,R0402,9097.34,12837.75,0.000,YES,,,
R1258,"Q_RES_0402LF-0,5%,1/16W,EMPTY,CS00002JB13",0,5%,R0402,9131.62,12710.25,180.000,YES,,,
R1259,"Q_RES_0402LF-0,5%,1/16W,CHIP,CS00002JB13",0,5%,R0402,9100.12,12710.25,0.000,YES,,,
R1260,"Q_RES_0402LF-0,5%,1/16W,EMPTY,CS00002JB13",0,5%,R0402,9130.48,12668.33,180.000,YES,,,
R1261,"Q_RES_0402LF-10K,5%,1/16W,CHIP,CS31002JB08",10K,5%,R0402,16889.25,1667.62,180.000,YES,,,
R1262,"Q_RES_0402LF-10K,5%,1/16W,CHIP,CS31002JB08",10K,5%,R0402,16889.25,1577.62,180.000,YES,,,
R1263,"Q_RES_0402LF-0,5%,1/16W,CHIP,CS00002JB13",0,5%,R0402,9098.98,12668.33,0.000,YES,,,
R1264,"Q_RES_0402LF-1K,1%,1/16W,EMPTY,CS21002FB06",1K,1%,R0402,16889.25,1417.62,180.000,YES,,,
R1265,"Q_RES_0402LF-10K,5%,1/16W,CHIP,CS31002JB08",10K,5%,R0402,16889.25,1537.62,0.000,YES,,,
R1266,"Q_RES_0402LF-200,1%,1/16W,CHIP,CS12002FB06",200,1%,R0402,13081.10,629.11,270.000,NO,,,
R1267,"Q_RES_0402LF-4.7K,1%,1/16W,EMPTY,CS24702FB06",4.7K,1%,R0402,8508.94,12874.38,0.000,YES,,,
R1268,"Q_RES_0402LF-4.7K,1%,1/16W,EMPTY,CS24702FB06",4.7K,1%,R0402,8507.50,12697.85,0.000,YES,,,
R1269,"Q_RES_0402LF-0,5%,1/16W,CHIP,CS00002JB13",0,5%,R0402,12642.02,3991.25,180.000,NO,,,
R1270,"Q_RES_0402LF-0,5%,1/16W,CHIP,CS00002JB13",0,5%,R0402,15405.17,2928.16,180.000,NO,,,
R1271,"Q_RES_0402LF-0,5%,1/16W,CHIP,CS00002JB13",0,5%,R0402,757.54,1491.91,180.000,NO,,,
R1272,"Q_RES_0402LF-0,5%,1/16W,CHIP,CS00002JB13",0,5%,R0402,12789.49,3908.84,180.000,NO,,,
R1273,"Q_RES_0402LF-0,5%,1/16W,CHIP,CS00002JB13",0,5%,R0402,15552.64,2845.75,180.000,NO,,,
R1274,"Q_RES_0402LF-0,5%,1/16W,CHIP,CS00002JB13",0,5%,R0402,905.01,1409.50,180.000,NO,,,
R1275,"Q_RES_0402LF-0,5%,1/16W,CHIP,CS00002JB13",0,5%,R0402,12720.49,3908.84,0.000,NO,,,
R1276,"Q_RES_0402LF-0,5%,1/16W,CHIP,CS00002JB13",0,5%,R0402,15483.64,2845.75,0.000,NO,,,
R1277,"Q_RES_0402LF-0,5%,1/16W,CHIP,CS00002JB13",0,5%,R0402,836.01,1409.50,0.000,NO,,,
R1278,"Q_RES_0402LF-33,5%,1/16W,CHIP,CS03302JB10",33,5%,R0402,7206.52,4993.44,90.000,YES,,,
R1279,"Q_RES_0402LF-33,5%,1/16W,CHIP,CS03302JB10",33,5%,R0402,7195.18,5258.31,270.000,NO,,,
R1280,"Q_RES_0402LF-33,5%,1/16W,CHIP,CS03302JB10",33,5%,R0402,7245.00,5418.62,270.000,NO,,,
R1281,"Q_RES_0402LF-33,5%,1/16W,CHIP,CS03302JB10",33,5%,R0402,7246.52,4993.44,90.000,YES,,,
R1282,"Q_RES_0402LF-33,5%,1/16W,CHIP,CS03302JB10",33,5%,R0402,7756.02,4465.64,0.000,YES,,,
R1283,"Q_RES_0402LF-10,1%,1/16W,CHIP,CS01002FB07",10,1%,R0402,9666.25,1981.71,180.000,NO,,,
R1284,"Q_RES_0402LF-10,1%,1/16W,CHIP,CS01002FB07",10,1%,R0402,17453.09,853.39,180.000,NO,,,
R1285,"Q_RES_0402LF-4.7K,5%,1/16W,CHIP,CS24702JB10",4.7K,5%,R0402,7148.45,5269.24,270.000,YES,,,
R1286,"Q_RES_0402LF-4.7K,5%,1/16W,CHIP,CS24702JB10",4.7K,5%,R0402,7205.00,5418.62,90.000,NO,,,
R1287,"Q_RES_0402LF-4.7K,5%,1/16W,CHIP,CS24702JB10",4.7K,5%,R0402,7205.00,5518.62,90.000,NO,,,
R1288,"Q_RES_0402LF-4.7K,5%,1/16W,CHIP,CS24702JB10",4.7K,5%,R0402,7219.09,5267.52,270.000,YES,,,
R1289,"Q_RES_0402LF-100K,1%,1/16W,CHIP,CS41002FB09",100K,1%,R0402,18246.56,3880.51,180.000,NO,,,
R1290,"Q_RES_0402LF-22,1%,1/16W,EMPTY,CS02202FB02",22,1%,R0402,7530.36,3112.45,270.000,YES,,,
R1291,"Q_RES_0402LF-10,1%,1/16W,CHIP,CS01002FB07",10,1%,R0402,2804.56,745.36,180.000,NO,,,
R1292,"Q_RES_0402LF-10,1%,1/16W,CHIP,CS01002FB07",10,1%,R0402,9596.25,1981.71,0.000,NO,,,
R1293,"Q_RES_0402LF-0,5%,1/16W,CHIP,CS00002JB13",0,5%,R0402,1364.77,6712.90,0.000,NO,,,
R1294,"Q_RES_0402LF-0,5%,1/16W,CHIP,CS00002JB13",0,5%,R0402,1364.77,6832.90,0.000,NO,,,
R1295,"Q_RES_0402LF-0,5%,1/16W,CHIP,CS00002JB13",0,5%,R0402,7141.29,6626.67,270.000,NO,,,
R1296,"Q_RES_0402LF-0,5%,1/16W,CHIP,CS00002JB13",0,5%,R0402,7262.01,6626.69,270.000,NO,,,
R1297,"Q_RES_0402LF-0,5%,1/16W,CHIP,CS00002JB13",0,5%,R0402,11673.82,5756.02,180.000,NO,,,
R1298,"Q_RES_0402LF-0,5%,1/16W,CHIP,CS00002JB13",0,5%,R0402,11674.25,5926.73,180.000,NO,,,
R1299,"Q_RES_0402LF-0,5%,1/16W,CHIP,CS00002JB13",0,5%,R0402,17130.00,6565.00,90.000,NO,,,
R1300,"Q_RES_0402LF-0,5%,1/16W,CHIP,CS00002JB13",0,5%,R0402,17130.00,6720.00,270.000,NO,,,
R1301,"Q_RES_0402LF-10,1%,1/16W,CHIP,CS01002FB07",10,1%,R0402,17383.09,853.39,0.000,NO,,,
R1302,"Q_RES_0402LF-10,1%,1/16W,CHIP,CS01002FB07",10,1%,R0402,2734.56,745.36,0.000,NO,,,
R1303,"Q_RES_0402LF-1K,1%,1/16W,CHIP,CS21002FB06",1K,1%,R0402,7435.00,3783.62,270.000,NO,,,
R1304,"Q_RES_0402LF-10K,1%,1/16W,CHIP,CS31002FB08",10K,1%,R0402,7635.00,3948.62,90.000,YES,,,
R1305,"Q_RES_0402LF-4.7K,1%,1/16W,EMPTY,CS24702FB06",4.7K,1%,R0402,12642.02,4111.25,0.000,NO,,,
R1306,"Q_RES_0402LF-4.7K,1%,1/16W,EMPTY,CS24702FB06",4.7K,1%,R0402,15405.17,3048.16,0.000,NO,,,
R1307,"Q_RES_0402LF-4.7K,1%,1/16W,EMPTY,CS24702FB06",4.7K,1%,R0402,757.54,1611.91,0.000,NO,,,
R1308,"Q_RES_0402LF-4.7K,1%,1/16W,CHIP,CS24702FB06",4.7K,1%,R0402,12642.02,4071.25,0.000,NO,,,
R1309,"Q_RES_0402LF-4.7K,1%,1/16W,EMPTY,CS24702FB06",4.7K,1%,R0402,15405.17,3008.16,0.000,NO,,,
R1310,"Q_RES_0402LF-4.7K,1%,1/16W,EMPTY,CS24702FB06",4.7K,1%,R0402,757.54,1571.91,0.000,NO,,,
R1311,"Q_RES_0402LF-33,5%,1/16W,CHIP,CS03302JB10",33,5%,R0402,6315.05,2883.55,270.000,NO,,,
R1312,"Q_RES_0402LF-0,5%,1/16W,CHIP,CS00002JB13",0,5%,R0402,10672.94,4670.00,0.000,NO,,,
R1313,"Q_RES_0402LF-4.7K,5%,1/16W,CHIP,CS24702JB10",4.7K,5%,R0402,1200.16,3166.31,90.000,NO,,,
R1314,"Q_RES_0402LF-4.7K,5%,1/16W,EMPTY,CS24702JB10",4.7K,5%,R0402,7911.52,4473.44,180.000,NO,,,
R1315,"Q_RES_0402LF-0,5%,1/16W,CHIP,CS00002JB13",0,5%,R0402,10672.94,4715.00,0.000,NO,,,
R1316,"Q_RES_0402LF-2.2K,5%,1/16W,CHIP,CS22202JB07",2.2K,5%,R0402,10762.94,4715.00,180.000,NO,,,
R1317,"Q_RES_0402LF-4.7K,1%,1/16W,EMPTY,CS24702FB06",4.7K,1%,R0402,12642.02,4151.25,0.000,NO,,,
R1318,"Q_RES_0402LF-4.7K,5%,1/16W,CHIP,CS24702JB10",4.7K,5%,R0402,1200.16,2961.97,90.000,NO,,,
R1319,"Q_RES_0402LF-2K,1%,1/16W,EMPTY,CS22002FB07",2K,1%,R0402,7146.66,931.33,270.000,YES,,,
R1320,"Q_RES_0402LF-4.7K,1%,1/16W,CHIP,CS24702FB06",4.7K,1%,R0402,15405.17,3088.16,0.000,NO,,,
R1321,"Q_RES_0402LF-33,5%,1/16W,CHIP,CS03302JB10",33,5%,R0402,885.00,14445.00,0.000,NO,,,
R1322,"Q_RES_0402LF-4.7K,1%,1/16W,CHIP,CS24702FB06",4.7K,1%,R0402,757.54,1651.91,0.000,NO,,,
R1323,"Q_RES_2512LF-0.002,1%,2W,CHIP,CS+002AFR06",0.002,1%,R2512XS,9629.45,1878.71,0.000,NO,,,
R1324,"Q_RES_2512LF-0.002,1%,2W,CHIP,CS+002AFR06",0.002,1%,R2512XS,17396.19,750.39,0.000,NO,,,
R1325,"Q_RES_2512LF-0.002,1%,2W,CHIP,CS+002AFR06",0.002,1%,R2512XS,2796.66,642.36,0.000,NO,,,
R1326,"Q_RES_0402LF-1K,1%,1/16W,EMPTY,CS21002FB06",1K,1%,R0402,12641.99,3951.25,180.000,NO,,,
R1327,"Q_RES_0402LF-1K,1%,1/16W,EMPTY,CS21002FB06",1K,1%,R0402,15405.14,2888.16,180.000,NO,,,
R1328,"Q_RES_0402LF-1K,1%,1/16W,EMPTY,CS21002FB06",1K,1%,R0402,757.51,1451.91,180.000,NO,,,
R1329,"Q_RES_0402LF-0,5%,1/16W,CHIP,CS00002JB13",0,5%,R0402,6995.00,3948.62,270.000,YES,,,
R1330,"Q_RES_0402LF-0,5%,1/16W,EMPTY,CS00002JB13",0,5%,R0402,11705.32,5756.02,180.000,NO,,,
R1331,"Q_RES_0402LF-0,5%,1/16W,EMPTY,CS00002JB13",0,5%,R0402,11705.75,5926.73,180.000,NO,,,
R1332,"Q_RES_0402LF-0,5%,1/16W,EMPTY,CS00002JB13",0,5%,R0402,17130.00,6533.50,90.000,NO,,,
R1333,"Q_RES_0402LF-0,5%,1/16W,EMPTY,CS00002JB13",0,5%,R0402,17130.00,6751.50,270.000,NO,,,
R1334,"Q_RES_0402LF-0,5%,1/16W,EMPTY,CS00002JB13",0,5%,R0402,1333.27,6712.90,0.000,NO,,,
R1335,"Q_RES_0402LF-0,5%,1/16W,EMPTY,CS00002JB13",0,5%,R0402,1333.27,6832.90,0.000,NO,,,
R1336,"Q_RES_0402LF-0,5%,1/16W,EMPTY,CS00002JB13",0,5%,R0402,7141.29,6658.17,270.000,NO,,,
R1337,"Q_RES_0402LF-0,5%,1/16W,EMPTY,CS00002JB13",0,5%,R0402,7262.01,6658.19,270.000,NO,,,
R1338,"Q_RES_0402LF-4.7K,5%,1/16W,CHIP,CS24702JB10",4.7K,5%,R0402,5950.00,4495.00,180.000,NO,,,
R1339,"Q_RES_0402LF-0,5%,1/16W,CHIP,CS00002JB13",0,5%,R0402,7396.52,3948.44,90.000,NO,,,
R1340,"Q_RES_0402LF-0,5%,1/16W,CHIP,CS00002JB13",0,5%,R0402,8286.83,4053.47,0.000,NO,,,
R1341,"Q_RES_0402LF-2.2K,5%,1/16W,CHIP,CS22202JB07",2.2K,5%,R0402,10762.94,4670.00,180.000,NO,,,
R1342,"Q_RES_0402LF-10K,1%,1/16W,CHIP,CS31002FB08",10K,1%,R0402,12303.12,926.35,270.000,NO,,,
R1343,"Q_RES_0402LF-4.7K,5%,1/16W,EMPTY,CS24702JB10",4.7K,5%,R0402,12531.52,888.95,90.000,NO,,,
R1344,"Q_RES_0402LF-33.2,1%,1/16W,CHIP,CS03322FB03",33.2,1%,R0402,11760.00,4290.00,270.000,NO,,,
R1345,"Q_RES_0402LF-33.2,1%,1/16W,CHIP,CS03322FB03",33.2,1%,R0402,11800.00,4290.00,270.000,NO,,,
R1346,"Q_RES_0402LF-33.2,1%,1/16W,CHIP,CS03322FB03",33.2,1%,R0402,5770.37,1935.16,0.000,NO,,,
R1347,"Q_RES_0402LF-33.2,1%,1/16W,CHIP,CS03322FB03",33.2,1%,R0402,5770.52,1974.81,0.000,NO,,,
R1348,"Q_RES_0402LF-33.2,1%,1/16W,CHIP,CS03322FB03",33.2,1%,R0402,11720.00,4290.00,270.000,NO,,,
R1349,"Q_RES_0402LF-33.2,1%,1/16W,CHIP,CS03322FB03",33.2,1%,R0402,11840.00,4274.25,270.000,NO,,,
R1350,"Q_RES_0402LF-0,5%,1/16W,CHIP,CS00002JB13",0,5%,R0402,12640.00,3905.00,0.000,NO,,,
R1351,"Q_RES_0402LF-2.2K,5%,1/16W,CHIP,CS22202JB07",2.2K,5%,R0402,15612.07,12904.18,180.000,YES,,,
R1352,"Q_RES_0402LF-0,5%,1/16W,CHIP,CS00002JB13",0,5%,R0402,15205.19,2092.50,180.000,NO,,,
R1353,"Q_RES_0402LF-0,5%,1/16W,CHIP,CS00002JB13",0,5%,R0402,15205.19,2132.50,180.000,NO,,,
R1354,"Q_RES_0402LF-0,5%,1/16W,CHIP,CS00002JB13",0,5%,R0402,15205.19,2212.50,180.000,NO,,,
R1355,"Q_RES_0402LF-0,5%,1/16W,CHIP,CS00002JB13",0,5%,R0402,15405.17,2968.16,180.000,NO,,,
R1356,"Q_RES_0402LF-4.7K,5%,1/16W,CHIP,CS24702JB10",4.7K,5%,R0402,16889.25,1367.62,180.000,YES,,,
R1357,"Q_RES_0402LF-2.2K,5%,1/16W,CHIP,CS22202JB07",2.2K,5%,R0402,16889.25,1317.62,180.000,YES,,,
R1358,"Q_RES_0402LF-10K,5%,1/16W,EMPTY,CS31002JB08",10K,5%,R0402,16889.25,1267.62,180.000,YES,,,
R1359,"Q_RES_0402LF-0,5%,1/16W,CHIP,CS00002JB13",0,5%,R0402,7525.00,5093.62,90.000,NO,,,
R1360,"Q_RES_0402LF-0,5%,1/16W,CHIP,CS00002JB13",0,5%,R0402,757.54,1531.91,180.000,NO,,,
R1361,"Q_RES_0201LF-4.7K,5%,1/20W,CHIP,CS24701JE04",4.7K,5%,R0201,9445.00,13145.00,0.000,YES,,,
R1362,"Q_RES_0402LF-33,5%,1/16W,CHIP,CS03302JB10",33,5%,R0402,7338.11,5257.37,270.000,NO,,,
R1363,"Q_RES_0402LF-33,5%,1/16W,CHIP,CS03302JB10",33,5%,R0402,3781.84,4703.51,270.000,NO,,,
R1364,"Q_RES_0201LF-1K,1%,1/20W,CHIP,CS21001FE07",1K,1%,R0201,12822.73,15713.70,0.000,NO,,,
R1365,"Q_RES_0201LF-4.7K,5%,1/20W,CHIP,CS24701JE04",4.7K,5%,R0201,12088.00,16854.00,180.000,YES,,,
R1366,"Q_RES_0201LF-4.7K,5%,1/20W,CHIP,CS24701JE04",4.7K,5%,R0201,10025.00,13460.00,180.000,YES,,,
R1367,"Q_RES_0201LF-4.7K,5%,1/20W,CHIP,CS24701JE04",4.7K,5%,R0201,10025.00,13415.80,180.000,YES,,,
R1368,"Q_RES_0201LF-4.7K,5%,1/20W,CHIP,CS24701JE04",4.7K,5%,R0201,12872.73,15361.00,0.000,NO,,,
R1369,"Q_RES_0201LF-1K,1%,1/20W,EMPTY,CS21001FE07",1K,1%,R0201,13030.30,15658.51,180.000,NO,,,
R1370,"Q_RES_0201LF-10K,1%,1/20W,CHIP,CS31001FE17",10K,1%,R0201,12822.73,15682.70,0.000,NO,,,
R1371,"Q_RES_0201LF-4.7K,5%,1/20W,CHIP,CS24701JE04",4.7K,5%,R0201,10025.00,13371.60,180.000,YES,,,
R1372,"Q_RES_0201LF-1K,1%,1/20W,CHIP,CS21001FE07",1K,1%,R0201,4102.00,15442.00,0.000,NO,,,
R1373,"Q_RES_0201LF-4.7K,5%,1/20W,CHIP,CS24701JE04",4.7K,5%,R0201,3719.00,16394.00,180.000,NO,,,
R1374,"Q_RES_0201LF-4.7K,5%,1/20W,CHIP,CS24701JE04",4.7K,5%,R0201,10025.00,13327.40,180.000,YES,,,
R1375,"Q_RES_0201LF-4.7K,5%,1/20W,CHIP,CS24701JE04",4.7K,5%,R0201,10025.00,13282.60,180.000,YES,,,
R1376,"Q_RES_0201LF-4.7K,5%,1/20W,CHIP,CS24701JE04",4.7K,5%,R0201,4053.62,15031.00,180.000,NO,,,
R1377,"Q_RES_0201LF-1K,1%,1/20W,EMPTY,CS21001FE07",1K,1%,R0201,4102.00,15380.00,0.000,NO,,,
R1378,"Q_RES_0201LF-10K,1%,1/20W,CHIP,CS31001FE17",10K,1%,R0201,4124.50,15334.40,0.000,NO,,,
R1379,"Q_RES_0201LF-4.7K,5%,1/20W,CHIP,CS24701JE04",4.7K,5%,R0201,10025.00,13238.40,180.000,YES,,,
R1380,"Q_RES_0201LF-1K,1%,1/20W,CHIP,CS21001FE07",1K,1%,R0201,2744.00,15383.70,0.000,NO,,,
R1381,"Q_RES_0201LF-4.7K,5%,1/20W,CHIP,CS24701JE04",4.7K,5%,R0201,1874.36,16587.66,0.000,NO,,,
R1382,"Q_RES_0201LF-4.7K,5%,1/20W,CHIP,CS24701JE04",4.7K,5%,R0201,10025.00,13194.20,180.000,YES,,,
R1383,"Q_RES_0201LF-4.7K,5%,1/20W,CHIP,CS24701JE04",4.7K,5%,R0201,10025.00,13150.00,180.000,YES,,,
R1384,"Q_RES_0402LF-2K,1%,1/16W,EMPTY,CS22002FB07",2K,1%,R0402,7024.81,541.58,90.000,YES,,,
R1385,"Q_RES_0402LF-2K,1%,1/16W,EMPTY,CS22002FB07",2K,1%,R0402,6902.91,563.32,90.000,YES,,,
R1386,"Q_RES_0402LF-2K,1%,1/16W,EMPTY,CS22002FB07",2K,1%,R0402,6628.63,569.50,270.000,YES,,,
R1387,"Q_RES_0201LF-4.7K,5%,1/20W,CHIP,CS24701JE04",4.7K,5%,R0201,2794.00,15031.00,0.000,NO,,,
R1388,"Q_RES_0201LF-1K,1%,1/20W,EMPTY,CS21001FE07",1K,1%,R0201,2951.57,15328.51,180.000,NO,,,
R1389,"Q_RES_0201LF-10K,1%,1/20W,CHIP,CS31001FE17",10K,1%,R0201,2744.00,15352.70,0.000,NO,,,
R1390,"Q_RES_0201LF-4.7K,5%,1/20W,CHIP,CS24701JE04",4.7K,5%,R0201,9445.00,13190.00,0.000,YES,,,
R1391,"Q_RES_0201LF-1K,1%,1/20W,CHIP,CS21001FE07",1K,1%,R0201,14180.73,15772.00,0.000,NO,,,
R1392,"Q_RES_0201LF-4.7K,5%,1/20W,CHIP,CS24701JE04",4.7K,5%,R0201,14180.00,15804.00,0.000,NO,,,
R1393,"Q_RES_0201LF-4.7K,5%,1/20W,CHIP,CS24701JE04",4.7K,5%,R0201,9445.00,13235.00,0.000,YES,,,
R1394,"Q_RES_0201LF-4.7K,5%,1/20W,CHIP,CS24701JE04",4.7K,5%,R0201,9445.00,13280.00,0.000,YES,,,
R1395,"Q_RES_0201LF-4.7K,5%,1/20W,CHIP,CS24701JE04",4.7K,5%,R0201,14132.35,15361.00,180.000,NO,,,
R1396,"Q_RES_0402LF-10K,1%,1/16W,CHIP,CS31002FB08",10K,1%,R0402,7117.00,1577.62,0.000,NO,,,
R1397,"Q_RES_0201LF-1K,1%,1/20W,EMPTY,CS21001FE07",1K,1%,R0201,14180.73,15710.00,0.000,NO,,,
R1398,"Q_RES_0201LF-10K,1%,1/20W,CHIP,CS31001FE17",10K,1%,R0201,14203.23,15664.40,0.000,NO,,,
R1399,"Q_RES_0201LF-4.7K,5%,1/20W,CHIP,CS24701JE04",4.7K,5%,R0201,9445.00,13325.00,0.000,YES,,,
R1400,"Q_RES_0201LF-1K,1%,1/20W,CHIP,CS21001FE07",1K,1%,R0201,17167.43,16063.40,0.000,NO,,,
R1401,"Q_RES_0201LF-4.7K,5%,1/20W,CHIP,CS24701JE04",4.7K,5%,R0201,17167.43,16129.40,0.000,NO,,,
R1402,"Q_RES_0201LF-4.7K,5%,1/20W,CHIP,CS24701JE04",4.7K,5%,R0201,9445.00,13370.00,0.000,YES,,,
R1403,"Q_RES_0201LF-4.7K,5%,1/20W,CHIP,CS24701JE04",4.7K,5%,R0201,9445.00,13415.00,0.000,YES,,,
R1404,"Q_RES_0201LF-4.7K,5%,1/20W,CHIP,CS24701JE04",4.7K,5%,R0201,16763.45,15346.54,270.000,NO,,,
R1405,"Q_RES_0201LF-1K,1%,1/20W,EMPTY,CS21001FE07",1K,1%,R0201,17020.00,15981.00,0.000,NO,,,
R1406,"Q_RES_0201LF-10K,1%,1/20W,CHIP,CS31001FE17",10K,1%,R0201,17167.43,15997.40,0.000,NO,,,
R1407,"Q_RES_0201LF-4.7K,5%,1/20W,CHIP,CS24701JE04",4.7K,5%,R0201,9445.00,13460.00,0.000,YES,,,
R1408,"Q_RES_0201LF-1K,1%,1/20W,CHIP,CS21001FE07",1K,1%,R0201,15464.46,15713.70,0.000,NO,,,
R1409,"Q_RES_0201LF-4.7K,5%,1/20W,CHIP,CS24701JE04",4.7K,5%,R0201,16714.00,16663.00,90.000,NO,,,
R1410,"Q_RES_0201LF-1K,1%,1/20W,CHIP,CS21001FE07",1K,1%,R0201,11871.47,16710.62,270.000,YES,,,
R1411,"Q_RES_0201LF-1K,1%,1/20W,CHIP,CS21001FE07",1K,1%,R0201,11853.63,16837.34,90.000,YES,,,
R1412,"Q_RES_0201LF-4.7K,5%,1/20W,CHIP,CS24701JE04",4.7K,5%,R0201,15514.46,15361.00,0.000,NO,,,
R1413,"Q_RES_0201LF-1K,1%,1/20W,EMPTY,CS21001FE07",1K,1%,R0201,15672.03,15658.51,180.000,NO,,,
R1414,"Q_RES_0201LF-10K,1%,1/20W,CHIP,CS31001FE17",10K,1%,R0201,15464.47,15682.70,0.000,NO,,,
R1415,"Q_RES_0201LF-1K,1%,1/20W,CHIP,CS21001FE07",1K,1%,R0201,11597.68,15540.23,180.000,NO,,,
R1416,"Q_RES_0201LF-1K,1%,1/20W,CHIP,CS21001FE07",1K,1%,R0201,7102.00,15451.00,0.000,NO,,,
R1417,"Q_RES_0201LF-4.7K,5%,1/20W,CHIP,CS24701JE04",4.7K,5%,R0201,7102.00,15517.00,0.000,NO,,,
R1418,"Q_RES_0201LF-1K,1%,1/20W,CHIP,CS21001FE07",1K,1%,R0201,11604.72,15445.75,180.000,NO,,,
R1419,"Q_RES_0402LF-4.7K,5%,1/16W,CHIP,CS24702JB10",4.7K,5%,R0402,14291.69,1113.13,90.000,NO,,,
R1420,"Q_RES_0201LF-1K,1%,1/20W,CHIP,CS21001FE07",1K,1%,R0201,14401.00,16795.44,0.000,NO,,,
R1421,"Q_RES_0201LF-4.7K,5%,1/20W,CHIP,CS24701JE04",4.7K,5%,R0201,6682.06,15040.89,270.000,NO,,,
R1422,"Q_RES_0402LF-100,1%,1/16W,CHIP,CS11002FB07",100,1%,R0402,7078.00,5240.62,270.000,YES,,,
R1423,"Q_RES_0402LF-0,5%,1/16W,CHIP,CS00002JB13",0,5%,R0402,14497.69,1702.17,270.000,NO,,,
R1424,"Q_RES_0402LF-2.2K,5%,1/16W,CHIP,CS22202JB07",2.2K,5%,R0402,3812.71,12074.88,180.000,YES,,,
R1425,"Q_RES_0402LF-0,5%,1/16W,CHIP,CS00002JB13",0,5%,R0402,14545.49,1184.43,270.000,NO,,,
R1426,"Q_RES_0201LF-1K,1%,1/20W,EMPTY,CS21001FE07",1K,1%,R0201,7000.40,15362.50,0.000,NO,,,
R1427,"Q_RES_0201LF-10K,1%,1/20W,CHIP,CS31001FE17",10K,1%,R0201,7102.00,15385.00,0.000,NO,,,
R1428,"Q_RES_0201LF-1K,1%,1/20W,CHIP,CS21001FE07",1K,1%,R0201,14401.17,16892.73,0.000,NO,,,
R1429,"Q_RES_0201LF-1K,1%,1/20W,CHIP,CS21001FE07",1K,1%,R0201,5385.97,15347.09,0.000,NO,,,
R1430,"Q_RES_0201LF-4.7K,5%,1/20W,CHIP,CS24701JE04",4.7K,5%,R0201,6475.00,16788.00,270.000,YES,,,
R1431,"Q_RES_0201LF-1K,1%,1/20W,CHIP,CS21001FE07",1K,1%,R0201,16719.86,16799.93,270.000,YES,,,
R1432,"Q_RES_0201LF-1K,1%,1/20W,CHIP,CS21001FE07",1K,1%,R0201,16719.06,16855.06,90.000,YES,,,
R1433,"Q_RES_0201LF-4.7K,5%,1/20W,CHIP,CS24701JE04",4.7K,5%,R0201,5435.73,15031.00,0.000,NO,,,
R1434,"Q_RES_0201LF-1K,1%,1/20W,EMPTY,CS21001FE07",1K,1%,R0201,5593.30,15328.51,180.000,NO,,,
R1435,"Q_RES_0201LF-10K,1%,1/20W,CHIP,CS31001FE17",10K,1%,R0201,5441.00,15325.90,90.000,NO,,,
R1436,"Q_RES_0201LF-1K,1%,1/20W,CHIP,CS21001FE07",1K,1%,R0201,3708.00,15794.00,180.000,NO,,,
R1437,"Q_RES_0201LF-1K,1%,1/20W,CHIP,CS21001FE07",1K,1%,R0201,3708.00,15826.00,180.000,NO,,,
R1438,"Q_RES_0201LF-4.7K,5%,1/20W,EMPTY,CS24701JE04",4.7K,5%,R0201,12024.54,16822.00,180.000,YES,,,
R1439,"Q_RES_0201LF-4.7K,5%,1/20W,EMPTY,CS24701JE04",4.7K,5%,R0201,12024.54,16758.00,180.000,YES,,,
R1440,"Q_RES_0402LF-100K,1%,1/16W,CHIP,CS41002FB09",100K,1%,R0402,4199.84,5030.24,270.000,NO,,,
R1441,"Q_RES_0402LF-16.9K,1%,1/16W,CHIP,CS31692FB03",16.9K,1%,R0402,4159.84,5030.24,90.000,NO,,,
R1442,"Q_RES_0402LF-100K,1%,1/16W,CHIP,CS41002FB09",100K,1%,R0402,4061.84,5031.01,270.000,NO,,,
R1443,"Q_RES_0402LF-16.9K,1%,1/16W,CHIP,CS31692FB03",16.9K,1%,R0402,4021.84,5031.01,90.000,NO,,,
R1444,"Q_RES_0402LF-130,1%,1/16W,CHIP,CS11302FB03",130,1%,R0402,13200.20,629.79,270.000,NO,,,
R1445,"Q_RES_0201LF-1K,1%,1/20W,EMPTY,CS21001FE07",1K,1%,R0201,12024.54,16790.00,180.000,YES,,,
R1446,"Q_RES_0201LF-4.7K,5%,1/20W,EMPTY,CS24701JE04",4.7K,5%,R0201,12024.54,16854.00,180.000,YES,,,
R1447,"Q_RES_0402LF-0,5%,1/16W,CHIP,CS00002JB13",0,5%,R0402,7485.00,5418.62,270.000,NO,,,
R1448,"Q_RES_0201LF-1K,1%,1/20W,CHIP,CS21001FE07",1K,1%,R0201,4650.00,15794.00,0.000,NO,,,
R1449,"Q_RES_0402LF-10K,5%,1/16W,CHIP,CS31002JB08",10K,5%,R0402,4159.84,4703.92,90.000,NO,,,
R1450,"Q_RES_0402LF-10K,5%,1/16W,CHIP,CS31002JB08",10K,5%,R0402,4021.84,4704.69,90.000,NO,,,
R1451,"Q_RES_0201LF-1K,1%,1/20W,CHIP,CS21001FE07",1K,1%,R0201,4650.00,15762.00,0.000,NO,,,
R1452,"Q_RES_0402LF-10K,5%,1/16W,CHIP,CS31002JB08",10K,5%,R0402,4109.84,5030.24,270.000,NO,,,
R1453,"Q_RES_0402LF-0,5%,1/16W,CHIP,CS00002JB13",0,5%,R0402,7605.00,5418.62,270.000,NO,,,
R1454,"Q_RES_0201LF-4.7K,5%,1/20W,EMPTY,CS24701JE04",4.7K,5%,R0201,3782.00,16426.00,180.000,NO,,,
R1455,"Q_RES_0201LF-4.7K,5%,1/20W,EMPTY,CS24701JE04",4.7K,5%,R0201,3782.00,16490.00,180.000,NO,,,
R1456,"Q_RES_0201LF-1K,1%,1/20W,EMPTY,CS21001FE07",1K,1%,R0201,3782.00,16458.00,180.000,NO,,,
R1457,"Q_RES_0402LF-10K,5%,1/16W,CHIP,CS31002JB08",10K,5%,R0402,3971.84,5031.01,270.000,NO,,,
R1458,"Q_RES_0402LF-33,5%,1/16W,CHIP,CS03302JB10",33,5%,R0402,3921.84,5031.01,270.000,NO,,,
R1459,"Q_RES_0402LF-33,5%,1/16W,CHIP,CS03302JB10",33,5%,R0402,3821.84,5031.01,270.000,NO,,,
R1460,"Q_RES_0402LF-2.2K,5%,1/16W,EMPTY,CS22202JB07",2.2K,5%,R0402,6822.91,528.22,270.000,YES,,,
R1461,"Q_RES_0201LF-4.7K,5%,1/20W,EMPTY,CS24701JE04",4.7K,5%,R0201,3782.00,16394.00,180.000,NO,,,
R1462,"Q_RES_0201LF-1K,1%,1/20W,CHIP,CS21001FE07",1K,1%,R0201,6626.00,16585.74,270.000,YES,,,
R1463,"Q_RES_0201LF-1K,1%,1/20W,CHIP,CS21001FE07",1K,1%,R0201,6662.00,16585.74,270.000,YES,,,
R1464,"Q_RES_0201LF-4.7K,5%,1/20W,EMPTY,CS24701JE04",4.7K,5%,R0201,1808.36,16555.66,0.000,NO,,,
R1465,"Q_RES_0201LF-4.7K,5%,1/20W,EMPTY,CS24701JE04",4.7K,5%,R0201,1808.36,16491.66,0.000,NO,,,
R1466,"Q_RES_0201LF-1K,1%,1/20W,EMPTY,CS21001FE07",1K,1%,R0201,1808.36,16523.66,0.000,NO,,,
R1467,"Q_RES_0201LF-4.7K,5%,1/20W,EMPTY,CS24701JE04",4.7K,5%,R0201,1808.36,16587.66,0.000,NO,,,
R1468,"Q_RES_0201LF-1K,1%,1/20W,CHIP,CS21001FE07",1K,1%,R0201,6190.00,16416.00,180.000,YES,,,
R1469,"Q_RES_0201LF-1K,1%,1/20W,CHIP,CS21001FE07",1K,1%,R0201,6190.00,16384.00,180.000,YES,,,
R1470,"Q_RES_0201LF-4.7K,5%,1/20W,EMPTY,CS24701JE04",4.7K,5%,R0201,13838.00,16058.00,90.000,NO,,,
R1471,"Q_RES_0201LF-4.7K,5%,1/20W,EMPTY,CS24701JE04",4.7K,5%,R0201,13870.00,16058.00,90.000,NO,,,
R1472,"Q_RES_0201LF-1K,1%,1/20W,EMPTY,CS21001FE07",1K,1%,R0201,13902.00,16058.00,90.000,NO,,,
R1473,"Q_RES_0201LF-4.7K,5%,1/20W,EMPTY,CS24701JE04",4.7K,5%,R0201,13934.00,16058.00,90.000,NO,,,
R1474,"Q_RES_0402LF-10K,1%,1/16W,EMPTY,CS31002FB08",10K,1%,R0402,1532.00,4388.10,180.000,NO,,,
R1475,"Q_RES_0402LF-10K,1%,1/16W,EMPTY,CS31002FB08",10K,1%,R0402,1799.80,4382.70,180.000,NO,,,
R1476,"Q_RES_0201LF-4.7K,5%,1/20W,EMPTY,CS24701JE04",4.7K,5%,R0201,17020.00,16043.00,0.000,NO,,,
R1477,"Q_RES_0201LF-4.7K,5%,1/20W,EMPTY,CS24701JE04",4.7K,5%,R0201,17020.00,15950.00,0.000,NO,,,
R1478,"Q_RES_0201LF-1K,1%,1/20W,EMPTY,CS21001FE07",1K,1%,R0201,17020.00,16012.00,0.000,NO,,,
R1479,"Q_RES_0201LF-4.7K,5%,1/20W,EMPTY,CS24701JE04",4.7K,5%,R0201,17020.00,16074.00,0.000,NO,,,
R1480,"Q_RES_2512LF-10,1%,2W,EMPTY,CS0100AFR00",10,1%,R2512XR,1472.90,4936.30,270.000,NO,,,
R1481,"Q_RES_2512LF-10,1%,2W,EMPTY,CS0100AFR00",10,1%,R2512XR,1740.70,4930.90,270.000,NO,,,
R1482,"Q_RES_0201LF-4.7K,5%,1/20W,EMPTY,CS24701JE04",4.7K,5%,R0201,16746.00,16600.00,90.000,NO,,,
R1483,"Q_RES_0201LF-4.7K,5%,1/20W,EMPTY,CS24701JE04",4.7K,5%,R0201,16810.00,16600.00,90.000,NO,,,
R1484,"Q_RES_0201LF-1K,1%,1/20W,EMPTY,CS21001FE07",1K,1%,R0201,16778.00,16600.00,90.000,NO,,,
R1485,"Q_RES_0201LF-4.7K,5%,1/20W,EMPTY,CS24701JE04",4.7K,5%,R0201,16714.00,16600.00,90.000,NO,,,
R1486,"Q_RES_0402LF-0,5%,1/16W,CHIP,CS00002JB13",0,5%,R0402,17841.33,1573.10,90.000,NO,,,
R1487,"Q_RES_0402LF-0,5%,1/16W,CHIP,CS00002JB13",0,5%,R0402,16500.35,4300.44,270.000,NO,,,
R1488,"Q_RES_0201LF-4.7K,5%,1/20W,EMPTY,CS24701JE04",4.7K,5%,R0201,7000.40,15484.00,0.000,NO,,,
R1489,"Q_RES_0201LF-4.7K,5%,1/20W,EMPTY,CS24701JE04",4.7K,5%,R0201,7000.40,15317.00,0.000,NO,,,
R1490,"Q_RES_0201LF-1K,1%,1/20W,EMPTY,CS21001FE07",1K,1%,R0201,7000.40,15418.00,0.000,NO,,,
R1491,"Q_RES_0402LF-10K,5%,1/16W,EMPTY,CS31002JB08",10K,5%,R0402,4435.00,4880.00,90.000,NO,,,
R1492,"Q_RES_0402LF-10K,5%,1/16W,CHIP,CS31002JB08",10K,5%,R0402,4297.84,4703.15,90.000,NO,,,
R1493,"Q_RES_0402LF-10K,5%,1/16W,CHIP,CS31002JB08",10K,5%,R0402,4247.84,5029.47,270.000,NO,,,
R1494,"Q_RES_0402LF-33,5%,1/16W,CHIP,CS03302JB10",33,5%,R0402,885.00,14485.00,0.000,NO,,,
R1495,"Q_RES_0402LF-33,5%,1/16W,CHIP,CS03302JB10",33,5%,R0402,800.00,14445.00,0.000,YES,,,
R1496,"Q_RES_0402LF-33,5%,1/16W,CHIP,CS03302JB10",33,5%,R0402,800.00,14485.00,0.000,YES,,,
R1497,"Q_RES_0402LF-33,5%,1/16W,CHIP,CS03302JB10",33,5%,R0402,9943.84,4736.75,180.000,NO,,,
R1498,"Q_RES_0402LF-33,5%,1/16W,CHIP,CS03302JB10",33,5%,R0402,9943.84,4791.75,180.000,NO,,,
R1499,"Q_RES_0201LF-4.7K,5%,1/20W,EMPTY,CS24701JE04",4.7K,5%,R0201,7000.40,15517.00,0.000,NO,,,
R1500,"Q_RES_0402LF-0,5%,1/16W,CHIP,CS00002JB13",0,5%,R0402,16239.42,2785.20,0.000,NO,,,
R1501,"Q_RES_0402LF-10K,5%,1/16W,EMPTY,CS31002JB08",10K,5%,R0402,5713.57,12527.88,180.000,YES,,,
R1502,"Q_RES_0402LF-10K,5%,1/16W,CHIP,CS31002JB08",10K,5%,R0402,5748.46,12619.13,180.000,YES,,,
R1503,"Q_RES_0402LF-30K,1%,1/16W,CHIP,CS33002FB02",30K,1%,R0402,15580.77,12747.88,90.000,NO,,,
R1504,"Q_RES_0402LF-30K,1%,1/16W,CHIP,CS33002FB02",30K,1%,R0402,15634.88,12734.45,0.000,NO,,,
R1505,"Q_RES_0402LF-30K,1%,1/16W,CHIP,CS33002FB02",30K,1%,R0402,15543.77,12747.88,90.000,NO,,,
R1506,"Q_RES_0402LF-30K,1%,1/16W,CHIP,CS33002FB02",30K,1%,R0402,15621.77,12841.08,0.000,YES,,,
R1507,"Q_RES_0402LF-1K,1%,1/16W,CHIP,CS21002FB06",1K,1%,R0402,13333.99,940.84,270.000,NO,,,
R1508,"Q_RES_0402LF-100,1%,1/16W,CHIP,CS11002FB07",100,1%,R0402,16565.25,1417.62,0.000,NO,,,
R1509,"Q_RES_0402LF-0,5%,1/16W,CHIP,CS00002JB13",0,5%,R0402,8711.90,3862.60,90.000,NO,,,
R1510,"Q_RES_0201LF-4.7K,5%,1/20W,EMPTY,CS24701JE04",4.7K,5%,R0201,6502.00,16716.55,270.000,YES,,,
R1511,"Q_RES_0201LF-4.7K,5%,1/20W,EMPTY,CS24701JE04",4.7K,5%,R0201,6438.00,16716.55,270.000,YES,,,
R1512,"Q_RES_0201LF-1K,1%,1/20W,EMPTY,CS21001FE07",1K,1%,R0201,6406.00,16716.55,270.000,YES,,,
R1513,"Q_RES_0201LF-4.7K,5%,1/20W,EMPTY,CS24701JE04",4.7K,5%,R0201,6470.00,16716.55,270.000,YES,,,
R1514,"Q_RES_0201LF-0,5%,1/20W,CHIP,CS00001JE10",0,5%,R0201,9676.00,13074.00,180.000,YES,,,
R1515,"Q_RES_0201LF-0,5%,1/20W,CHIP,CS00001JE10",0,5%,R0201,9676.00,13042.00,180.000,YES,,,
R1516,"Q_RES_0402LF-33.2,1%,1/16W,CHIP,CS03322FB03",33.2,1%,R0402,4010.00,16268.00,180.000,YES,,,
R1517,"Q_RES_0402LF-33.2,1%,1/16W,CHIP,CS03322FB03",33.2,1%,R0402,4060.06,16312.19,180.000,YES,,,
R1518,"Q_RES_0402LF-0,5%,1/16W,CHIP,CS00002JB13",0,5%,R0402,8700.20,4187.20,0.000,NO,,,
R1519,"Q_RES_0402LF-0,5%,1/16W,EMPTY,CS00002JB13",0,5%,R0402,8671.90,3862.60,90.000,NO,,,
R1520,"Q_RES_0402LF-0,5%,1/16W,CHIP,CS00002JB13",0,5%,R0402,2250.90,1549.70,90.000,NO,,,
R1521,"Q_RES_0402LF-0,5%,1/16W,CHIP,CS00002JB13",0,5%,R0402,2238.52,1447.10,180.000,NO,,,
R1522,"Q_RES_0402LF-0,5%,1/16W,CHIP,CS00002JB13",0,5%,R0402,6017.70,1322.70,0.000,NO,,,
R1523,"Q_RES_0402LF-0,5%,1/16W,CHIP,CS00002JB13",0,5%,R0402,2260.20,2068.20,0.000,NO,,,
R1524,"Q_RES_0402LF-0,5%,1/16W,CHIP,CS00002JB13",0,5%,R0402,2617.10,2076.60,0.000,NO,,,
R1525,"Q_RES_0402LF-0,5%,1/16W,EMPTY,CS00002JB13",0,5%,R0402,2490.40,2243.70,0.000,NO,,,
R1526,"Q_RES_0402LF-0,5%,1/16W,CHIP,CS00002JB13",0,5%,R0402,10501.04,16638.84,270.000,NO,,,
R1527,"Q_RES_0402LF-1K,1%,1/16W,CHIP,CS21002FB06",1K,1%,R0402,7766.52,4913.44,0.000,NO,,,
R1528,"Q_RES_0402LF-33,5%,1/16W,CHIP,CS03302JB10",33,5%,R0402,15893.03,2142.50,180.000,NO,,,
R1529,"Q_RES_0402LF-1K,1%,1/16W,EMPTY,CS21002FB06",1K,1%,R0402,10432.54,5445.74,180.000,NO,,,
R1530,"Q_RES_0402LF-1K,1%,1/16W,EMPTY,CS21002FB06",1K,1%,R0402,10432.54,5495.74,180.000,NO,,,
R1531,"Q_RES_0402LF-1K,1%,1/16W,EMPTY,CS21002FB06",1K,1%,R0402,10300.00,5660.00,180.000,NO,,,
R1532,"Q_RES_0402LF-1K,1%,1/16W,EMPTY,CS21002FB06",1K,1%,R0402,10390.00,5590.00,90.000,NO,,,
R1533,"Q_RES_0402LF-0,5%,1/16W,CHIP,CS00002JB13",0,5%,R0402,7194.38,3823.34,90.000,YES,,,
R1546,"Q_RES_0402LF-1K,1%,1/16W,CHIP,CS21002FB06",1K,1%,R0402,5673.33,681.62,90.000,YES,,,
R1547,"Q_RES_0402LF-4.7K,5%,1/16W,CHIP,CS24702JB10",4.7K,5%,R0402,9900.56,5310.74,0.000,NO,,,
R1549,"Q_RES_0402LF-33,5%,1/16W,CHIP,CS03302JB10",33,5%,R0402,7692.52,4993.44,180.000,YES,,,
R1550,"Q_RES_0402LF-33,5%,1/16W,CHIP,CS03302JB10",33,5%,R0402,7444.39,4993.44,270.000,YES,,,
R1551,"Q_RES_0402LF-33,5%,1/16W,CHIP,CS03302JB10",33,5%,R0402,7405.00,5418.62,270.000,NO,,,
R1552,"Q_RES_0402LF-33,5%,1/16W,CHIP,CS03302JB10",33,5%,R0402,7365.00,5418.62,90.000,NO,,,
R1553,"Q_RES_0402LF-33,5%,1/16W,CHIP,CS03302JB10",33,5%,R0402,7408.95,5258.81,90.000,NO,,,
R1556,"Q_RES_0402LF-33,5%,1/16W,CHIP,CS03302JB10",33,5%,R0402,7730.00,5418.62,90.000,NO,,,
R1557,"Q_RES_0402LF-33,5%,1/16W,CHIP,CS03302JB10",33,5%,R0402,7285.00,5418.62,90.000,NO,,,
R1558,"Q_RES_0402LF-33,5%,1/16W,CHIP,CS03302JB10",33,5%,R0402,7404.39,4993.44,270.000,YES,,,
R1563,"Q_RES_0402LF-33,5%,1/16W,CHIP,CS03302JB10",33,5%,R0402,8069.09,4396.28,180.000,NO,,,
R1564,"Q_RES_0402LF-33,5%,1/16W,CHIP,CS03302JB10",33,5%,R0402,7605.00,5093.62,90.000,NO,,,
R1567,"Q_RES_0402LF-4.7K,5%,1/16W,CHIP,CS24702JB10",4.7K,5%,R0402,7565.00,5418.62,270.000,NO,,,
R1568,"Q_RES_0402LF-49.9,1%,1/16W,CHIP,CS04992FB07",49.9,1%,R0402,12100.05,7676.65,180.000,YES,,,
R1569,"Q_RES_0402LF-49.9,1%,1/16W,CHIP,CS04992FB07",49.9,1%,R0402,11774.35,7672.99,180.000,YES,,,
R1570,"Q_RES_0402LF-49.9,1%,1/16W,CHIP,CS04992FB07",49.9,1%,R0402,11477.35,7672.99,180.000,YES,,,
R1571,"Q_RES_0402LF-0,5%,1/16W,CHIP,CS00002JB13",0,5%,R0402,17800.75,1907.99,0.000,NO,,,
R1572,"Q_RES_0402LF-49.9,1%,1/16W,CHIP,CS04992FB07",49.9,1%,R0402,10883.33,7672.99,180.000,YES,,,
R1573,"Q_RES_0402LF-49.9,1%,1/16W,CHIP,CS04992FB07",49.9,1%,R0402,10586.32,7672.99,180.000,YES,,,
R1574,"Q_RES_0402LF-49.9,1%,1/16W,CHIP,CS04992FB07",49.9,1%,R0402,16366.63,7672.65,180.000,YES,,,
R1575,"Q_RES_0402LF-49.9,1%,1/16W,CHIP,CS04992FB07",49.9,1%,R0402,16663.64,7672.65,180.000,YES,,,
R1576,"Q_RES_0402LF-49.9,1%,1/16W,CHIP,CS04992FB07",49.9,1%,R0402,16960.65,7672.65,180.000,YES,,,
R1577,"Q_RES_0402LF-49.9,1%,1/16W,CHIP,CS04992FB07",49.9,1%,R0402,17257.66,7672.99,180.000,YES,,,
R1578,"Q_RES_0402LF-49.9,1%,1/16W,CHIP,CS04992FB07",49.9,1%,R0402,17554.66,7673.05,180.000,YES,,,
R1579,"Q_RES_0402LF-49.9,1%,1/16W,CHIP,CS04992FB07",49.9,1%,R0402,17851.67,7675.65,180.000,YES,,,
R1580,"Q_RES_0402LF-49.9,1%,1/16W,CHIP,CS04992FB07",49.9,1%,R0402,2338.63,7677.66,180.000,YES,,,
R1581,"Q_RES_0402LF-49.9,1%,1/16W,CHIP,CS04992FB07",49.9,1%,R0402,2012.93,7674.00,180.000,YES,,,
R1582,"Q_RES_0402LF-49.9,1%,1/16W,CHIP,CS04992FB07",49.9,1%,R0402,1715.62,7676.66,180.000,YES,,,
R1583,"Q_RES_0402LF-49.9,1%,1/16W,CHIP,CS04992FB07",49.9,1%,R0402,1418.92,7674.00,180.000,YES,,,
R1584,"Q_RES_0402LF-49.9,1%,1/16W,CHIP,CS04992FB07",49.9,1%,R0402,1120.60,7677.66,180.000,YES,,,
R1585,"Q_RES_0402LF-49.9,1%,1/16W,CHIP,CS04992FB07",49.9,1%,R0402,823.59,7677.66,180.000,YES,,,
R1586,"Q_RES_0402LF-49.9,1%,1/16W,CHIP,CS04992FB07",49.9,1%,R0402,6605.22,7673.00,180.000,YES,,,
R1587,"Q_RES_0402LF-49.9,1%,1/16W,CHIP,CS04992FB07",49.9,1%,R0402,6902.23,7673.00,180.000,YES,,,
R1588,"Q_RES_0402LF-49.9,1%,1/16W,CHIP,CS04992FB07",49.9,1%,R0402,7199.24,7673.00,180.000,YES,,,
R1589,"Q_RES_0402LF-49.9,1%,1/16W,CHIP,CS04992FB07",49.9,1%,R0402,7496.24,7673.00,180.000,YES,,,
R1590,"Q_RES_0402LF-49.9,1%,1/16W,CHIP,CS04992FB07",49.9,1%,R0402,7793.25,7673.00,180.000,YES,,,
R1591,"Q_RES_0402LF-49.9,1%,1/16W,CHIP,CS04992FB07",49.9,1%,R0402,8118.95,7676.65,0.000,YES,,,
R1592,"Q_RES_0402LF-33,5%,1/16W,CHIP,CS03302JB10",33,5%,R0402,15696.07,12787.88,180.000,YES,,,
R1593,"Q_RES_0402LF-33,5%,1/16W,CHIP,CS03302JB10",33,5%,R0402,15910.07,12751.68,180.000,YES,,,
R1594,"Q_RES_0402LF-33.2,1%,1/16W,CHIP,CS03322FB03",33.2,1%,R0402,18235.80,1478.34,0.000,NO,,,
R1595,"Q_RES_0402LF-33.2,1%,1/16W,CHIP,CS03322FB03",33.2,1%,R0402,14734.05,615.63,0.000,NO,,,
R1605,"Q_RES_0402LF-1K,1%,1/16W,CHIP,CS21002FB06",1K,1%,R0402,6477.21,1848.62,180.000,NO,,,
R1616,"Q_RES_0402LF-33,5%,1/16W,CHIP,CS03302JB10",33,5%,R0402,7685.00,5418.62,270.000,YES,,,
R1619,"Q_RES_0402LF-0,5%,1/16W,CHIP,CS00002JB13",0,5%,R0402,5795.24,2571.71,180.000,NO,,,
R1620,"Q_RES_0402LF-33,5%,1/16W,CHIP,CS03302JB10",33,5%,R0402,15893.03,2252.50,180.000,NO,,,
R1621,"Q_RES_0402LF-1K,1%,1/16W,CHIP,CS21002FB06",1K,1%,R0402,15893.03,2292.50,180.000,NO,,,
R1622,"Q_RES_0402LF-4.7K,5%,1/16W,CHIP,CS24702JB10",4.7K,5%,R0402,5727.36,2358.21,0.000,NO,,,
R1624,"Q_RES_0402LF-1K,1%,1/16W,CHIP,CS21002FB06",1K,1%,R0402,10700.81,3697.92,180.000,NO,,,
R1625,"Q_RES_0402LF-0,5%,1/16W,CHIP,CS00002JB13",0,5%,R0402,5027.76,2052.85,0.000,NO,,,
R1626,"Q_RES_0402LF-1K,1%,1/16W,CHIP,CS21002FB06",1K,1%,R0402,15136.44,2148.25,270.000,NO,,,
R1627,"Q_RES_0402LF-1K,1%,1/16W,CHIP,CS21002FB06",1K,1%,R0402,15205.19,2252.50,180.000,NO,,,
R1628,"Q_RES_0402LF-1K,1%,1/16W,CHIP,CS21002FB06",1K,1%,R0402,15205.19,2312.50,180.000,NO,,,
R1629,"Q_RES_0402LF-1K,1%,1/16W,CHIP,CS21002FB06",1K,1%,R0402,15205.19,2492.50,180.000,NO,,,
R1630,"Q_RES_0402LF-1K,1%,1/16W,CHIP,CS21002FB06",1K,1%,R0402,15205.19,2380.17,180.000,NO,,,
R1631,"Q_RES_0402LF-33,5%,1/16W,CHIP,CS03302JB10",33,5%,R0402,15205.19,2442.50,180.000,NO,,,
R1632,"Q_RES_0402LF-33,5%,1/16W,CHIP,CS03302JB10",33,5%,R0402,15205.19,2532.50,180.000,NO,,,
R1633,"Q_RES_0402LF-0,5%,1/16W,CHIP,CS00002JB13",0,5%,R0402,10229.69,3787.64,180.000,NO,,,
R1634,"Q_RES_0402LF-0,5%,1/16W,CHIP,CS00002JB13",0,5%,R0402,10229.69,3837.64,180.000,NO,,,
R1635,"Q_RES_0402LF-22,1%,1/16W,CHIP,CS02202FB02",22,1%,R0402,10229.69,3887.64,180.000,NO,,,
R1636,"Q_RES_0402LF-22,1%,1/16W,CHIP,CS02202FB02",22,1%,R0402,10229.69,3937.64,180.000,NO,,,
R1637,"Q_RES_0402LF-4.7K,5%,1/16W,CHIP,CS24702JB10",4.7K,5%,R0402,5283.04,2124.97,270.000,NO,,,
R1638,"Q_RES_0402LF-22,1%,1/16W,CHIP,CS02202FB02",22,1%,R0402,10004.60,3650.36,270.000,NO,,,
R1639,"Q_RES_0402LF-22,1%,1/16W,CHIP,CS02202FB02",22,1%,R0402,9964.60,3650.36,270.000,NO,,,
R1640,"Q_RES_0402LF-22,1%,1/16W,CHIP,CS02202FB02",22,1%,R0402,9924.60,3650.36,270.000,NO,,,
R1641,"Q_RES_0402LF-22,1%,1/16W,CHIP,CS02202FB02",22,1%,R0402,9884.60,3650.36,270.000,NO,,,
R1642,"Q_RES_0402LF-22,1%,1/16W,CHIP,CS02202FB02",22,1%,R0402,10832.35,3792.26,180.000,NO,,,
R1643,"Q_RES_0402LF-22,1%,1/16W,CHIP,CS02202FB02",22,1%,R0402,10832.35,3832.26,180.000,NO,,,
R1644,"Q_RES_0402LF-22,1%,1/16W,CHIP,CS02202FB02",22,1%,R0402,10832.35,3872.26,180.000,NO,,,
R1645,"Q_RES_0402LF-22,1%,1/16W,CHIP,CS02202FB02",22,1%,R0402,10832.35,3912.26,180.000,NO,,,
R1646,"Q_RES_0402LF-1K,1%,1/16W,CHIP,CS21002FB06",1K,1%,R0402,9184.56,5707.06,0.000,NO,,,
R1647,"Q_RES_0402LF-1K,1%,1/16W,CHIP,CS21002FB06",1K,1%,R0402,9280.24,5707.03,180.000,NO,,,
R1648,"Q_RES_0402LF-0,5%,1/16W,CHIP,CS00002JB13",0,5%,R0402,9465.43,5852.00,0.000,NO,,,
R1649,"Q_RES_0402LF-1K,1%,1/16W,CHIP,CS21002FB06",1K,1%,R0402,8418.72,5366.85,90.000,NO,,,
R1650,"Q_RES_0402LF-1K,1%,1/16W,CHIP,CS21002FB06",1K,1%,R0402,8640.65,5175.36,90.000,NO,,,
R1651,"Q_RES_0402LF-0,5%,1/16W,CHIP,CS00002JB13",0,5%,R0402,9472.31,6141.50,0.000,NO,,,
R1654,"Q_RES_0402LF-1K,1%,1/16W,CHIP,CS21002FB06",1K,1%,R0402,5846.42,4319.76,180.000,NO,,,
R1655,"Q_RES_0402LF-1K,1%,1/16W,EMPTY,CS21002FB06",1K,1%,R0402,9900.56,5260.74,0.000,NO,,,
R1658,"Q_RES_0402LF-4.7K,5%,1/16W,CHIP,CS24702JB10",4.7K,5%,R0402,5449.88,2224.41,180.000,NO,,,
R1659,"Q_RES_0402LF-4.7K,5%,1/16W,EMPTY,CS24702JB10",4.7K,5%,R0402,5449.88,2184.41,0.000,NO,,,
R1671,"Q_RES_0402LF-0,5%,1/16W,CHIP,CS00002JB13",0,5%,R0402,17117.98,637.79,270.000,NO,,,
R1673,"Q_RES_0402LF-10K,1%,1/16W,CHIP,CS31002FB08",10K,1%,R0402,8827.15,1831.69,0.000,NO,,,
R1674,"Q_RES_0402LF-10,1%,1/16W,CHIP,CS01002FB07",10,1%,R0402,12100.05,7714.65,180.000,YES,,,
R1675,"Q_RES_0402LF-10,1%,1/16W,CHIP,CS01002FB07",10,1%,R0402,11774.35,7710.99,180.000,YES,,,
R1676,"Q_RES_0402LF-10,1%,1/16W,CHIP,CS01002FB07",10,1%,R0402,11180.34,7710.99,180.000,YES,,,
R1677,"Q_RES_0402LF-10,1%,1/16W,CHIP,CS01002FB07",10,1%,R0402,11477.35,7710.99,180.000,YES,,,
R1678,"Q_RES_0402LF-10,1%,1/16W,CHIP,CS01002FB07",10,1%,R0402,10883.33,7710.99,180.000,YES,,,
R1679,"Q_RES_0402LF-10,1%,1/16W,CHIP,CS01002FB07",10,1%,R0402,10586.32,7710.99,180.000,YES,,,
R1680,"Q_RES_0402LF-10,1%,1/16W,CHIP,CS01002FB07",10,1%,R0402,16366.63,7710.65,180.000,YES,,,
R1681,"Q_RES_0402LF-10,1%,1/16W,CHIP,CS01002FB07",10,1%,R0402,16663.64,7710.65,180.000,YES,,,
R1683,"Q_RES_0402LF-10,1%,1/16W,CHIP,CS01002FB07",10,1%,R0402,16960.65,7710.65,180.000,YES,,,
R1684,"Q_RES_0402LF-10,1%,1/16W,CHIP,CS01002FB07",10,1%,R0402,17257.66,7710.99,180.000,YES,,,
R1685,"Q_RES_0402LF-10,1%,1/16W,CHIP,CS01002FB07",10,1%,R0402,17554.66,7711.05,180.000,YES,,,
R1686,"Q_RES_0402LF-10,1%,1/16W,CHIP,CS01002FB07",10,1%,R0402,17851.67,7713.65,180.000,YES,,,
R1687,"Q_RES_0402LF-10,1%,1/16W,CHIP,CS01002FB07",10,1%,R0402,2338.63,7713.66,180.000,YES,,,
R1696,"Q_RES_0402LF-10,1%,1/16W,CHIP,CS01002FB07",10,1%,R0402,2012.62,7713.66,180.000,YES,,,
R1697,"Q_RES_0402LF-10,1%,1/16W,CHIP,CS01002FB07",10,1%,R0402,1715.62,7712.66,180.000,YES,,,
R1699,"Q_RES_0402LF-10,1%,1/16W,CHIP,CS01002FB07",10,1%,R0402,1418.92,7712.00,180.000,YES,,,
R1700,"Q_RES_0402LF-200K,1%,1/16W,CHIP,CS42002FB05",200K,1%,R0402,6213.10,1771.09,270.000,NO,,,
R1701,"Q_RES_0402LF-10,1%,1/16W,CHIP,CS01002FB07",10,1%,R0402,1120.60,7713.66,180.000,YES,,,
R1702,"Q_RES_0402LF-4.7K,5%,1/16W,CHIP,CS24702JB10",4.7K,5%,R0402,5852.03,1643.56,0.000,NO,,,
R1703,"Q_RES_0402LF-4.7K,5%,1/16W,CHIP,CS24702JB10",4.7K,5%,R0402,5852.03,1694.15,0.000,NO,,,
R1704,"Q_RES_0402LF-10,1%,1/16W,CHIP,CS01002FB07",10,1%,R0402,823.59,7713.66,180.000,YES,,,
R1705,"Q_RES_0402LF-10,1%,1/16W,CHIP,CS01002FB07",10,1%,R0402,6605.22,7711.00,180.000,YES,,,
R1707,"Q_RES_0402LF-10,1%,1/16W,CHIP,CS01002FB07",10,1%,R0402,6902.23,7711.00,180.000,YES,,,
R1708,"Q_RES_0402LF-10,1%,1/16W,CHIP,CS01002FB07",10,1%,R0402,7199.24,7711.00,180.000,YES,,,
R1709,"Q_RES_0402LF-10,1%,1/16W,CHIP,CS01002FB07",10,1%,R0402,7496.24,7711.00,180.000,YES,,,
R1710,"Q_RES_0402LF-10,1%,1/16W,CHIP,CS01002FB07",10,1%,R0402,7793.25,7711.00,180.000,YES,,,
R1711,"Q_RES_0402LF-10,1%,1/16W,CHIP,CS01002FB07",10,1%,R0402,8118.95,7714.65,0.000,YES,,,
R1714,"Q_RES_0402LF-0,5%,1/16W,CHIP,CS00002JB13",0,5%,R0402,7140.90,16020.43,90.000,YES,,,
R1719,"Q_RES_0402LF-33.2,1%,1/16W,CHIP,CS03322FB03",33.2,1%,R0402,17937.71,3904.11,0.000,NO,,,
R1727,"Q_RES_0402LF-10K,1%,1/16W,EMPTY,CS31002FB08",10K,1%,R0402,4960.34,2381.19,0.000,NO,,,
R1728,"Q_RES_0402LF-10K,1%,1/16W,EMPTY,CS31002FB08",10K,1%,R0402,5449.88,2355.60,180.000,NO,,,
R1729,"Q_RES_0402LF-4.7K,5%,1/16W,CHIP,CS24702JB10",4.7K,5%,R0402,4579.31,2166.78,270.000,NO,,,
R1730,"Q_RES_0402LF-4.7K,5%,1/16W,EMPTY,CS24702JB10",4.7K,5%,R0402,4619.31,2166.78,90.000,NO,,,
R1731,"Q_RES_0402LF-10K,1%,1/16W,EMPTY,CS31002FB08",10K,1%,R0402,4159.40,2354.42,0.000,NO,,,
R1734,"Q_RES_0402LF-10K,1%,1/16W,CHIP,CS31002FB08",10K,1%,R0402,4673.96,2357.64,180.000,NO,,,
R1735,"Q_RES_0402LF-10K,1%,1/16W,EMPTY,CS31002FB08",10K,1%,R0402,4673.96,2317.64,0.000,NO,,,
R1736,"Q_RES_0402LF-0,5%,1/16W,CHIP,CS00002JB13",0,5%,R0402,4673.96,2397.64,0.000,NO,,,
R1737,"Q_RES_0402LF-0,5%,1/16W,CHIP,CS00002JB13",0,5%,R0402,4159.40,2303.23,180.000,NO,,,
R1738,"Q_RES_0402LF-0,5%,1/16W,CHIP,CS00002JB13",0,5%,R0402,5449.88,2395.66,0.000,NO,,,
R1739,"Q_RES_0402LF-0,5%,1/16W,CHIP,CS00002JB13",0,5%,R0402,4960.34,2330.00,180.000,NO,,,
R1740,"Q_RES_0402LF-22,1%,1/16W,CHIP,CS02202FB02",22,1%,R0402,4673.96,2277.64,0.000,NO,,,
R1741,"Q_RES_0402LF-22,1%,1/16W,CHIP,CS02202FB02",22,1%,R0402,4159.40,2405.01,180.000,NO,,,
R1742,"Q_RES_0402LF-22,1%,1/16W,CHIP,CS02202FB02",22,1%,R0402,5449.88,2304.41,0.000,NO,,,
R1743,"Q_RES_0402LF-22,1%,1/16W,CHIP,CS02202FB02",22,1%,R0402,4960.34,2431.78,180.000,NO,,,
R1744,"Q_RES_0402LF-10K,1%,1/16W,CHIP,CS31002FB08",10K,1%,R0402,5529.38,2395.66,180.000,NO,,,
R1745,"Q_RES_0402LF-10K,1%,1/16W,CHIP,CS31002FB08",10K,1%,R0402,4876.84,2330.00,0.000,NO,,,
R1746,"Q_RES_0402LF-10K,1%,1/16W,CHIP,CS31002FB08",10K,1%,R0402,4159.40,2263.23,180.000,NO,,,
R1747,"Q_RES_0402LF-10K,1%,1/16W,CHIP,CS31002FB08",10K,1%,R0402,4673.96,2477.64,0.000,NO,,,
R1748,"Q_RES_0402LF-10K,1%,1/16W,EMPTY,CS31002FB08",10K,1%,R0402,4673.96,2437.64,180.000,NO,,,
R1775,"Q_RES_0402LF-1K,1%,1/16W,CHIP,CS21002FB06",1K,1%,R0402,12037.56,1338.66,0.000,NO,,,
R1776,"Q_RES_0402LF-1K,1%,1/16W,CHIP,CS21002FB06",1K,1%,R0402,11874.88,911.25,0.000,NO,,,
R1777,"Q_RES_0402LF-1K,1%,1/16W,CHIP,CS21002FB06",1K,1%,R0402,11811.91,958.64,0.000,NO,,,
R1779,"Q_RES_0402LF-100,1%,1/16W,CHIP,CS11002FB07",100,1%,R0402,11954.88,895.50,90.000,NO,,,
R1785,"Q_RES_0402LF-4.7K,1%,1/16W,CHIP,CS24702FB06",4.7K,1%,R0402,12881.07,1620.51,0.000,NO,,,
R1791,"Q_RES_0402LF-9.09K,1%,1/16W,CHIP,CS29092FB05",9.09K,1%,R0402,12881.07,1715.51,0.000,NO,,,
R1792,"Q_RES_0402LF-0,5%,1/16W,EMPTY,CS00002JB13",0,5%,R0402,12966.93,1417.39,180.000,NO,,,
R1793,"Q_RES_0402LF-0,5%,1/16W,EMPTY,CS00002JB13",0,5%,R0402,12966.93,1377.39,180.000,NO,,,
R1798,"Q_RES_0402LF-0,5%,1/16W,CHIP,CS00002JB13",0,5%,R0402,5499.19,356.62,270.000,YES,,,
R1799,"Q_RES_0402LF-7.87K,1%,1/16W,CHIP,CS27872FB02",7.87K,1%,R0402,12976.07,1840.51,180.000,NO,,,
R1800,"Q_RES_0402LF-1.21K,1%,1/16W,CHIP,CS21212FB05",1.21K,1%,R0402,12881.07,1840.51,0.000,NO,,,
R1801,"Q_RES_0402LF-0,5%,1/16W,CHIP,CS00002JB13",0,5%,R0402,7506.63,760.29,180.000,YES,,,
R1815,"Q_RES_0402LF-0,5%,1/16W,CHIP,CS00002JB13",0,5%,R0402,5642.00,541.82,90.000,YES,,,
R1816,"Q_RES_0402LF-0,5%,1/16W,CHIP,CS00002JB13",0,5%,R0402,5722.00,541.82,90.000,YES,,,
R1822,"Q_RES_0402LF-10K,1%,1/16W,CHIP,CS31002FB08",10K,1%,R0402,10919.38,4846.05,0.000,NO,,,
R1824,"Q_RES_0402LF-10K,1%,1/16W,CHIP,CS31002FB08",10K,1%,R0402,17913.90,1468.34,0.000,NO,,,
R1837,"Q_RES_4P_12-0.001,1%,3W,SMLF,CHIP,SP_CS+001DFR10",,,R2512_4P_H41,507.73,7652.25,270.000,NO,,,
R1838,"Q_RES_4P_12-0.001,1%,3W,SMLF,CHIP,SP_CS+001DFR10",,,R2512_4P_H41,17750.29,7090.79,180.000,NO,,,
R1854,"Q_RES_0402LF-1K,1%,1/16W,CHIP,CS21002FB06",1K,1%,R0402,7472.45,1378.64,180.000,NO,,,
R1856,"Q_RES_0402LF-100,1%,1/16W,CHIP,CS11002FB07",100,1%,R0402,7472.35,1420.50,0.000,NO,,,
R1857,"Q_RES_0402LF-10K,1%,1/16W,CHIP,CS31002FB08",10K,1%,R0402,7763.03,1537.28,0.000,NO,,,
R1895,"Q_RES_0402LF-0,5%,1/16W,CHIP,CS00002JB13",0,5%,R0402,17131.73,327.44,270.000,YES,,,
R1896,"Q_RES_0402LF-100,1%,1/16W,CHIP,CS11002FB07",100,1%,R0402,17244.62,751.05,270.000,YES,,,
R1897,"Q_RES_0402LF-100,1%,1/16W,CHIP,CS11002FB07",100,1%,R0402,17127.99,1058.52,90.000,YES,,,
R1898,"Q_RES_0402LF-100,1%,1/16W,CHIP,CS11002FB07",100,1%,R0402,17204.62,751.05,270.000,YES,,,
R1905,"Q_RES_0402LF-1K,1%,1/16W,CHIP,CS21002FB06",1K,1%,R0402,17862.99,4254.32,0.000,NO,,,
R1906,"Q_RES_0402LF-1K,1%,1/16W,CHIP,CS21002FB06",1K,1%,R0402,17862.99,4104.32,0.000,NO,,,
R1907,"Q_RES_0402LF-1K,1%,1/16W,CHIP,CS21002FB06",1K,1%,R0402,17862.99,4189.32,0.000,NO,,,
R1908,"Q_RES_0402LF-1K,1%,1/16W,CHIP,CS21002FB06",1K,1%,R0402,17862.99,4039.32,0.000,NO,,,
R1929,"Q_RES_0402LF-10K,1%,1/16W,CHIP,CS31002FB08",10K,1%,R0402,17117.98,772.67,270.000,NO,,,
R1930,"Q_RES_0402LF-10K,1%,1/16W,CHIP,CS31002FB08",10K,1%,R0402,17916.72,515.86,90.000,YES,,,
R2113,"Q_RES_0402LF-0,5%,1/16W,CHIP,CS00002JB13",0,5%,R0402,5546.73,4035.86,180.000,NO,,,
R2114,"Q_RES_0402LF-0,5%,1/16W,CHIP,CS00002JB13",0,5%,R0402,10168.34,2873.11,0.000,NO,,,
R2121,"Q_RES_0402LF-4.7K,5%,1/16W,CHIP,CS24702JB10",4.7K,5%,R0402,5546.73,3995.86,0.000,NO,,,
R2125,"Q_RES_0402LF-4.7K,5%,1/16W,CHIP,CS24702JB10",4.7K,5%,R0402,10294.04,2873.11,180.000,NO,,,
R2204,"Q_RES_0402LF-2.2K,5%,1/16W,EMPTY,CS22202JB07",2.2K,5%,R0402,6562.86,354.86,270.000,YES,,,
R2205,"Q_RES_0402LF-2.2K,5%,1/16W,EMPTY,CS22202JB07",2.2K,5%,R0402,6431.46,354.86,270.000,YES,,,
R2212,"Q_RES_0402LF-2.2K,5%,1/16W,EMPTY,CS22202JB07",2.2K,5%,R0402,5944.44,696.61,270.000,YES,,,
R2213,"Q_RES_0402LF-2.2K,5%,1/16W,EMPTY,CS22202JB07",2.2K,5%,R0402,5894.44,696.61,270.000,YES,,,
R2219,"Q_RES_0402LF-267K,1%,1/16W,EMPTY,CS42672FB03",267K,1%,R0402,6314.09,4688.56,180.000,NO,,,
R2221,"Q_RES_0402LF-26.7K,1%,1/16W,EMPTY,CS32672FB03",26.7K,1%,R0402,5920.03,4688.93,0.000,NO,,,
R2222,"Q_RES_0402LF-1K,1%,1/16W,EMPTY,CS21002FB06",1K,1%,R0402,5920.03,4743.53,180.000,NO,,,
R2227,"Q_RES_0402LF-10K,1%,1/16W,EMPTY,CS31002FB08",10K,1%,R0402,6314.21,4740.20,0.000,NO,,,
R2230,"Q_RES_0402LF-10K,1%,1/16W,EMPTY,CS31002FB08",10K,1%,R0402,5921.27,4584.61,0.000,NO,,,
R2233,"Q_RES_0402LF-1K,1%,1/16W,EMPTY,CS21002FB06",1K,1%,R0402,6316.59,4614.41,180.000,NO,,,
R2261,"Q_RES_0402LF-33.2,1%,1/16W,CHIP,CS03322FB03",33.2,1%,R0402,7715.00,3948.62,90.000,NO,,,
R2262,"Q_RES_0402LF-33.2,1%,1/16W,CHIP,CS03322FB03",33.2,1%,R0402,8225.46,4392.79,180.000,NO,,,
R2268,"Q_RES_0402LF-0,5%,1/16W,CHIP,CS00002JB13",0,5%,R0402,11004.48,4793.55,0.000,NO,,,
R2310,"Q_RES_0402LF-0,5%,1/16W,EMPTY,CS00002JB13",0,5%,R0402,12637.06,7562.90,270.000,NO,,,
R2311,"Q_RES_0402LF-0,5%,1/16W,EMPTY,CS00002JB13",0,5%,R0402,12567.85,7562.90,270.000,NO,,,
R2316,"Q_RES_0402LF-0,5%,1/16W,CHIP,CS00002JB13",0,5%,R0402,16120.65,5387.23,180.000,NO,,,
R2317,"Q_RES_0402LF-10K,1%,1/16W,CHIP,CS31002FB08",10K,1%,R0402,9429.45,1850.52,180.000,NO,,,
R2318,"Q_RES_0402LF-0,5%,1/16W,CHIP,CS00002JB13",0,5%,R0402,13351.77,12039.88,0.000,YES,,,
R2343,"Q_RES_0402LF-10K,1%,1/16W,EMPTY,CS31002FB08",10K,1%,R0402,16002.99,5312.26,180.000,NO,,,
R2344,"Q_RES_0402LF-4.7K,5%,1/16W,CHIP,CS24702JB10",4.7K,5%,R0402,15716.43,5312.20,0.000,NO,,,
R2346,"Q_RES_0402LF-100K,1%,1/16W,CHIP,CS41002FB09",100K,1%,R0402,16002.99,5363.44,180.000,NO,,,
R2356,"Q_RES_0402LF-10K,1%,1/16W,CHIP,CS31002FB08",10K,1%,R0402,16203.79,5489.35,90.000,YES,,,
R2410,"Q_RES_0402LF-33.2,1%,1/16W,CHIP,CS03322FB03",33.2,1%,R0402,5760.03,1643.56,180.000,NO,,,
R2411,"Q_RES_0402LF-33.2,1%,1/16W,CHIP,CS03322FB03",33.2,1%,R0402,5760.03,1694.15,180.000,NO,,,
R2413,"Q_RES_0402LF-33.2,1%,1/16W,CHIP,CS03322FB03",33.2,1%,R0402,6148.45,541.82,90.000,YES,,,
R2414,"Q_RES_0402LF-33.2,1%,1/16W,CHIP,CS03322FB03",33.2,1%,R0402,6102.85,541.82,90.000,YES,,,
R2415,"Q_RES_0402LF-33.2,1%,1/16W,CHIP,CS03322FB03",33.2,1%,R0402,6063.30,541.82,90.000,YES,,,
R2416,"Q_RES_0402LF-33.2,1%,1/16W,CHIP,CS03322FB03",33.2,1%,R0402,6023.50,541.82,90.000,YES,,,
R2417,"Q_RES_0402LF-33.2,1%,1/16W,CHIP,CS03322FB03",33.2,1%,R0402,5944.05,541.82,90.000,YES,,,
R2418,"Q_RES_0402LF-33.2,1%,1/16W,CHIP,CS03322FB03",33.2,1%,R0402,5900.97,541.82,90.000,YES,,,
R2419,"Q_RES_0402LF-33.2,1%,1/16W,CHIP,CS03322FB03",33.2,1%,R0402,7160.33,802.29,90.000,YES,,,
R2420,"Q_RES_0402LF-33.2,1%,1/16W,CHIP,CS03322FB03",33.2,1%,R0402,7120.43,802.29,90.000,YES,,,
R2421,"Q_RES_0402LF-33.2,1%,1/16W,CHIP,CS03322FB03",33.2,1%,R0402,6978.93,399.50,270.000,YES,,,
R2422,"Q_RES_0402LF-33.2,1%,1/16W,CHIP,CS03322FB03",33.2,1%,R0402,6924.66,399.50,270.000,YES,,,
R2423,"Q_RES_0402LF-33.2,1%,1/16W,CHIP,CS03322FB03",33.2,1%,R0402,6492.22,537.60,90.000,YES,,,
R2424,"Q_RES_0402LF-33.2,1%,1/16W,CHIP,CS03322FB03",33.2,1%,R0402,6452.22,537.60,90.000,YES,,,
R2425,"Q_RES_0402LF-33.2,1%,1/16W,CHIP,CS03322FB03",33.2,1%,R0402,6858.38,317.20,270.000,YES,,,
R2426,"Q_RES_0402LF-100,1%,1/16W,EMPTY,CS11002FB07",100,1%,R0402,8827.25,1920.55,180.000,NO,,,
R2473,"Q_RES_0402LF-0,5%,1/16W,CHIP,CS00002JB13",0,5%,R0402,18246.69,3839.52,0.000,NO,,,
R2474,"Q_RES_0402LF-0,5%,1/16W,EMPTY,CS00002JB13",0,5%,R0402,18246.69,3795.52,0.000,NO,,,
R2476,"Q_RES_0402LF-200K,1%,1/16W,EMPTY,CS42002FB05",200K,1%,R0402,6253.10,1771.09,90.000,NO,,,
R2487,"Q_RES_0402LF-4.7K,1%,1/16W,EMPTY,CS24702FB06",4.7K,1%,R0402,6423.01,1515.51,270.000,NO,,,
R2488,"Q_RES_0402LF-4.7K,1%,1/16W,CHIP,CS24702FB06",4.7K,1%,R0402,18235.80,1518.34,180.000,NO,,,
R2489,"Q_RES_0402LF-33.2,1%,1/16W,CHIP,CS03322FB03",33.2,1%,R0402,6462.31,1515.51,90.000,NO,,,
R2528,"Q_RES_0402LF-100K,1%,1/16W,CHIP,CS41002FB09",100K,1%,R0402,8097.08,5414.48,0.000,NO,,,
R2529,"Q_RES_0402LF-0,5%,1/16W,CHIP,CS00002JB13",0,5%,R0402,8098.17,5634.37,90.000,NO,,,
R2530,"Q_RES_0402LF-4.7K,5%,1/16W,CHIP,CS24702JB10",4.7K,5%,R0402,8347.50,5677.22,270.000,NO,,,
R2531,"Q_RES_0402LF-0,5%,1/16W,CHIP,CS00002JB13",0,5%,R0402,8419.00,5437.97,270.000,NO,,,
R2565,"Q_RES_0402LF-0,5%,1/16W,CHIP,CS00002JB13",0,5%,R0402,11591.38,4616.91,0.000,NO,,,
R2566,"Q_RES_0402LF-0,5%,1/16W,CHIP,CS00002JB13",0,5%,R0402,11591.38,4576.91,0.000,NO,,,
R2585,"Q_RES_0402LF-31.6K,1%,1/16W,CHIP,CS33162FB02",31.6K,1%,R0402,10680.94,16494.95,90.000,NO,,,
R2586,"Q_RES_0402LF-0,5%,1/16W,CHIP,CS00002JB13",0,5%,R0402,7257.50,15663.33,180.000,NO,,,
R2587,"Q_RES_0402LF-1K,1%,1/16W,CHIP,CS21002FB06",1K,1%,R0402,7530.10,15855.98,90.000,YES,,,
R2588,"Q_RES_0402LF-22,1%,1/16W,CHIP,CS02202FB02",22,1%,R0402,7536.10,15840.23,0.000,NO,,,
R2624,"Q_RES_0402LF-49.9,1%,1/16W,CHIP,CS04992FB07",49.9,1%,R0402,11210.10,15903.98,270.000,NO,,,
R2625,"Q_RES_0402LF-49.9,1%,1/16W,CHIP,CS04992FB07",49.9,1%,R0402,11250.10,15903.98,270.000,NO,,,
R2626,"Q_RES_0402LF-0,5%,1/16W,CHIP,CS00002JB13",0,5%,R0402,11141.17,15373.80,270.000,NO,,,
R2627,"Q_RES_0402LF-0,5%,1/16W,CHIP,CS00002JB13",0,5%,R0402,11087.47,15373.80,270.000,NO,,,
R2628,"Q_RES_0402LF-0,5%,1/16W,CHIP,CS00002JB13",0,5%,R0402,11095.22,15529.33,270.000,NO,,,
R2656,"Q_RES_0402LF-100,1%,1/16W,EMPTY,CS11002FB07",100,1%,R0402,4161.23,16221.80,90.000,YES,,,
R2659,"Q_RES_0402LF-0,5%,1/16W,CHIP,CS00002JB13",0,5%,R0402,14425.32,12767.60,90.000,NO,,,
R2660,"Q_RES_0402LF-0,5%,1/16W,CHIP,CS00002JB13",0,5%,R0402,14385.32,12767.60,90.000,NO,,,
R2663,"Q_RES_0402LF-33.2,1%,1/16W,CHIP,CS03322FB03",33.2,1%,R0402,8080.02,4913.44,0.000,NO,,,
R2664,"Q_RES_0402LF-33.2,1%,1/16W,CHIP,CS03322FB03",33.2,1%,R0402,8223.58,4713.44,0.000,NO,,,
R2666,"Q_RES_0402LF-10K,1%,1/16W,CHIP,CS31002FB08",10K,1%,R0402,11305.09,16860.65,0.000,YES,,,
R2667,"Q_RES_0402LF-2.2K,5%,1/16W,CHIP,CS22202JB07",2.2K,5%,R0402,6568.00,16928.00,90.000,NO,,,
R2668,"Q_RES_0402LF-4.7K,5%,1/16W,EMPTY,CS24702JB10",4.7K,5%,R0402,11520.00,16775.00,270.000,YES,,,
R2669,"Q_RES_0402LF-2.2K,5%,1/16W,CHIP,CS22202JB07",2.2K,5%,R0402,6640.00,17120.84,180.000,NO,,,
R2670,"Q_RES_0402LF-4.7K,5%,1/16W,EMPTY,CS24702JB10",4.7K,5%,R0402,11260.00,16770.00,270.000,YES,,,
R2671,"Q_RES_0402LF-33.2,1%,1/16W,CHIP,CS03322FB03",33.2,1%,R0402,6548.00,16984.00,0.000,NO,,,
R2672,"Q_RES_0402LF-33.2,1%,1/16W,CHIP,CS03322FB03",33.2,1%,R0402,6640.00,17081.84,0.000,NO,,,
R2674,"Q_RES_0402LF-27,5%,1/16W,CHIP,CS02702JB02",27,5%,R0402,11415.00,16790.00,0.000,YES,,,
R2675,"Q_RES_0402LF-33.2,1%,1/16W,CHIP,CS03322FB03",33.2,1%,R0402,11350.00,16790.00,180.000,YES,,,
R2676,"Q_RES_0402LF-0,5%,1/16W,CHIP,CS00002JB13",0,5%,R0402,11305.09,16825.65,0.000,YES,,,
R2693,"Q_RES_0402LF-1K,1%,1/16W,EMPTY,CS21002FB06",1K,1%,R0402,6997.99,16291.93,90.000,NO,,,
R2694,"Q_RES_0402LF-1K,1%,1/16W,CHIP,CS21002FB06",1K,1%,R0402,7037.99,16291.93,270.000,NO,,,
R2695,"Q_RES_0402LF-1K,1%,1/16W,EMPTY,CS21002FB06",1K,1%,R0402,6983.39,16784.74,0.000,NO,,,
R2696,"Q_RES_0402LF-1K,1%,1/16W,CHIP,CS21002FB06",1K,1%,R0402,6983.39,16819.96,180.000,NO,,,
R2703,"Q_RES_0402LF-0,5%,1/16W,CHIP,CS00002JB13",0,5%,R0402,11591.38,4536.91,0.000,NO,,,
R2704,"Q_RES_0402LF-0,5%,1/16W,CHIP,CS00002JB13",0,5%,R0402,11591.38,4496.91,0.000,NO,,,
R2705,"Q_RES_0402LF-0,5%,1/16W,EMPTY,CS00002JB13",0,5%,R0402,6528.00,16928.00,90.000,NO,,,
R2706,"Q_RES_0402LF-0,5%,1/16W,CHIP,CS00002JB13",0,5%,R0402,11479.47,16774.05,270.000,YES,,,
R2707,"Q_RES_0402LF-0,5%,1/16W,CHIP,CS00002JB13",0,5%,R0402,6548.00,17024.00,180.000,NO,,,
R2724,"Q_RES_0402LF-0,5%,1/16W,EMPTY,CS00002JB13",0,5%,R0402,6548.00,17120.84,0.000,NO,,,
R2725,"Q_RES_0402LF-0,5%,1/16W,CHIP,CS00002JB13",0,5%,R0402,11295.00,16770.00,270.000,YES,,,
R2786,"Q_RES_0402LF-0,5%,1/16W,CHIP,CS00002JB13",0,5%,R0402,449.67,4152.85,90.000,NO,,,
R2787,"Q_RES_0402LF-0,5%,1/16W,CHIP,CS00002JB13",0,5%,R0402,503.39,4153.70,90.000,NO,,,
R2788,"Q_RES_0402LF-0,5%,1/16W,EMPTY,CS00002JB13",0,5%,R0402,449.67,4184.35,270.000,NO,,,
R2789,"Q_RES_0402LF-0,5%,1/16W,EMPTY,CS00002JB13",0,5%,R0402,503.39,4185.20,270.000,NO,,,
R2790,"Q_RES_0402LF-0,5%,1/16W,EMPTY,CS00002JB13",0,5%,R0402,601.89,4154.95,90.000,NO,,,
R2791,"Q_RES_0402LF-0,5%,1/16W,EMPTY,CS00002JB13",0,5%,R0402,655.33,4156.15,90.000,NO,,,
R2793,"Q_RES_0402LF-0,5%,1/16W,CHIP,CS00002JB13",0,5%,R0402,7586.62,16933.69,0.000,NO,,,
R2794,"Q_RES_0402LF-4.7K,5%,1/16W,CHIP,CS24702JB10",4.7K,5%,R0402,7521.87,16764.94,270.000,NO,,,
R2796,"Q_RES_0402LF-0,5%,1/16W,CHIP,CS00002JB13",0,5%,R0402,7270.91,16529.97,0.000,YES,,,
R2800,"Q_RES_0402LF-0,5%,1/16W,EMPTY,CS00002JB13",0,5%,R0402,7174.22,16473.37,270.000,YES,,,
R2801,"Q_RES_0402LF-0,5%,1/16W,EMPTY,CS00002JB13",0,5%,R0402,6833.98,16486.50,270.000,YES,,,
R2802,"Q_RES_0402LF-0,5%,1/16W,CHIP,CS00002JB13",0,5%,R0402,9277.98,16647.62,90.000,YES,,,
R2803,"Q_RES_0402LF-0,5%,1/16W,CHIP,CS00002JB13",0,5%,R0402,9517.98,16647.62,90.000,YES,,,
R2805,"Q_RES_0402LF-4.7K,5%,1/16W,EMPTY,CS24702JB10",4.7K,5%,R0402,7270.91,16479.97,0.000,YES,,,
R2807,"Q_RES_0402LF-4.7K,5%,1/16W,EMPTY,CS24702JB10",4.7K,5%,R0402,6783.97,16504.19,180.000,YES,,,
R2811,"Q_RES_0402LF-33.2,1%,1/16W,CHIP,CS03322FB03",33.2,1%,R0402,7270.91,16439.97,180.000,YES,,,
R2812,"Q_RES_0402LF-33.2,1%,1/16W,CHIP,CS03322FB03",33.2,1%,R0402,6783.97,16464.19,0.000,YES,,,
R2815,"Q_RES_0402LF-100K,1%,1/16W,EMPTY,CS41002FB09",100K,1%,R0402,6789.61,16330.42,180.000,YES,,,
R2820,"Q_RES_0402LF-4.7K,5%,1/16W,EMPTY,CS24702JB10",4.7K,5%,R0402,7133.17,16257.86,90.000,YES,,,
R2828,"Q_RES_0402LF-100K,1%,1/16W,CHIP,CS41002FB09",100K,1%,R0402,16545.13,17323.34,270.000,NO,,,
R2829,"Q_RES_0402LF-100K,1%,1/16W,EMPTY,CS41002FB09",100K,1%,R0402,16505.13,17323.34,90.000,NO,,,
R2830,"Q_RES_0402LF-100K,1%,1/16W,CHIP,CS41002FB09",100K,1%,R0402,6434.00,17330.00,0.000,NO,,,
R2831,"Q_RES_0402LF-100K,1%,1/16W,EMPTY,CS41002FB09",100K,1%,R0402,6504.00,17330.00,0.000,NO,,,
R2832,"Q_RES_0402LF-100K,1%,1/16W,CHIP,CS41002FB09",100K,1%,R0402,16895.13,17171.84,270.000,NO,,,
R2833,"Q_RES_0402LF-100K,1%,1/16W,EMPTY,CS41002FB09",100K,1%,R0402,16855.13,17171.84,90.000,NO,,,
R2834,"Q_RES_0402LF-4.7K,5%,1/16W,CHIP,CS24702JB10",4.7K,5%,R0402,16753.60,17252.52,90.000,NO,,,
R2835,"Q_RES_0402LF-4.7K,5%,1/16W,CHIP,CS24702JB10",4.7K,5%,R0402,6731.13,17312.61,90.000,NO,,,
R2836,"Q_RES_0402LF-4.7K,5%,1/16W,CHIP,CS24702JB10",4.7K,5%,R0402,17103.60,17105.02,90.000,NO,,,
R2837,"Q_RES_0402LF-100K,1%,1/16W,EMPTY,CS41002FB09",100K,1%,R0402,14083.89,16497.20,180.000,YES,,,
R2838,"Q_RES_0402LF-100K,1%,1/16W,CHIP,CS41002FB09",100K,1%,R0402,14155.11,16497.16,180.000,YES,,,
R2841,"Q_RES_0402LF-4.7K,5%,1/16W,CHIP,CS24702JB10",4.7K,5%,R0402,13969.01,16560.08,90.000,YES,,,
R2842,"Q_RES_0402LF-4.7K,5%,1/16W,CHIP,CS24702JB10",4.7K,5%,R0402,1828.13,16704.96,270.000,YES,,,
R2843,"Q_RES_0402LF-4.7K,1%,1/16W,CHIP,CS24702FB06",4.7K,1%,R0402,12881.07,1660.51,0.000,NO,,,
R2844,"Q_RES_0402LF-33.2,1%,1/16W,CHIP,CS03322FB03",33.2,1%,R0402,8079.33,4873.44,0.000,NO,,,
R2845,"Q_RES_0402LF-33.2,1%,1/16W,CHIP,CS03322FB03",33.2,1%,R0402,8224.19,4356.28,180.000,NO,,,
R2846,"Q_RES_0402LF-33.2,1%,1/16W,CHIP,CS03322FB03",33.2,1%,R0402,7874.93,4875.24,180.000,YES,,,
R2847,"Q_RES_0402LF-33.2,1%,1/16W,CHIP,CS03322FB03",33.2,1%,R0402,7766.52,4993.44,0.000,NO,,,
R2848,"Q_RES_0402LF-0,5%,1/16W,CHIP,CS00002JB13",0,5%,R0402,7247.23,16285.20,270.000,NO,,,
R2893,"Q_RES_0402LF-0,5%,1/16W,EMPTY,CS00002JB13",0,5%,R0402,925.00,17004.50,90.000,NO,,,
R2894,"Q_RES_0402LF-0,5%,1/16W,EMPTY,CS00002JB13",0,5%,R0402,1324.20,17030.11,90.000,NO,,,
R2897,"Q_RES_0402LF-33.2,1%,1/16W,CHIP,CS03322FB03",33.2,1%,R0402,869.20,17065.11,180.000,NO,,,
R2898,"Q_RES_0402LF-33.2,1%,1/16W,CHIP,CS03322FB03",33.2,1%,R0402,1383.18,17091.66,0.000,NO,,,
R2899,"Q_RES_0402LF-0,5%,1/16W,CHIP,CS00002JB13",0,5%,R0402,1090.00,17124.50,180.000,NO,,,
R2900,"Q_RES_0402LF-2K,1%,1/16W,CHIP,CS22002FB07",2K,1%,R0402,12431.93,1452.39,0.000,NO,,,
R2905,"Q_RES_0402LF-0,5%,1/16W,CHIP,CS00002JB13",0,5%,R0402,9437.98,16647.62,270.000,YES,,,
R2906,"Q_RES_0402LF-0,5%,1/16W,CHIP,CS00002JB13",0,5%,R0402,9357.98,16647.62,90.000,YES,,,
R2907,"Q_RES_0402LF-5.11K,1%,1/16W,CHIP,CS25112FB04",5.11K,1%,R0402,12976.07,1620.51,180.000,NO,,,
R2908,"Q_RES_0402LF-5.11K,1%,1/16W,CHIP,CS25112FB04",5.11K,1%,R0402,12976.07,1660.51,180.000,NO,,,
R2909,"Q_RES_0402LF-4.7K,5%,1/16W,CHIP,CS24702JB10",4.7K,5%,R0402,6789.61,16370.42,180.000,YES,,,
R2910,"Q_RES_0402LF-100K,1%,1/16W,EMPTY,CS41002FB09",100K,1%,R0402,1499.00,17213.66,270.000,NO,,,
R2911,"Q_RES_0402LF-4.7K,5%,1/16W,EMPTY,CS24702JB10",4.7K,5%,R0402,7133.17,16362.86,270.000,YES,,,
R2912,"Q_RES_0402LF-4.7K,5%,1/16W,EMPTY,CS24702JB10",4.7K,5%,R0402,1857.60,17273.76,270.000,NO,,,
R2914,"Q_RES_0402LF-4.7K,5%,1/16W,EMPTY,CS24702JB10",4.7K,5%,R0402,1587.40,17090.00,90.000,NO,,,
R2915,"Q_RES_0402LF-4.7K,5%,1/16W,CHIP,CS24702JB10",4.7K,5%,R0402,6789.61,16290.42,0.000,YES,,,
R2916,"Q_RES_0402LF-4.7K,5%,1/16W,EMPTY,CS24702JB10",4.7K,5%,R0402,6789.61,16420.42,0.000,YES,,,
R2917,"Q_RES_0402LF-49.9,1%,1/16W,CHIP,CS04992FB07",49.9,1%,R0402,7196.92,16289.11,180.000,YES,,,
R2918,"Q_RES_0402LF-4.7K,5%,1/16W,CHIP,CS24702JB10",4.7K,5%,R0402,1499.00,17143.66,270.000,NO,,,
R2919,"Q_RES_0402LF-100K,1%,1/16W,CHIP,CS41002FB09",100K,1%,R0402,16505.13,17253.34,90.000,NO,,,
R2920,"Q_RES_0402LF-100K,1%,1/16W,CHIP,CS41002FB09",100K,1%,R0402,6434.00,17280.00,0.000,NO,,,
R2921,"Q_RES_0402LF-10K,1%,1/16W,EMPTY,CS31002FB08",10K,1%,R0402,7191.52,16290.81,270.000,NO,,,
R2922,"Q_RES_0402LF-0,5%,1/16W,CHIP,CS00002JB13",0,5%,R0402,7151.52,16290.81,90.000,NO,,,
R2923,"Q_RES_0402LF-4.7K,5%,1/16W,EMPTY,CS24702JB10",4.7K,5%,R0402,6960.30,16292.77,90.000,NO,,,
R2924,"Q_RES_0402LF-49.9,1%,1/16W,CHIP,CS04992FB07",49.9,1%,R0402,7196.92,16329.61,180.000,YES,,,
R2925,"Q_RES_0402LF-49.9,1%,1/16W,CHIP,CS04992FB07",49.9,1%,R0402,1897.60,17273.76,90.000,NO,,,
R2926,"Q_RES_0402LF-4.7K,5%,1/16W,CHIP,CS24702JB10",4.7K,5%,R0402,7093.17,16257.86,270.000,YES,,,
R2927,"Q_RES_0402LF-100K,1%,1/16W,CHIP,CS41002FB09",100K,1%,R0402,7093.17,16362.86,90.000,YES,,,
R2932,"Q_RES_0402LF-4.7K,5%,1/16W,CHIP,CS24702JB10",4.7K,5%,R0402,1547.40,17090.00,270.000,NO,,,
R2933,"Q_RES_0402LF-100K,1%,1/16W,CHIP,CS41002FB09",100K,1%,R0402,16855.13,17101.84,90.000,NO,,,
R2934,"Q_RES_0402LF-100K,1%,1/16W,CHIP,CS41002FB09",100K,1%,R0402,14095.98,16414.05,180.000,YES,,,
R2935,"Q_RES_0402LF-100K,1%,1/16W,CHIP,CS41002FB09",100K,1%,R0402,2076.60,16701.78,270.000,YES,,,
R2936,"Q_RES_0402LF-100K,1%,1/16W,EMPTY,CS41002FB09",100K,1%,R0402,1735.00,17210.00,0.000,NO,,,
R2937,"Q_RES_0402LF-4.7K,5%,1/16W,CHIP,CS24702JB10",4.7K,5%,R0402,1735.00,17250.00,180.000,NO,,,
R2939,"Q_RES_0402LF-33.2,1%,1/16W,CHIP,CS03322FB03",33.2,1%,R0402,8224.19,4593.44,180.000,NO,,,
R2940,"Q_RES_0402LF-4.7K,5%,1/16W,EMPTY,CS24702JB10",4.7K,5%,R0402,7577.70,16297.83,90.000,NO,,,
R2941,"Q_RES_0402LF-100K,1%,1/16W,CHIP,CS41002FB09",100K,1%,R0402,7517.70,16297.83,270.000,NO,,,
R2944,"Q_RES_0402LF-33.2,1%,1/16W,CHIP,CS03322FB03",33.2,1%,R0402,7540.30,16645.83,90.000,NO,,,
R2946,"Q_RES_0402LF-4.7K,5%,1/16W,EMPTY,CS24702JB10",4.7K,5%,R0402,7580.30,16645.83,270.000,NO,,,
R2948,"Q_RES_0402LF-4.7K,5%,1/16W,EMPTY,CS24702JB10",4.7K,5%,R0402,7620.30,16645.83,90.000,NO,,,
R2950,"Q_RES_0402LF-1K,1%,1/16W,CHIP,CS21002FB06",1K,1%,R0402,7521.87,16869.94,90.000,NO,,,
R2967,"Q_RES_0402LF-0,5%,1/16W,CHIP,CS00002JB13",0,5%,R0402,11004.48,4553.55,180.000,NO,,,
R2968,"Q_RES_0402LF-0,5%,1/16W,CHIP,CS00002JB13",0,5%,R0402,11004.48,4593.55,180.000,NO,,,
R2982,"Q_RES_0402LF-0,5%,1/16W,CHIP,CS00002JB13",0,5%,R0402,6984.55,16744.29,0.000,NO,,,
R2983,"Q_RES_0402LF-0,5%,1/16W,CHIP,CS00002JB13",0,5%,R0402,6984.17,16704.08,0.000,NO,,,
R2984,"Q_RES_0402LF-2.2K,5%,1/16W,CHIP,CS22202JB07",2.2K,5%,R0402,11712.06,4478.41,180.000,NO,,,
R2985,"Q_RES_0402LF-2.2K,5%,1/16W,CHIP,CS22202JB07",2.2K,5%,R0402,11712.06,4423.41,180.000,NO,,,
R2986,"Q_RES_0402LF-0,5%,1/16W,EMPTY,CS00002JB13",0,5%,R0402,1327.67,17247.41,270.000,NO,,,
R2987,"Q_RES_0402LF-0,5%,1/16W,EMPTY,CS00002JB13",0,5%,R0402,922.57,17228.31,270.000,NO,,,
R2990,"Q_RES_0402LF-33.2,1%,1/16W,CHIP,CS03322FB03",33.2,1%,R0402,1412.67,17182.41,0.000,NO,,,
R2991,"Q_RES_0402LF-33.2,1%,1/16W,CHIP,CS03322FB03",33.2,1%,R0402,867.57,17163.31,180.000,NO,,,
R2992,"Q_RES_0402LF-0,5%,1/16W,CHIP,CS00002JB13",0,5%,R0402,1342.67,17182.41,180.000,NO,,,
R2995,"Q_RES_0402LF-33.2,1%,1/16W,CHIP,CS03322FB03",33.2,1%,R0402,6587.35,569.39,270.000,YES,,,
R2996,"Q_RES_0402LF-33.2,1%,1/16W,CHIP,CS03322FB03",33.2,1%,R0402,6494.39,647.45,180.000,YES,,,
R2999,"Q_RES_0402LF-2.2K,5%,1/16W,EMPTY,CS22202JB07",2.2K,5%,R0402,6168.15,663.43,270.000,YES,,,
R3004,"Q_RES_0402LF-2.2K,5%,1/16W,EMPTY,CS22202JB07",2.2K,5%,R0402,6103.15,663.43,270.000,YES,,,
R3005,"Q_RES_0402LF-18K,1%,1/16W,CHIP,CS31802FB04",18K,1%,R0402,12976.07,1715.51,180.000,NO,,,
R3028,"Q_RES_0402LF-100K,1%,1/16W,EMPTY,CS41002FB09",100K,1%,R0402,4530.85,16454.33,90.000,NO,,,
R3029,"Q_RES_0402LF-4.7K,5%,1/16W,CHIP,CS24702JB10",4.7K,5%,R0402,4435.94,16460.27,270.000,NO,,,
R3030,"Q_RES_0402LF-100K,1%,1/16W,CHIP,CS41002FB09",100K,1%,R0402,4570.00,16455.00,270.000,NO,,,
R3032,"Q_RES_0402LF-100K,1%,1/16W,EMPTY,CS41002FB09",100K,1%,R0402,4155.00,16535.00,0.000,YES,,,
R3033,"Q_RES_0402LF-0,5%,1/16W,CHIP,CS00002JB13",0,5%,R0402,14156.22,16117.67,90.000,NO,,,
R3034,"Q_RES_0402LF-4.7K,5%,1/16W,CHIP,CS24702JB10",4.7K,5%,R0402,4085.00,16480.00,90.000,YES,,,
R3035,"Q_RES_0402LF-100K,1%,1/16W,CHIP,CS41002FB09",100K,1%,R0402,4320.00,16450.00,270.000,YES,,,
R3036,"Q_RES_0402LF-33.2,1%,1/16W,CHIP,CS03322FB03",33.2,1%,R0402,14203.15,16429.67,0.000,NO,,,
R3047,"Q_RES_0402LF-0,5%,1/16W,CHIP,CS00002JB13",0,5%,R0402,12260.94,3011.41,270.000,YES,,,
R3048,"Q_RES_0402LF-0,5%,1/16W,CHIP,CS00002JB13",0,5%,R0402,12220.94,3011.41,270.000,YES,,,
R3062,"Q_RES_0402LF-2K,1%,1/16W,EMPTY,CS22002FB07",2K,1%,R0402,7106.66,931.33,270.000,YES,,,
R3063,"Q_RES_0402LF-0,5%,1/16W,CHIP,CS00002JB13",0,5%,R0402,14106.22,16117.67,90.000,NO,,,
R3066,"Q_RES_0402LF-33.2,1%,1/16W,CHIP,CS03322FB03",33.2,1%,R0402,8079.33,4713.44,0.000,NO,,,
R3069,"Q_RES_0402LF-130,1%,1/16W,CHIP,CS11302FB03",130,1%,R0402,12300.94,2626.33,90.000,YES,,,
R3071,"Q_RES_0402LF-130,1%,1/16W,CHIP,CS11302FB03",130,1%,R0402,12540.94,2626.33,90.000,YES,,,
R3074,"Q_RES_0402LF-130,1%,1/16W,CHIP,CS11302FB03",130,1%,R0402,12220.94,2626.33,90.000,YES,,,
R3075,"Q_RES_0402LF-130,1%,1/16W,CHIP,CS11302FB03",130,1%,R0402,12620.94,2626.33,90.000,YES,,,
R3086,"Q_RES_0402LF-130,1%,1/16W,CHIP,CS11302FB03",130,1%,R0402,12700.94,2626.33,90.000,YES,,,
R3087,"Q_RES_0402LF-130,1%,1/16W,CHIP,CS11302FB03",130,1%,R0402,12780.94,2626.33,90.000,YES,,,
R3088,"Q_RES_0402LF-130,1%,1/16W,CHIP,CS11302FB03",130,1%,R0402,12940.94,2626.33,90.000,YES,,,
R3089,"Q_RES_0402LF-130,1%,1/16W,CHIP,CS11302FB03",130,1%,R0402,12860.94,2626.33,90.000,YES,,,
R3090,"Q_RES_0402LF-130,1%,1/16W,CHIP,CS11302FB03",130,1%,R0402,13100.94,2626.33,90.000,YES,,,
R3091,"Q_RES_0402LF-130,1%,1/16W,CHIP,CS11302FB03",130,1%,R0402,13180.94,2626.33,90.000,YES,,,
R3092,"Q_RES_0402LF-130,1%,1/16W,CHIP,CS11302FB03",130,1%,R0402,13020.94,2626.33,90.000,YES,,,
R3093,"Q_RES_0402LF-130,1%,1/16W,CHIP,CS11302FB03",130,1%,R0402,13260.94,2626.33,90.000,YES,,,
R3094,"Q_RES_0402LF-130,1%,1/16W,CHIP,CS11302FB03",130,1%,R0402,13340.94,2626.33,90.000,YES,,,
R3095,"Q_RES_0402LF-130,1%,1/16W,CHIP,CS11302FB03",130,1%,R0402,13500.94,2626.33,90.000,YES,,,
R3096,"Q_RES_0402LF-130,1%,1/16W,CHIP,CS11302FB03",130,1%,R0402,13420.94,2626.33,90.000,YES,,,
R3097,"Q_RES_0402LF-130,1%,1/16W,CHIP,CS11302FB03",130,1%,R0402,13660.94,2626.33,90.000,YES,,,
R3099,"Q_RES_0402LF-130,1%,1/16W,CHIP,CS11302FB03",130,1%,R0402,13580.94,2626.33,90.000,YES,,,
R3100,"Q_RES_0402LF-130,1%,1/16W,CHIP,CS11302FB03",130,1%,R0402,12460.94,2626.33,90.000,YES,,,
R3102,"Q_RES_0402LF-470,1%,1/16W,CHIP,CS14702FB04",470,1%,R0402,12380.94,2626.33,90.000,YES,,,
R3105,"Q_RES_0402LF-0,5%,1/16W,CHIP,CS00002JB13",0,5%,R0402,6542.00,16874.00,180.000,NO,,,
R3106,"Q_RES_0402LF-0,5%,1/16W,CHIP,CS00002JB13",0,5%,R0402,6548.00,17081.84,180.000,NO,,,
R3107,"Q_RES_0402LF-0,5%,1/16W,CHIP,CS00002JB13",0,5%,R0402,1412.67,17262.41,180.000,NO,,,
R3108,"Q_RES_0402LF-0,5%,1/16W,CHIP,CS00002JB13",0,5%,R0402,867.57,17243.31,0.000,NO,,,
R3109,"Q_RES_0402LF-0,5%,1/16W,CHIP,CS00002JB13",0,5%,R0402,869.20,16985.11,0.000,NO,,,
R3110,"Q_RES_0402LF-0,5%,1/16W,CHIP,CS00002JB13",0,5%,R0402,1384.20,17010.11,180.000,NO,,,
R3111,"Q_RES_0402LF-0,5%,1/16W,CHIP,CS00002JB13",0,5%,R0402,11420.96,16739.37,180.000,YES,,,
R3112,"Q_RES_0402LF-33.2,1%,1/16W,CHIP,CS03322FB03",33.2,1%,R0402,6782.91,536.82,270.000,YES,,,
R3113,"Q_RES_0402LF-33.2,1%,1/16W,CHIP,CS03322FB03",33.2,1%,R0402,6255.95,516.82,180.000,YES,,,
R3114,"Q_RES_0402LF-33.2,1%,1/16W,CHIP,CS03322FB03",33.2,1%,R0402,6220.07,707.48,270.000,YES,,,
R3117,"Q_RES_0402LF-510K,5%,1/16W,EMPTY,CS45102JB03",510K,5%,R0402,17979.94,1810.19,270.000,YES,,,
R3118,"Q_RES_0402LF-86.6K,1%,1/16W,EMPTY,CS38662FB05",86.6K,1%,R0402,17916.45,1893.97,270.000,YES,,,
R3132,"Q_RES_0402LF-100K,1%,1/16W,CHIP,CS41002FB09",100K,1%,R0402,17876.72,515.86,90.000,YES,,,
R3133,"Q_RES_0402LF-1K,1%,1/16W,CHIP,CS21002FB06",1K,1%,R0402,383.65,3129.16,0.000,NO,,,
R3134,"Q_RES_0402LF-1K,1%,1/16W,CHIP,CS21002FB06",1K,1%,R0402,383.65,2829.16,0.000,NO,,,
R3135,"Q_RES_0402LF-1K,1%,1/16W,CHIP,CS21002FB06",1K,1%,R0402,383.65,3077.98,0.000,NO,,,
R3136,"Q_RES_0402LF-1K,1%,1/16W,CHIP,CS21002FB06",1K,1%,R0402,383.65,2777.98,0.000,NO,,,
R3142,"Q_RES_0402LF-0,5%,1/16W,CHIP,CS00002JB13",0,5%,R0402,613.55,2763.57,0.000,NO,,,
R3144,"Q_RES_0402LF-0,5%,1/16W,CHIP,CS00002JB13",0,5%,R0402,17891.63,709.87,0.000,NO,,,
R3147,"Q_RES_0402LF-1K,1%,1/16W,CHIP,CS21002FB06",1K,1%,R0402,613.55,2723.57,0.000,NO,,,
R3162,"Q_RES_0402LF-4.7K,1%,1/16W,CHIP,CS24702FB06",4.7K,1%,R0402,2827.16,443.65,270.000,YES,,,
R3163,"Q_RES_0402LF-4.7K,1%,1/16W,EMPTY,CS24702FB06",4.7K,1%,R0402,2867.16,443.65,90.000,YES,,,
R3164,"Q_RES_0402LF-10K,1%,1/16W,CHIP,CS31002FB08",10K,1%,R0402,2437.20,758.62,180.000,NO,,,
R3165,"Q_RES_0402LF-10K,1%,1/16W,CHIP,CS31002FB08",10K,1%,R0402,3077.16,443.65,270.000,YES,,,
R3166,"Q_RES_0402LF-4.7K,1%,1/16W,EMPTY,CS24702FB06",4.7K,1%,R0402,2975.20,167.37,270.000,YES,,,
R3167,"Q_RES_0402LF-4.7K,1%,1/16W,CHIP,CS24702FB06",4.7K,1%,R0402,2935.20,167.37,90.000,YES,,,
R3168,"Q_RES_0402LF-0,5%,1/16W,CHIP,CS00002JB13",0,5%,R0402,3037.20,443.62,90.000,YES,,,
R3169,"Q_RES_0402LF-0,5%,1/16W,CHIP,CS00002JB13",0,5%,R0402,2482.66,638.62,270.000,NO,,,
R3170,"Q_RES_0402LF-0,5%,1/16W,CHIP,CS00002JB13",0,5%,R0402,2442.66,638.62,270.000,NO,,,
R3171,"Q_RES_0402LF-0,5%,1/16W,CHIP,CS00002JB13",0,5%,R0402,2402.66,638.62,270.000,NO,,,
R3172,"Q_RES_0402LF-0,5%,1/16W,CHIP,CS00002JB13",0,5%,R0402,2362.66,638.62,270.000,NO,,,
R3173,"Q_RES_0402LF-1K,1%,1/16W,CHIP,CS21002FB06",1K,1%,R0402,3000.20,443.62,90.000,YES,,,
R3174,"Q_RES_0402LF-10K,1%,1/16W,CHIP,CS31002FB08",10K,1%,R0402,2971.41,374.20,180.000,YES,,,
R3175,"Q_RES_0402LF-10K,1%,1/16W,CHIP,CS31002FB08",10K,1%,R0402,2901.41,374.20,0.000,YES,,,
R3176,"Q_RES_0402LF-1K,1%,1/16W,CHIP,CS21002FB06",1K,1%,R0402,2907.16,443.65,90.000,YES,,,
R3177,"Q_RES_0402LF-0,5%,1/16W,CHIP,CS00002JB13",0,5%,R0402,503.04,603.20,90.000,NO,,,
R3178,"Q_RES_0402LF-0,5%,1/16W,CHIP,CS00002JB13",0,5%,R0402,546.16,603.20,90.000,NO,,,
R3180,"Q_RES_0402LF-0,5%,1/16W,CHIP,CS00002JB13",0,5%,R0402,2380.63,327.53,270.000,YES,,,
R3181,"Q_RES_0402LF-27.4,1%,1/16W,CHIP,CS02742FB03",27.4,1%,R0402,8566.30,644.93,270.000,NO,,,
R3182,"Q_RES_0402LF-10K,1%,1/16W,CHIP,CS31002FB08",10K,1%,R0402,4037.93,1570.34,180.000,NO,,,
R3183,"Q_RES_0402LF-10K,1%,1/16W,CHIP,CS31002FB08",10K,1%,R0402,4037.93,1522.78,180.000,NO,,,
R3184,"Q_RES_0402LF-4.7K,1%,1/16W,CHIP,CS24702FB06",4.7K,1%,R0402,3724.63,1580.28,0.000,NO,,,
R3185,"Q_RES_0402LF-33.2,1%,1/16W,CHIP,CS03322FB03",33.2,1%,R0402,3724.63,1631.73,180.000,NO,,,
R3190,"Q_RES_0402LF-4.7K,1%,1/16W,CHIP,CS24702FB06",4.7K,1%,R0402,10155.57,4259.02,180.000,NO,,,
R3191,"Q_RES_0402LF-33.2,1%,1/16W,CHIP,CS03322FB03",33.2,1%,R0402,10155.57,4209.02,0.000,NO,,,
R3192,"Q_RES_0402LF-4.7K,1%,1/16W,EMPTY,CS24702FB06",4.7K,1%,R0402,3942.96,1389.80,0.000,NO,,,
R3193,"Q_RES_0402LF-33.2,1%,1/16W,CHIP,CS03322FB03",33.2,1%,R0402,3974.06,1349.80,0.000,NO,,,
R3194,"Q_RES_0402LF-0,5%,1/16W,CHIP,CS00002JB13",0,5%,R0402,6114.43,7533.91,270.000,NO,,,
R3195,"Q_RES_0402LF-0,5%,1/16W,CHIP,CS00002JB13",0,5%,R0402,6154.43,7533.91,270.000,NO,,,
R3196,"Q_RES_0402LF-0,5%,1/16W,CHIP,CS00002JB13",0,5%,R0402,5915.21,7534.33,270.000,NO,,,
R3197,"Q_RES_0402LF-0,5%,1/16W,CHIP,CS00002JB13",0,5%,R0402,5875.21,7534.33,270.000,NO,,,
R3198,"Q_RES_0402LF-0,5%,1/16W,CHIP,CS00002JB13",0,5%,R0402,5791.25,7533.65,270.000,NO,,,
R3199,"Q_RES_0402LF-0,5%,1/16W,CHIP,CS00002JB13",0,5%,R0402,5831.25,7533.65,270.000,NO,,,
R3200,"Q_RES_0402LF-0,5%,1/16W,CHIP,CS00002JB13",0,5%,R0402,5954.89,7533.65,270.000,NO,,,
R3201,"Q_RES_0402LF-0,5%,1/16W,CHIP,CS00002JB13",0,5%,R0402,5994.89,7533.65,270.000,NO,,,
R3203,"Q_RES_0402LF-33.2,1%,1/16W,CHIP,CS03322FB03",33.2,1%,R0402,1959.79,996.42,90.000,NO,,,
R3205,"Q_RES_0402LF-0,5%,1/16W,CHIP,CS00002JB13",0,5%,R0402,1976.45,1321.87,90.000,NO,,,
R3206,"Q_RES_0402LF-0,5%,1/16W,EMPTY,CS00002JB13",0,5%,R0402,1944.20,1409.62,180.000,NO,,,
R3207,"Q_RES_0402LF-100K,1%,1/16W,CHIP,CS41002FB09",100K,1%,R0402,1944.20,1449.62,0.000,NO,,,
R3208,"Q_RES_0402LF-100,1%,1/16W,CHIP,CS11002FB07",100,1%,R0402,2468.05,613.40,90.000,YES,,,
R3209,"Q_RES_0402LF-22,1%,1/16W,EMPTY,CS02202FB02",22,1%,R0402,7993.91,3040.62,0.000,YES,,,
R3210,"Q_RES_0402LF-22,1%,1/16W,EMPTY,CS02202FB02",22,1%,R0402,7995.00,2954.88,0.000,YES,,,
R3211,"Q_RES_0402LF-22,1%,1/16W,EMPTY,CS02202FB02",22,1%,R0402,8512.31,3015.42,180.000,YES,,,
R3212,"Q_RES_0402LF-22,1%,1/16W,EMPTY,CS02202FB02",22,1%,R0402,8513.90,3088.52,180.000,YES,,,
R3213,"Q_RES_0402LF-0,5%,1/16W,EMPTY,CS00002JB13",0,5%,R0402,7558.77,2733.99,0.000,YES,,,
R3214,"Q_RES_0402LF-0,5%,1/16W,EMPTY,CS00002JB13",0,5%,R0402,8085.64,2768.20,180.000,YES,,,
R3215,"Q_RES_0402LF-0,5%,1/16W,EMPTY,CS00002JB13",0,5%,R0402,8086.18,2843.11,180.000,YES,,,
R3216,"Q_RES_0402LF-100,1%,1/16W,CHIP,CS11002FB07",100,1%,R0402,2417.87,613.40,90.000,YES,,,
R3217,"Q_RES_0402LF-100,1%,1/16W,CHIP,CS11002FB07",100,1%,R0402,2437.20,718.62,0.000,NO,,,
R3226,"Q_RES_0402LF-2.2K,5%,1/16W,EMPTY,CS22202JB07",2.2K,5%,R0402,6062.63,663.43,270.000,YES,,,
R3227,"Q_RES_0402LF-2.2K,5%,1/16W,EMPTY,CS22202JB07",2.2K,5%,R0402,6023.34,663.43,270.000,YES,,,
R3228,"Q_RES_0402LF-33.2,1%,1/16W,CHIP,CS03322FB03",33.2,1%,R0402,6042.78,1576.40,180.000,NO,,,
R3229,"Q_RES_0402LF-33.2,1%,1/16W,CHIP,CS03322FB03",33.2,1%,R0402,6017.69,1456.40,180.000,NO,,,
R3231,"Q_RES_0402LF-33.2,1%,1/16W,CHIP,CS03322FB03",33.2,1%,R0402,17937.71,3678.66,0.000,NO,,,
R3232,"Q_RES_0402LF-100K,1%,1/16W,CHIP,CS41002FB09",100K,1%,R0402,18257.32,3673.59,0.000,NO,,,
R3233,"Q_RES_0402LF-0,5%,1/16W,CHIP,CS00002JB13",0,5%,R0402,18257.32,3713.29,0.000,NO,,,
R3234,"Q_RES_0402LF-33.2,1%,1/16W,CHIP,CS03322FB03",33.2,1%,R0402,2081.79,996.42,90.000,NO,,,
R3235,"Q_RES_0402LF-100K,1%,1/16W,CHIP,CS41002FB09",100K,1%,R0402,2224.80,1246.62,0.000,NO,,,
R3236,"Q_RES_0402LF-0,5%,1/16W,CHIP,CS00002JB13",0,5%,R0402,2224.80,1206.62,0.000,NO,,,
R3237,"Q_RES_0402LF-0,5%,1/16W,CHIP,CS00002JB13",0,5%,R0402,7530.36,3042.45,270.000,YES,,,
R3238,"Q_RES_0402LF-33.2,1%,1/16W,CHIP,CS03322FB03",33.2,1%,R0402,7240.00,802.29,90.000,YES,,,
R3239,"Q_RES_0402LF-33.2,1%,1/16W,CHIP,CS03322FB03",33.2,1%,R0402,7200.10,802.29,90.000,YES,,,
R3240,"Q_RES_0402LF-2.2K,5%,1/16W,EMPTY,CS22202JB07",2.2K,5%,R0402,7226.66,931.33,270.000,YES,,,
R3241,"Q_RES_0402LF-2.2K,5%,1/16W,EMPTY,CS22202JB07",2.2K,5%,R0402,7186.66,931.33,270.000,YES,,,
R3242,"Q_RES_0402LF-2.2K,5%,1/16W,EMPTY,CS22202JB07",2.2K,5%,R0402,6806.21,317.42,270.000,YES,,,
R3243,"Q_RES_0402LF-2.2K,5%,1/16W,EMPTY,CS22202JB07",2.2K,5%,R0402,6749.63,317.42,270.000,YES,,,
R3244,"Q_RES_0402LF-0,5%,1/16W,CHIP,CS00002JB13",0,5%,R0402,7993.91,3080.62,180.000,YES,,,
R3254,"Q_RES_0402LF-0,5%,1/16W,EMPTY,CS00002JB13",0,5%,R0402,5155.39,841.42,90.000,NO,,,
R3263,"Q_RES_0402LF-0,5%,1/16W,EMPTY,CS00002JB13",0,5%,R0402,16239.09,2867.42,0.000,NO,,,
R3264,"Q_RES_0402LF-0,5%,1/16W,EMPTY,CS00002JB13",0,5%,R0402,6017.69,1416.40,0.000,NO,,,
R3265,"Q_RES_0402LF-4.7K,1%,1/16W,EMPTY,CS24702FB06",4.7K,1%,R0402,1594.27,16920.87,270.000,NO,,,
R3266,"Q_RES_0402LF-4.7K,1%,1/16W,CHIP,CS24702FB06",4.7K,1%,R0402,1523.53,16505.87,90.000,NO,,,
R3267,"Q_RES_0402LF-68K,1%,1/16W,EMPTY,CS36802FB04",68K,1%,R0402,1353.53,16920.87,90.000,NO,,,
R3268,"Q_RES_0402LF-68K,1%,1/16W,EMPTY,CS36802FB04",68K,1%,R0402,1163.53,16505.87,270.000,NO,,,
R3269,"Q_RES_0402LF-1K,1%,1/16W,EMPTY,CS21002FB06",1K,1%,R0402,1273.53,16920.87,270.000,NO,,,
R3270,"Q_RES_0402LF-1K,1%,1/16W,EMPTY,CS21002FB06",1K,1%,R0402,1313.53,16920.87,90.000,NO,,,
R3271,"Q_RES_0402LF-1K,1%,1/16W,EMPTY,CS21002FB06",1K,1%,R0402,1123.53,16505.87,90.000,NO,,,
R3272,"Q_RES_0402LF-1K,1%,1/16W,EMPTY,CS21002FB06",1K,1%,R0402,1203.53,16505.87,270.000,NO,,,
R3273,"Q_RES_0402LF-68K,1%,1/16W,EMPTY,CS36802FB04",68K,1%,R0402,1283.53,16505.87,270.000,NO,,,
R3274,"Q_RES_0402LF-68K,1%,1/16W,EMPTY,CS36802FB04",68K,1%,R0402,1054.86,16713.61,180.000,NO,,,
R3275,"Q_RES_0402LF-1K,1%,1/16W,EMPTY,CS21002FB06",1K,1%,R0402,1323.53,16505.87,90.000,NO,,,
R3276,"Q_RES_0402LF-1K,1%,1/16W,EMPTY,CS21002FB06",1K,1%,R0402,1243.53,16505.87,270.000,NO,,,
R3277,"Q_RES_0402LF-1K,1%,1/16W,EMPTY,CS21002FB06",1K,1%,R0402,1143.53,16703.13,0.000,NO,,,
R3278,"Q_RES_0402LF-1K,1%,1/16W,CHIP,CS21002FB06",1K,1%,R0402,1054.86,16673.61,180.000,NO,,,
R3279,"Q_RES_0402LF-68K,1%,1/16W,EMPTY,CS36802FB04",68K,1%,R0402,1153.53,16919.66,90.000,NO,,,
R3280,"Q_RES_0402LF-1K,1%,1/16W,EMPTY,CS21002FB06",1K,1%,R0402,1233.53,16919.66,270.000,NO,,,
R3281,"Q_RES_0402LF-1K,1%,1/16W,EMPTY,CS21002FB06",1K,1%,R0402,1193.53,16919.66,90.000,NO,,,
R3282,"Q_RES_0402LF-68K,1%,1/16W,EMPTY,CS36802FB04",68K,1%,R0402,1054.86,16795.64,180.000,NO,,,
R3283,"Q_RES_0402LF-1K,1%,1/16W,EMPTY,CS21002FB06",1K,1%,R0402,1143.53,16743.13,0.000,NO,,,
R3284,"Q_RES_0402LF-1K,1%,1/16W,CHIP,CS21002FB06",1K,1%,R0402,1054.86,16755.64,180.000,NO,,,
R3285,"Q_RES_0402LF-68K,1%,1/16W,EMPTY,CS36802FB04",68K,1%,R0402,1433.53,16920.87,90.000,NO,,,
R3286,"Q_RES_0402LF-1K,1%,1/16W,EMPTY,CS21002FB06",1K,1%,R0402,1472.53,16920.87,270.000,NO,,,
R3287,"Q_RES_0402LF-1K,1%,1/16W,EMPTY,CS21002FB06",1K,1%,R0402,1393.53,16920.87,90.000,NO,,,
R3288,"Q_RES_0402LF-68K,1%,1/16W,EMPTY,CS36802FB04",68K,1%,R0402,1442.53,16505.87,270.000,NO,,,
R3289,"Q_RES_0402LF-1K,1%,1/16W,EMPTY,CS21002FB06",1K,1%,R0402,1363.53,16505.87,90.000,NO,,,
R3290,"Q_RES_0402LF-1K,1%,1/16W,EMPTY,CS21002FB06",1K,1%,R0402,1403.53,16505.87,270.000,NO,,,
R3291,"Q_RES_0402LF-4.7K,1%,1/16W,EMPTY,CS24702FB06",4.7K,1%,R0402,1513.53,16700.87,0.000,NO,,,
R3292,"Q_RES_0402LF-4.7K,1%,1/16W,CHIP,CS24702FB06",4.7K,1%,R0402,1553.53,16920.87,90.000,NO,,,
R3293,"Q_RES_0402LF-4.7K,1%,1/16W,EMPTY,CS24702FB06",4.7K,1%,R0402,1483.53,16505.87,270.000,NO,,,
R3294,"Q_RES_0402LF-0,5%,1/16W,CHIP,CS00002JB13",0,5%,R0402,5918.10,4002.87,0.000,NO,,,
R3295,"Q_RES_0402LF-4.7K,1%,1/16W,CHIP,CS24702FB06",4.7K,1%,R0402,5918.10,4042.87,0.000,NO,,,
R3296,"Q_RES_0402LF-4.7K,1%,1/16W,CHIP,CS24702FB06",4.7K,1%,R0402,5546.73,4142.74,0.000,NO,,,
R3297,"Q_RES_0402LF-10K,1%,1/16W,CHIP,CS31002FB08",10K,1%,R0402,6153.85,4001.53,270.000,NO,,,
R3298,"Q_RES_0402LF-10K,1%,1/16W,CHIP,CS31002FB08",10K,1%,R0402,5846.23,4158.46,180.000,NO,,,
R3301,"Q_RES_0402LF-33.2,1%,1/16W,CHIP,CS03322FB03",33.2,1%,R0402,6478.14,1618.62,0.000,NO,,,
R3303,"Q_RES_0402LF-0,5%,1/16W,CHIP,CS00002JB13",0,5%,R0402,6215.85,3888.02,90.000,NO,,,
R3304,"Q_RES_0402LF-0,5%,1/16W,CHIP,CS00002JB13",0,5%,R0402,6215.85,3760.52,90.000,NO,,,
R3305,"Q_RES_0402LF-0,5%,1/16W,CHIP,CS00002JB13",0,5%,R0402,6174.60,3668.27,180.000,NO,,,
R3306,"Q_RES_0402LF-0,5%,1/16W,CHIP,CS00002JB13",0,5%,R0402,5855.85,3760.52,90.000,NO,,,
R3307,"Q_RES_0402LF-0,5%,1/16W,CHIP,CS00002JB13",0,5%,R0402,5814.60,3668.27,180.000,NO,,,
R3308,"Q_RES_0402LF-0,5%,1/16W,CHIP,CS00002JB13",0,5%,R0402,5855.85,3888.02,90.000,NO,,,
R3315,"Q_RES_0402LF-33.2,1%,1/16W,CHIP,CS03322FB03",33.2,1%,R0402,1897.60,17088.88,270.000,NO,,,
R3317,"Q_RES_0402LF-4.7K,5%,1/16W,EMPTY,CS24702JB10",4.7K,5%,R0402,1857.60,17088.88,90.000,NO,,,
R3318,"Q_RES_0402LF-100K,1%,1/16W,EMPTY,CS41002FB09",100K,1%,R0402,2090.30,16644.79,0.000,YES,,,
R3320,"Q_RES_0402LF-4.7K,5%,1/16W,CHIP,CS24702JB10",4.7K,5%,R0402,1828.13,16634.96,90.000,YES,,,
R3321,"Q_RES_0402LF-100K,1%,1/16W,CHIP,CS41002FB09",100K,1%,R0402,2092.58,16581.92,0.000,YES,,,
R3322,"Q_RES_0402LF-1K,1%,1/16W,CHIP,CS21002FB06",1K,1%,R0402,1429.92,5309.97,180.000,NO,,,
R3324,"Q_RES_0402LF-33.2,1%,1/16W,CHIP,CS03322FB03",33.2,1%,R0402,7916.62,4834.58,0.000,NO,,,
R3326,"Q_RES_0402LF-0,5%,1/16W,CHIP,CS00002JB13",0,5%,R0402,1429.92,5219.97,180.000,NO,,,
R3327,"Q_RES_0402LF-0,5%,1/16W,CHIP,CS00002JB13",0,5%,R0402,1429.92,5349.97,180.000,NO,,,
R3335,"Q_RES_0402LF-0,5%,1/16W,CHIP,CS00002JB13",0,5%,R0402,736.33,5216.13,0.000,NO,,,
R3336,"Q_RES_0402LF-0,5%,1/16W,CHIP,CS00002JB13",0,5%,R0402,736.33,5255.13,0.000,NO,,,
R3337,"Q_RES_0402LF-0,5%,1/16W,CHIP,CS00002JB13",0,5%,R0402,736.33,5393.13,0.000,NO,,,
R3338,"Q_RES_0402LF-0,5%,1/16W,CHIP,CS00002JB13",0,5%,R0402,736.33,5432.13,0.000,NO,,,
R3340,"Q_RES_0402LF-33.2,1%,1/16W,CHIP,CS03322FB03",33.2,1%,R0402,485.02,5062.72,90.000,NO,,,
R3341,"Q_RES_0402LF-33.2,1%,1/16W,CHIP,CS03322FB03",33.2,1%,R0402,529.02,5060.85,90.000,NO,,,
R3352,"Q_RES_0402LF-0,5%,1/16W,CHIP,CS00002JB13",0,5%,R0402,4965.00,12663.62,90.000,NO,,,
R3353,"Q_RES_0402LF-0,5%,1/16W,CHIP,CS00002JB13",0,5%,R0402,4925.00,12663.62,90.000,NO,,,
R3354,"Q_RES_0402LF-0,5%,1/16W,CHIP,CS00002JB13",0,5%,R0402,6034.56,7533.79,270.000,NO,,,
R3355,"Q_RES_0402LF-0,5%,1/16W,CHIP,CS00002JB13",0,5%,R0402,6074.56,7533.79,270.000,NO,,,
R3390,"Q_RES_0402LF-49.9,1%,1/16W,CHIP,CS04992FB07",49.9,1%,R0402,4740.00,16680.00,180.000,NO,,,
R3391,"Q_RES_0402LF-49.9,1%,1/16W,CHIP,CS04992FB07",49.9,1%,R0402,2075.00,17070.00,0.000,NO,,,
R3392,"Q_RES_0402LF-49.9,1%,1/16W,CHIP,CS04992FB07",49.9,1%,R0402,4665.00,16680.00,0.000,NO,,,
R3393,"Q_RES_0402LF-0,5%,1/16W,CHIP,CS00002JB13",0,5%,R0402,11004.48,4633.55,180.000,NO,,,
R3394,"Q_RES_0402LF-0,5%,1/16W,CHIP,CS00002JB13",0,5%,R0402,11004.48,4673.55,180.000,NO,,,
R3395,"Q_RES_0402LF-2.2K,5%,1/16W,CHIP,CS22202JB07",2.2K,5%,R0402,11712.06,4698.41,180.000,NO,,,
R3396,"Q_RES_0402LF-2.2K,5%,1/16W,CHIP,CS22202JB07",2.2K,5%,R0402,11712.06,4643.41,180.000,NO,,,
R3397,"Q_RES_0402LF-33.2,1%,1/16W,CHIP,CS03322FB03",33.2,1%,R0402,4155.00,16495.00,180.000,NO,,,
R3428,"Q_RES_0402LF-100K,1%,1/16W,EMPTY,CS41002FB09",100K,1%,R0402,2078.07,17074.13,270.000,YES,,,
R3429,"Q_RES_0402LF-100K,1%,1/16W,EMPTY,CS41002FB09",100K,1%,R0402,6434.00,17221.38,0.000,NO,,,
R3430,"Q_RES_0402LF-100K,1%,1/16W,EMPTY,CS41002FB09",100K,1%,R0402,12142.54,17084.36,270.000,NO,,,
R3431,"Q_RES_0402LF-100K,1%,1/16W,EMPTY,CS41002FB09",100K,1%,R0402,4740.00,16555.00,0.000,NO,,,
R3432,"Q_RES_0402LF-4.7K,5%,1/16W,CHIP,CS24702JB10",4.7K,5%,R0402,1825.17,17007.31,270.000,YES,,,
R3433,"Q_RES_0402LF-4.7K,5%,1/16W,CHIP,CS24702JB10",4.7K,5%,R0402,6731.13,17205.99,90.000,NO,,,
R3434,"Q_RES_0402LF-4.7K,5%,1/16W,CHIP,CS24702JB10",4.7K,5%,R0402,4650.00,16490.00,270.000,NO,,,
R3435,"Q_RES_0402LF-4.7K,5%,1/16W,CHIP,CS24702JB10",4.7K,5%,R0402,11894.07,17135.18,270.000,NO,,,
R3436,"Q_RES_0402LF-100K,1%,1/16W,CHIP,CS41002FB09",100K,1%,R0402,4665.00,16595.00,0.000,NO,,,
R3437,"Q_RES_0402LF-100K,1%,1/16W,CHIP,CS41002FB09",100K,1%,R0402,12142.54,17154.36,270.000,NO,,,
R3438,"Q_RES_0402LF-100K,1%,1/16W,CHIP,CS41002FB09",100K,1%,R0402,6434.00,17171.38,0.000,NO,,,
R3439,"Q_RES_0402LF-100K,1%,1/16W,CHIP,CS41002FB09",100K,1%,R0402,2078.07,17004.13,270.000,YES,,,
R3440,"Q_RES_0402LF-0,5%,1/16W,EMPTY,CS00002JB13",0,5%,R0402,7413.26,16853.12,90.000,NO,,,
R3441,"Q_RES_0402LF-0,5%,1/16W,CHIP,CS00002JB13",0,5%,R0402,7374.68,16887.03,90.000,NO,,,
R3442,"Q_RES_0402LF-0,5%,1/16W,CHIP,CS00002JB13",0,5%,R0402,7324.34,16866.73,90.000,NO,,,
R3443,"Q_RES_0402LF-0,5%,1/16W,CHIP,CS00002JB13",0,5%,R0402,7284.54,16865.04,90.000,NO,,,
R3448,"Q_RES_0402LF-4.7K,5%,1/16W,EMPTY,CS24702JB10",4.7K,5%,R0402,4740.00,16970.00,180.000,NO,,,
R3449,"Q_RES_0402LF-100K,1%,1/16W,CHIP,CS41002FB09",100K,1%,R0402,4740.00,17010.00,0.000,NO,,,
R3451,"Q_RES_0402LF-4.7K,5%,1/16W,EMPTY,CS24702JB10",4.7K,5%,R0402,4670.00,16970.00,0.000,NO,,,
R3452,"Q_RES_0402LF-100K,1%,1/16W,CHIP,CS41002FB09",100K,1%,R0402,4670.00,17010.00,180.000,NO,,,
R3453,"Q_RES_0402LF-100K,1%,1/16W,EMPTY,CS41002FB09",100K,1%,R0402,4740.00,16720.00,0.000,NO,,,
R3454,"Q_RES_0402LF-1K,1%,1/16W,CHIP,CS21002FB06",1K,1%,R0402,4740.00,16760.00,180.000,NO,,,
R3455,"Q_RES_0402LF-10K,1%,1/16W,CHIP,CS31002FB08",10K,1%,R0402,2005.00,17070.00,180.000,NO,,,
R3456,"Q_RES_0402LF-100K,1%,1/16W,EMPTY,CS41002FB09",100K,1%,R0402,4665.00,16720.00,180.000,NO,,,
R3457,"Q_RES_0402LF-10K,1%,1/16W,CHIP,CS31002FB08",10K,1%,R0402,4665.00,16760.00,0.000,NO,,,
R3459,"Q_RES_0402LF-1K,1%,1/16W,CHIP,CS21002FB06",1K,1%,R0402,4130.00,16790.00,270.000,NO,,,
R3460,"Q_RES_0402LF-100K,1%,1/16W,EMPTY,CS41002FB09",100K,1%,R0402,4170.00,16790.00,90.000,NO,,,
R3461,"Q_RES_0402LF-54.9K,1%,1/16W,CHIP,CS35492FB03",54.9K,1%,R0402,4155.00,16575.00,0.000,NO,,,
R3462,"Q_RES_0402LF-100K,1%,1/16W,EMPTY,CS41002FB09",100K,1%,R0402,4155.00,16535.00,180.000,NO,,,
R3463,"Q_RES_0402LF-54.9K,1%,1/16W,CHIP,CS35492FB03",54.9K,1%,R0402,6504.00,17221.38,0.000,NO,,,
R3464,"Q_RES_0402LF-54.9K,1%,1/16W,CHIP,CS35492FB03",54.9K,1%,R0402,12102.54,17084.36,90.000,NO,,,
R3465,"Q_RES_0402LF-10K,1%,1/16W,CHIP,CS31002FB08",10K,1%,R0402,4740.00,16595.00,180.000,NO,,,
R3466,"Q_RES_0402LF-10K,1%,1/16W,CHIP,CS31002FB08",10K,1%,R0402,1573.15,17265.00,180.000,NO,,,
R3467,"Q_RES_0402LF-10K,1%,1/16W,CHIP,CS31002FB08",10K,1%,R0402,1992.79,17230.00,180.000,NO,,,
R3468,"Q_RES_0402LF-49.9,1%,1/16W,CHIP,CS04992FB07",49.9,1%,R0402,1643.15,17265.00,0.000,NO,,,
R3469,"Q_RES_0402LF-49.9,1%,1/16W,CHIP,CS04992FB07",49.9,1%,R0402,2078.15,17230.00,0.000,NO,,,
R3470,"Q_RES_0402LF-1K,1%,1/16W,CHIP,CS21002FB06",1K,1%,R0402,17286.33,17136.90,270.000,NO,,,
R3471,"Q_RES_0402LF-10K,1%,1/16W,EMPTY,CS31002FB08",10K,1%,R0402,17246.33,17136.90,90.000,NO,,,
R3472,"Q_RES_0402LF-0,5%,1/16W,EMPTY,CS00002JB13",0,5%,R0402,17286.33,17066.90,90.000,NO,,,
R3473,"Q_RES_0402LF-100K,1%,1/16W,EMPTY,CS41002FB09",100K,1%,R0402,2038.07,16922.95,270.000,YES,,,
R3474,"Q_RES_0402LF-4.7K,5%,1/16W,CHIP,CS24702JB10",4.7K,5%,R0402,1825.17,16935.63,90.000,YES,,,
R3475,"Q_RES_0402LF-100K,1%,1/16W,CHIP,CS41002FB09",100K,1%,R0402,2078.07,16852.95,270.000,YES,,,
R3476,"Q_RES_0402LF-33.2,1%,1/16W,CHIP,CS03322FB03",33.2,1%,R0402,7766.52,4793.44,180.000,YES,,,
R3477,"Q_RES_0402LF-33.2,1%,1/16W,CHIP,CS03322FB03",33.2,1%,R0402,7755.00,3948.62,90.000,NO,,,
R3478,"Q_RES_0402LF-33.2,1%,1/16W,CHIP,CS03322FB03",33.2,1%,R0402,7911.52,4353.44,180.000,NO,,,
R3479,"Q_RES_0402LF-33.2,1%,1/16W,CHIP,CS03322FB03",33.2,1%,R0402,7766.52,4953.44,0.000,NO,,,
R3480,"Q_RES_0402LF-33.2,1%,1/16W,CHIP,CS03322FB03",33.2,1%,R0402,8078.02,4635.78,0.000,NO,,,
R3481,"Q_RES_0402LF-33.2,1%,1/16W,CHIP,CS03322FB03",33.2,1%,R0402,8223.58,4635.78,0.000,NO,,,
R3482,"Q_RES_0402LF-33.2,1%,1/16W,CHIP,CS03322FB03",33.2,1%,R0402,7645.00,5258.62,90.000,NO,,,
R3483,"Q_RES_0402LF-33.2,1%,1/16W,CHIP,CS03322FB03",33.2,1%,R0402,8080.09,4356.28,180.000,NO,,,
R3484,"Q_RES_0402LF-33.2,1%,1/16W,CHIP,CS03322FB03",33.2,1%,R0402,7911.52,4833.44,180.000,YES,,,
R3485,"Q_RES_0402LF-33.2,1%,1/16W,CHIP,CS03322FB03",33.2,1%,R0402,7793.52,4833.44,180.000,YES,,,
R3486,"Q_RES_0402LF-33.2,1%,1/16W,CHIP,CS03322FB03",33.2,1%,R0402,6446.41,4698.63,180.000,NO,,,
R3487,"Q_RES_0402LF-10K,1%,1/16W,CHIP,CS31002FB08",10K,1%,R0402,2078.07,16922.95,90.000,YES,,,
R3488,"Q_RES_0402LF-1K,1%,1/16W,CHIP,CS21002FB06",1K,1%,R0402,4090.00,16790.00,270.000,NO,,,
R3489,"Q_RES_0402LF-100K,1%,1/16W,EMPTY,CS41002FB09",100K,1%,R0402,4050.00,16790.00,90.000,NO,,,
R3490,"Q_RES_0402LF-1K,1%,1/16W,CHIP,CS21002FB06",1K,1%,R0402,4740.00,17335.00,180.000,NO,,,
R3491,"Q_RES_0402LF-100K,1%,1/16W,EMPTY,CS41002FB09",100K,1%,R0402,4670.00,17335.00,180.000,NO,,,
R3492,"Q_RES_0402LF-54.9K,1%,1/16W,CHIP,CS35492FB03",54.9K,1%,R0402,4075.00,16495.00,180.000,NO,,,
R3493,"Q_RES_0402LF-100K,1%,1/16W,EMPTY,CS41002FB09",100K,1%,R0402,4075.00,16535.00,0.000,NO,,,
R3494,"Q_RES_0402LF-54.9K,1%,1/16W,CHIP,CS35492FB03",54.9K,1%,R0402,4740.00,17105.00,180.000,NO,,,
R3495,"Q_RES_0402LF-100K,1%,1/16W,EMPTY,CS41002FB09",100K,1%,R0402,4740.00,17145.00,0.000,NO,,,
R3496,"Q_RES_0402LF-33.2,1%,1/16W,CHIP,CS03322FB03",33.2,1%,R0402,4075.00,16455.00,0.000,NO,,,
R3497,"Q_RES_0402LF-33.2,1%,1/16W,CHIP,CS03322FB03",33.2,1%,R0402,4740.00,17065.00,0.000,NO,,,
R3498,"Q_RES_0402LF-54.9K,1%,1/16W,CHIP,CS35492FB03",54.9K,1%,R0402,2038.07,17074.13,90.000,YES,,,
R3499,"Q_RES_0402LF-0,5%,1/16W,CHIP,CS00002JB13",0,5%,R0402,7374.67,16821.07,270.000,NO,,,
R3500,"Q_RES_0402LF-4.7K,5%,1/16W,CHIP,CS24702JB10",4.7K,5%,R0402,16239.09,2987.42,180.000,NO,,,
R3501,"Q_RES_0402LF-4.7K,5%,1/16W,CHIP,CS24702JB10",4.7K,5%,R0402,16239.09,2947.42,180.000,NO,,,
R3502,"Q_RES_0402LF-100K,1%,1/16W,EMPTY,CS41002FB09",100K,1%,R0402,4610.00,16455.00,270.000,YES,,,
R3503,"Q_RES_0402LF-4.7K,5%,1/16W,CHIP,CS24702JB10",4.7K,5%,R0402,4385.00,16465.00,180.000,YES,,,
R3504,"Q_RES_0402LF-100K,1%,1/16W,CHIP,CS41002FB09",100K,1%,R0402,4611.86,16374.50,270.000,YES,,,
R3505,"Q_RES_0402LF-33.2,1%,1/16W,CHIP,CS03322FB03",33.2,1%,R0402,8223.58,4675.68,0.000,NO,,,
R3506,"Q_RES_0402LF-4.7K,5%,1/16W,EMPTY,CS24702JB10",4.7K,5%,R0402,1735.00,17150.00,0.000,NO,,,
R3507,"Q_RES_0402LF-10K,1%,1/16W,CHIP,CS31002FB08",10K,1%,R0402,1735.00,17110.00,180.000,NO,,,
R3508,"Q_RES_0402LF-54.9K,1%,1/16W,CHIP,CS35492FB03",54.9K,1%,R0402,1817.60,17273.76,90.000,NO,,,
R3509,"Q_RES_0402LF-10K,1%,1/16W,CHIP,CS31002FB08",10K,1%,R0402,1817.60,17088.88,270.000,NO,,,
R3510,"Q_RES_0402LF-54.9K,1%,1/16W,CHIP,CS35492FB03",54.9K,1%,R0402,4475.76,16459.82,270.000,NO,,,
R3511,"Q_RES_0402LF-54.9K,1%,1/16W,CHIP,CS35492FB03",54.9K,1%,R0402,2020.81,16644.79,0.000,YES,,,
R3512,"Q_RES_0402LF-100K,1%,1/16W,EMPTY,CS41002FB09",100K,1%,R0402,2076.60,16771.78,90.000,YES,,,
R3513,"Q_RES_0402LF-54.9K,1%,1/16W,CHIP,CS35492FB03",54.9K,1%,R0402,2036.60,16771.78,270.000,YES,,,
R3514,"Q_RES_0402LF-54.9K,1%,1/16W,CHIP,CS35492FB03",54.9K,1%,R0402,4155.00,16575.00,180.000,YES,,,
R3515,"Q_RES_0402LF-49.9,1%,1/16W,CHIP,CS04992FB07",49.9,1%,R0402,1627.40,17090.00,270.000,NO,,,
R3516,"Q_RES_0402LF-0,5%,1/16W,CHIP,CS00002JB13",0,5%,R0402,7413.26,16785.57,270.000,NO,,,
R3517,"Q_RES_0402LF-0,5%,1/16W,CHIP,CS00002JB13",0,5%,R0402,7256.32,16787.60,270.000,NO,,,
R3518,"Q_RES_0402LF-0,5%,1/16W,CHIP,CS00002JB13",0,5%,R0402,7296.16,16787.61,270.000,NO,,,
R3519,"Q_RES_0402LF-4.7K,5%,1/16W,CHIP,CS24702JB10",4.7K,5%,R0402,6017.69,1536.40,180.000,NO,,,
R3520,"Q_RES_0402LF-4.7K,5%,1/16W,CHIP,CS24702JB10",4.7K,5%,R0402,6017.69,1496.40,180.000,NO,,,
R3521,"Q_RES_0402LF-54.9K,1%,1/16W,CHIP,CS35492FB03",54.9K,1%,R0402,1412.67,17222.41,180.000,NO,,,
R3522,"Q_RES_0402LF-54.9K,1%,1/16W,CHIP,CS35492FB03",54.9K,1%,R0402,867.57,17203.31,0.000,NO,,,
R3523,"Q_RES_0402LF-54.9K,1%,1/16W,CHIP,CS35492FB03",54.9K,1%,R0402,869.20,17025.11,0.000,NO,,,
R3524,"Q_RES_0402LF-54.9K,1%,1/16W,CHIP,CS35492FB03",54.9K,1%,R0402,1383.18,17051.66,180.000,NO,,,
R3525,"Q_RES_0402LF-54.9K,1%,1/16W,CHIP,CS35492FB03",54.9K,1%,R0402,4570.00,16455.00,90.000,YES,,,
R3526,"Q_RES_0402LF-0,5%,1/16W,CHIP,CS00002JB13",0,5%,R0402,11004.48,4473.55,180.000,NO,,,
R3527,"Q_RES_0402LF-0,5%,1/16W,CHIP,CS00002JB13",0,5%,R0402,11004.48,4513.55,180.000,NO,,,
R3529,"Q_RES_0402LF-10K,1%,1/16W,CHIP,CS31002FB08",10K,1%,R0402,8297.20,1668.62,0.000,NO,,,
R3530,"Q_RES_0402LF-4.7K,5%,1/16W,CHIP,CS24702JB10",4.7K,5%,R0402,8727.20,1713.62,180.000,NO,,,
R3531,"Q_RES_0402LF-200K,1%,1/16W,EMPTY,CS42002FB05",200K,1%,R0402,8297.20,1763.62,0.000,NO,,,
R3532,"Q_RES_0402LF-4.7K,5%,1/16W,CHIP,CS24702JB10",4.7K,5%,R0402,8727.20,1768.62,180.000,NO,,,
R3533,"Q_RES_0402LF-33.2,1%,1/16W,CHIP,CS03322FB03",33.2,1%,R0402,8807.20,1713.62,0.000,NO,,,
R3534,"Q_RES_0402LF-33.2,1%,1/16W,CHIP,CS03322FB03",33.2,1%,R0402,8807.20,1768.62,0.000,NO,,,
R3535,"Q_RES_0402LF-2.2K,5%,1/16W,CHIP,CS22202JB07",2.2K,5%,R0402,10919.38,4406.05,0.000,NO,,,
R3536,"Q_RES_0402LF-2.2K,5%,1/16W,CHIP,CS22202JB07",2.2K,5%,R0402,10919.38,4461.05,0.000,NO,,,
R3553,"Q_RES_0402LF-33.2,1%,1/16W,CHIP,CS03322FB03",33.2,1%,R0402,4208.37,668.65,0.000,NO,,,
R3554,"Q_RES_0402LF-33.2,1%,1/16W,CHIP,CS03322FB03",33.2,1%,R0402,4208.37,716.65,0.000,NO,,,
R3559,"Q_RES_0402LF-0,5%,1/16W,CHIP,CS00002JB13",0,5%,R0402,2685.53,1472.03,180.000,NO,,,
R3560,"Q_RES_0402LF-0,5%,1/16W,CHIP,CS00002JB13",0,5%,R0402,5925.29,2132.77,180.000,NO,,,
R3561,"Q_RES_0402LF-0,5%,1/16W,CHIP,CS00002JB13",0,5%,R0402,8351.14,1191.98,270.000,NO,,,
R3563,"Q_RES_0402LF-0,5%,1/16W,CHIP,CS00002JB13",0,5%,R0402,17527.20,3724.52,0.000,NO,,,
R3568,"Q_RES_0402LF-0,5%,1/16W,CHIP,CS00002JB13",0,5%,R0402,2853.00,1369.62,180.000,NO,,,
R3569,"Q_RES_0402LF-0,5%,1/16W,CHIP,CS00002JB13",0,5%,R0402,2784.00,1369.62,0.000,NO,,,
R3570,"Q_RES_0402LF-10,1%,1/16W,CHIP,CS01002FB07",10,1%,R0402,3158.39,2318.51,180.000,NO,,,
R3571,"Q_RES_0402LF-10,1%,1/16W,CHIP,CS01002FB07",10,1%,R0402,3158.39,2278.51,180.000,NO,,,
R3572,"Q_RES_0402LF-0,5%,1/16W,CHIP,CS00002JB13",0,5%,R0402,6087.93,2077.61,90.000,NO,,,
R3573,"Q_RES_0402LF-0,5%,1/16W,CHIP,CS00002JB13",0,5%,R0402,6022.93,2077.61,90.000,NO,,,
R3574,"Q_RES_0402LF-10,1%,1/16W,CHIP,CS01002FB07",10,1%,R0402,6361.09,2309.75,180.000,NO,,,
R3575,"Q_RES_0402LF-10,1%,1/16W,CHIP,CS01002FB07",10,1%,R0402,6361.09,2269.75,180.000,NO,,,
R3576,"Q_RES_0402LF-0,5%,1/16W,CHIP,CS00002JB13",0,5%,R0402,8407.20,1358.62,180.000,NO,,,
R3577,"Q_RES_0402LF-0,5%,1/16W,CHIP,CS00002JB13",0,5%,R0402,8407.20,1293.62,180.000,NO,,,
R3578,"Q_RES_0402LF-10,1%,1/16W,CHIP,CS01002FB07",10,1%,R0402,8005.20,1442.62,180.000,YES,,,
R3579,"Q_RES_0402LF-10,1%,1/16W,CHIP,CS01002FB07",10,1%,R0402,8005.20,1392.62,180.000,YES,,,
R3580,"Q_RES_0402LF-0,5%,1/16W,CHIP,CS00002JB13",0,5%,R0402,11591.38,4696.91,0.000,NO,,,
R3581,"Q_RES_0402LF-0,5%,1/16W,CHIP,CS00002JB13",0,5%,R0402,11591.38,4656.91,0.000,NO,,,
R3582,"Q_RES_0402LF-2.2K,5%,1/16W,CHIP,CS22202JB07",2.2K,5%,R0402,10919.38,4626.05,0.000,NO,,,
R3583,"Q_RES_0402LF-2.2K,5%,1/16W,CHIP,CS22202JB07",2.2K,5%,R0402,10919.38,4681.05,0.000,NO,,,
R3586,"Q_RES_0402LF-33.2,1%,1/16W,CHIP,CS03322FB03",33.2,1%,R0402,11783.40,4711.65,90.000,NO,,,
R3587,"Q_RES_0402LF-33.2,1%,1/16W,CHIP,CS03322FB03",33.2,1%,R0402,11808.49,4631.90,90.000,NO,,,
R3588,"Q_RES_0402LF-33.2,1%,1/16W,CHIP,CS03322FB03",33.2,1%,R0402,8442.21,1863.62,90.000,NO,,,
R3589,"Q_RES_0402LF-33.2,1%,1/16W,CHIP,CS03322FB03",33.2,1%,R0402,8402.21,1863.62,90.000,NO,,,
R3590,"Q_RES_0402LF-33.2,1%,1/16W,CHIP,CS03322FB03",33.2,1%,R0402,6087.94,1927.61,270.000,NO,,,
R3591,"Q_RES_0402LF-33.2,1%,1/16W,CHIP,CS03322FB03",33.2,1%,R0402,5982.94,1997.61,90.000,NO,,,
R3592,"Q_RES_0402LF-33.2,1%,1/16W,CHIP,CS03322FB03",33.2,1%,R0402,8502.21,1358.62,180.000,NO,,,
R3593,"Q_RES_0402LF-33.2,1%,1/16W,CHIP,CS03322FB03",33.2,1%,R0402,8502.21,1293.62,180.000,NO,,,
R3594,"Q_RES_0402LF-33.2,1%,1/16W,CHIP,CS03322FB03",33.2,1%,R0402,6087.94,1997.61,90.000,NO,,,
R3595,"Q_RES_0402LF-33.2,1%,1/16W,CHIP,CS03322FB03",33.2,1%,R0402,6022.94,1997.61,90.000,NO,,,
R3600,"Q_RES_0402LF-0,5%,1/16W,CHIP,CS00002JB13",0,5%,R0402,17527.20,3829.52,180.000,NO,,,
R3601,"Q_RES_0402LF-0,5%,1/16W,CHIP,CS00002JB13",0,5%,R0402,17527.20,3774.52,180.000,NO,,,
R3602,"Q_RES_0402LF-10,1%,1/16W,CHIP,CS01002FB07",10,1%,R0402,17032.94,3697.73,0.000,NO,,,
R3603,"Q_RES_0402LF-10,1%,1/16W,CHIP,CS01002FB07",10,1%,R0402,17032.94,3737.73,0.000,NO,,,
R3608,"Q_RES_0402LF-4.7K,1%,1/16W,CHIP,CS24702FB06",4.7K,1%,R0402,2685.53,1592.03,0.000,NO,,,
R3609,"Q_RES_0402LF-4.7K,1%,1/16W,EMPTY,CS24702FB06",4.7K,1%,R0402,2685.53,1552.03,0.000,NO,,,
R3610,"Q_RES_0402LF-4.7K,1%,1/16W,EMPTY,CS24702FB06",4.7K,1%,R0402,5925.29,2292.77,0.000,NO,,,
R3611,"Q_RES_0402LF-4.7K,1%,1/16W,CHIP,CS24702FB06",4.7K,1%,R0402,5925.29,2212.77,0.000,NO,,,
R3612,"Q_RES_0402LF-4.7K,1%,1/16W,EMPTY,CS24702FB06",4.7K,1%,R0402,8191.14,1191.98,90.000,NO,,,
R3613,"Q_RES_0402LF-4.7K,1%,1/16W,EMPTY,CS24702FB06",4.7K,1%,R0402,8311.14,1191.98,90.000,NO,,,
R3616,"Q_RES_0402LF-4.7K,1%,1/16W,CHIP,CS24702FB06",4.7K,1%,R0402,17664.27,3641.48,180.000,NO,,,
R3617,"Q_RES_0402LF-4.7K,1%,1/16W,EMPTY,CS24702FB06",4.7K,1%,R0402,17664.27,3681.48,180.000,NO,,,
R3620,"Q_RES_0402LF-0,5%,1/16W,CHIP,CS00002JB13",0,5%,R0402,2685.53,1512.03,180.000,NO,,,
R3621,"Q_RES_0402LF-4.7K,1%,1/16W,EMPTY,CS24702FB06",4.7K,1%,R0402,5925.29,2172.77,0.000,NO,,,
R3622,"Q_RES_0402LF-4.7K,1%,1/16W,CHIP,CS24702FB06",4.7K,1%,R0402,8271.14,1191.98,90.000,NO,,,
R3623,"Q_RES_0402LF-4.7K,1%,1/16W,CHIP,CS24702FB06",4.7K,1%,R0402,5925.29,2252.77,0.000,NO,,,
R3624,"Q_RES_0402LF-4.7K,1%,1/16W,CHIP,CS24702FB06",4.7K,1%,R0402,8231.14,1191.98,90.000,NO,,,
R3627,"Q_RES_0402LF-4.7K,1%,1/16W,CHIP,CS24702FB06",4.7K,1%,R0402,17525.87,3680.48,180.000,NO,,,
R3628,"Q_RES_0402LF-4.7K,1%,1/16W,EMPTY,CS24702FB06",4.7K,1%,R0402,17525.87,3640.48,180.000,NO,,,
R3630,"Q_RES_0402LF-0,5%,1/16W,EMPTY,CS00002JB13",0,5%,R0402,2757.97,1255.43,270.000,NO,,,
R3631,"Q_RES_0402LF-0,5%,1/16W,EMPTY,CS00002JB13",0,5%,R0402,3825.88,2873.70,180.000,NO,,,
R3633,"Q_RES_2512LF-0.002,1%,2W,CHIP,CS+002AFR06",0.002,1%,R2512XS,3292.19,2301.26,90.000,NO,,,
R3634,"Q_RES_2512LF-0.002,1%,2W,CHIP,CS+002AFR06",0.002,1%,R2512XS,6493.19,2286.15,90.000,NO,,,
R3635,"Q_RES_2512LF-0.002,1%,2W,CHIP,CS+002AFR06",0.002,1%,R2512XS,7915.26,1374.96,90.000,NO,,,
R3645,"Q_RES_2512LF-0.002,1%,2W,CHIP,CS+002AFR06",0.002,1%,R2512XS,16961.71,3865.16,180.000,NO,,,
R3651,"Q_RES_0402LF-0,5%,1/16W,CHIP,CS00002JB13",0,5%,R0402,601.89,4123.45,90.000,NO,,,
R3652,"Q_RES_0402LF-0,5%,1/16W,CHIP,CS00002JB13",0,5%,R0402,655.33,4124.65,90.000,NO,,,
R3653,"Q_RES_0402LF-680,1%,1/16W,CHIP,CS16802FB03",680,1%,R0402,344.85,4010.00,180.000,NO,,,
R3654,"Q_RES_0402LF-33.2,1%,1/16W,CHIP,CS03322FB03",33.2,1%,R0402,390.08,3649.12,90.000,NO,,,
R3655,"Q_RES_0402LF-0,5%,1/16W,CHIP,CS00002JB13",0,5%,R0402,741.69,3831.92,270.000,YES,,,
R3656,"Q_RES_0402LF-10K,1%,1/16W,EMPTY,CS31002FB08",10K,1%,R0402,833.74,3958.65,180.000,NO,,,
R3657,"Q_RES_0402LF-10K,1%,1/16W,EMPTY,CS31002FB08",10K,1%,R0402,833.74,3913.91,180.000,NO,,,
R3658,"Q_RES_0402LF-10K,1%,1/16W,EMPTY,CS31002FB08",10K,1%,R0402,634.29,3649.12,90.000,NO,,,
R3659,"Q_RES_0402LF-10K,1%,1/16W,EMPTY,CS31002FB08",10K,1%,R0402,593.22,3649.12,90.000,NO,,,
R3660,"Q_RES_0402LF-10K,1%,1/16W,CHIP,CS31002FB08",10K,1%,R0402,511.14,3649.12,90.000,NO,,,
R3661,"Q_RES_0402LF-47K,0.1%,1/16W,EMPTY,CS34702BB05",47K,0.1%,R0402,428.09,3649.12,90.000,NO,,,
R3662,"Q_RES_0402LF-0,5%,1/16W,CHIP,CS00002JB13",0,5%,R0402,676.81,3649.12,90.000,NO,,,
R3663,"Q_RES_0402LF-10K,1%,1/16W,CHIP,CS31002FB08",10K,1%,R0402,833.74,3822.19,180.000,NO,,,
R3664,"Q_RES_0402LF-10K,1%,1/16W,EMPTY,CS31002FB08",10K,1%,R0402,833.91,3760.26,0.000,NO,,,
R3665,"Q_RES_0402LF-100K,1%,1/16W,CHIP,CS41002FB09",100K,1%,R0402,833.74,3865.02,0.000,NO,,,
R3666,"Q_RES_0402LF-0,5%,1/16W,CHIP,CS00002JB13",0,5%,R0402,551.90,3649.12,270.000,NO,,,
R3667,"Q_RES_0402LF-1K,1%,1/16W,EMPTY,CS21002FB06",1K,1%,R0402,11937.02,1609.87,0.000,NO,,,
R3668,"Q_RES_0402LF-1K,1%,1/16W,CHIP,CS21002FB06",1K,1%,R0402,12040.12,1609.87,180.000,NO,,,
R3669,"Q_RES_0402LF-1K,1%,1/16W,EMPTY,CS21002FB06",1K,1%,R0402,11937.02,1649.87,0.000,NO,,,
R3670,"Q_RES_0402LF-1K,1%,1/16W,CHIP,CS21002FB06",1K,1%,R0402,12040.12,1649.87,180.000,NO,,,
R3671,"Q_RES_0402LF-0,5%,1/16W,CHIP,CS00002JB13",0,5%,R0402,12040.12,1811.87,0.000,NO,,,
R3672,"Q_RES_0402LF-0,5%,1/16W,CHIP,CS00002JB13",0,5%,R0402,12040.12,1771.87,0.000,NO,,,
R3679,"Q_RES_0402LF-0,5%,1/16W,EMPTY,CS00002JB13",0,5%,R0402,12741.62,1849.87,0.000,NO,,,
R3680,"Q_RES_0402LF-0,5%,1/16W,CHIP,CS00002JB13",0,5%,R0402,12710.12,1849.87,180.000,NO,,,
R3681,"Q_RES_0402LF-0,5%,1/16W,EMPTY,CS00002JB13",0,5%,R0402,12741.62,1620.51,0.000,NO,,,
R3682,"Q_RES_0402LF-0,5%,1/16W,CHIP,CS00002JB13",0,5%,R0402,12710.12,1620.51,180.000,NO,,,
R3683,"Q_RES_0402LF-0,5%,1/16W,EMPTY,CS00002JB13",0,5%,R0402,12741.62,1660.51,0.000,NO,,,
R3684,"Q_RES_0402LF-0,5%,1/16W,CHIP,CS00002JB13",0,5%,R0402,12710.12,1660.51,180.000,NO,,,
R3685,"Q_RES_0402LF-0,5%,1/16W,EMPTY,CS00002JB13",0,5%,R0402,12741.62,1715.51,0.000,NO,,,
R3686,"Q_RES_0402LF-0,5%,1/16W,CHIP,CS00002JB13",0,5%,R0402,12710.12,1715.51,180.000,NO,,,
R3687,"Q_RES_0402LF-0,5%,1/16W,EMPTY,CS00002JB13",0,5%,R0402,12741.62,1580.51,0.000,NO,,,
R3688,"Q_RES_0402LF-0,5%,1/16W,CHIP,CS00002JB13",0,5%,R0402,12710.12,1580.51,180.000,NO,,,
R3689,"Q_RES_0402LF-4.7K,1%,1/16W,EMPTY,CS24702FB06",4.7K,1%,R0402,12040.43,1889.42,0.000,NO,,,
R3690,"Q_RES_0402LF-4.7K,1%,1/16W,EMPTY,CS24702FB06",4.7K,1%,R0402,12040.12,1851.87,180.000,NO,,,
R3703,"Q_RES_0402LF-10K,1%,1/16W,EMPTY,CS31002FB08",10K,1%,R0402,10672.94,4755.25,180.000,NO,,,
R3704,"Q_RES_0402LF-1K,1%,1/16W,CHIP,CS21002FB06",1K,1%,R0402,10672.64,4796.55,0.000,NO,,,
R3705,"Q_RES_0402LF-10K,1%,1/16W,EMPTY,CS31002FB08",10K,1%,R0402,10023.34,4901.75,0.000,NO,,,
R3706,"Q_RES_0402LF-10K,1%,1/16W,EMPTY,CS31002FB08",10K,1%,R0402,10023.34,4941.75,0.000,NO,,,
R3707,"Q_RES_0402LF-1K,1%,1/16W,CHIP,CS21002FB06",1K,1%,R0402,10127.64,4886.42,180.000,NO,,,
R3708,"Q_RES_0402LF-10K,1%,1/16W,EMPTY,CS31002FB08",10K,1%,R0402,10023.34,4996.75,0.000,NO,,,
R3709,"Q_RES_0402LF-1K,1%,1/16W,CHIP,CS21002FB06",1K,1%,R0402,10127.64,4936.55,180.000,NO,,,
R3710,"Q_RES_0402LF-0,5%,1/16W,CHIP,CS00002JB13",0,5%,R0402,10127.64,4841.55,0.000,NO,,,
R3711,"Q_RES_0402LF-33.2,1%,1/16W,CHIP,CS03322FB03",33.2,1%,R0402,10672.64,4836.55,180.000,NO,,,
R3712,"Q_RES_0402LF-33.2,1%,1/16W,CHIP,CS03322FB03",33.2,1%,R0402,10672.64,4876.55,180.000,NO,,,
R3713,"Q_RES_0402LF-0,5%,1/16W,CHIP,CS00002JB13",0,5%,R0402,10127.64,4761.55,180.000,NO,,,
R3714,"Q_RES_0402LF-0,5%,1/16W,CHIP,CS00002JB13",0,5%,R0402,10127.64,4801.55,180.000,NO,,,
R3715,"Q_RES_0402LF-0,5%,1/16W,CHIP,CS00002JB13",0,5%,R0402,10127.64,4681.55,180.000,NO,,,
R3716,"Q_RES_0402LF-0,5%,1/16W,CHIP,CS00002JB13",0,5%,R0402,10127.64,4721.55,180.000,NO,,,
R3717,"Q_RES_0402LF-0,5%,1/16W,CHIP,CS00002JB13",0,5%,R0402,10127.64,4601.55,180.000,NO,,,
R3718,"Q_RES_0402LF-0,5%,1/16W,CHIP,CS00002JB13",0,5%,R0402,10127.64,4641.55,180.000,NO,,,
R3719,"Q_RES_0402LF-0,5%,1/16W,CHIP,CS00002JB13",0,5%,R0402,10127.64,4521.55,180.000,NO,,,
R3720,"Q_RES_0402LF-0,5%,1/16W,CHIP,CS00002JB13",0,5%,R0402,10127.64,4561.55,180.000,NO,,,
R3721,"Q_RES_0402LF-0,5%,1/16W,CHIP,CS00002JB13",0,5%,R0402,10672.64,4536.55,0.000,NO,,,
R3722,"Q_RES_0402LF-0,5%,1/16W,CHIP,CS00002JB13",0,5%,R0402,10672.64,4496.55,0.000,NO,,,
R3723,"Q_RES_0402LF-2.2K,5%,1/16W,CHIP,CS22202JB07",2.2K,5%,R0402,10023.34,4791.75,0.000,NO,,,
R3724,"Q_RES_0402LF-2.2K,5%,1/16W,CHIP,CS22202JB07",2.2K,5%,R0402,10023.34,4846.75,0.000,NO,,,
R3725,"Q_RES_0402LF-2.2K,5%,1/16W,CHIP,CS22202JB07",2.2K,5%,R0402,10023.34,4681.75,0.000,NO,,,
R3726,"Q_RES_0402LF-2.2K,5%,1/16W,CHIP,CS22202JB07",2.2K,5%,R0402,10023.34,4736.75,0.000,NO,,,
R3727,"Q_RES_0402LF-2.2K,5%,1/16W,CHIP,CS22202JB07",2.2K,5%,R0402,10023.34,4571.75,0.000,NO,,,
R3728,"Q_RES_0402LF-2.2K,5%,1/16W,CHIP,CS22202JB07",2.2K,5%,R0402,10023.34,4626.75,0.000,NO,,,
R3729,"Q_RES_0402LF-2.2K,5%,1/16W,CHIP,CS22202JB07",2.2K,5%,R0402,10023.34,4461.75,0.000,NO,,,
R3730,"Q_RES_0402LF-2.2K,5%,1/16W,CHIP,CS22202JB07",2.2K,5%,R0402,10023.34,4516.75,0.000,NO,,,
R3731,"Q_RES_0402LF-2.2K,5%,1/16W,CHIP,CS22202JB07",2.2K,5%,R0402,10672.96,4579.59,0.000,NO,,,
R3732,"Q_RES_0402LF-2.2K,5%,1/16W,CHIP,CS22202JB07",2.2K,5%,R0402,10672.46,4454.99,0.000,NO,,,
R3751,"Q_RES_0402LF-0,5%,1/16W,CHIP,CS00002JB13",0,5%,R0402,8417.20,2143.62,90.000,YES,,,
R3752,"Q_RES_0402LF-0,5%,1/16W,CHIP,CS00002JB13",0,5%,R0402,8334.45,2247.18,270.000,YES,,,
R3754,"Q_RES_0402LF-0,5%,1/16W,CHIP,CS00002JB13",0,5%,R0402,8442.20,1993.62,90.000,NO,,,
R3756,"Q_RES_0402LF-0,5%,1/16W,CHIP,CS00002JB13",0,5%,R0402,8402.20,1993.62,90.000,NO,,,
R3758,"Q_RES_0402LF-10,1%,1/16W,CHIP,CS01002FB07",10,1%,R0402,8668.93,2277.63,180.000,NO,,,
R3760,"Q_RES_0402LF-10,1%,1/16W,CHIP,CS01002FB07",10,1%,R0402,8668.93,2237.63,180.000,NO,,,
R3763,"Q_RES_0402LF-4.7K,1%,1/16W,CHIP,CS24702FB06",4.7K,1%,R0402,8337.15,2265.68,270.000,NO,,,
R3764,"Q_RES_0402LF-4.7K,1%,1/16W,EMPTY,CS24702FB06",4.7K,1%,R0402,8442.20,2203.62,0.000,YES,,,
R3767,"Q_RES_2512LF-0.002,1%,2W,CHIP,CS+002AFR06",0.002,1%,R2512XS,8821.83,2259.33,90.000,NO,,,
R3770,"Q_RES_0402LF-0,5%,1/16W,CHIP,CS00002JB13",0,5%,R0402,7617.70,16297.83,90.000,NO,,,
R3771,"Q_RES_0402LF-10K,1%,1/16W,CHIP,CS31002FB08",10K,1%,R0402,9299.25,1976.12,180.000,YES,,,
R3772,"Q_RES_0402LF-0,5%,1/16W,CHIP,CS00002JB13",0,5%,R0402,10168.34,2983.11,0.000,NO,,,
R3773,"Q_RES_0402LF-4.7K,5%,1/16W,EMPTY,CS24702JB10",4.7K,5%,R0402,10294.04,2983.11,180.000,NO,,,
R3775,"Q_RES_0402LF-0,5%,1/16W,CHIP,CS00002JB13",0,5%,R0402,9860.84,2956.41,0.000,NO,,,
R3776,"Q_RES_0402LF-0,5%,1/16W,CHIP,CS00002JB13",0,5%,R0402,5536.20,357.62,270.000,YES,,,
R3777,"Q_RES_0402LF-0,5%,1/16W,CHIP,CS00002JB13",0,5%,R0402,5391.20,355.62,270.000,YES,,,
R3778,"Q_RES_0402LF-0,5%,1/16W,CHIP,CS00002JB13",0,5%,R0402,7093.03,547.11,90.000,YES,,,
R3779,"Q_RES_0402LF-0,5%,1/16W,CHIP,CS00002JB13",0,5%,R0402,9429.45,1890.52,180.000,NO,,,
R3783,"Q_RES_0402LF-100K,1%,1/16W,EMPTY,CS41002FB09",100K,1%,R0402,16940.04,4014.85,180.000,NO,,,
R3784,"Q_RES_0402LF-0,5%,1/16W,CHIP,CS00002JB13",0,5%,R0402,17913.90,1568.34,180.000,NO,,,
R3785,"Q_RES_0402LF-0,5%,1/16W,CHIP,CS00002JB13",0,5%,R0402,16905.60,4286.12,90.000,YES,,,
R3794,"Q_RES_0402LF-0,5%,1/16W,EMPTY,CS00002JB13",0,5%,R0402,16885.04,4030.60,270.000,NO,,,
R3796,"Q_RES_0402LF-100K,1%,1/16W,CHIP,CS41002FB09",100K,1%,R0402,17013.84,4014.85,0.000,NO,,,
R3797,"Q_RES_0402LF-100K,1%,1/16W,CHIP,CS41002FB09",100K,1%,R0402,17907.38,764.87,270.000,NO,,,
R3799,"Q_RES_0402LF-100K,1%,1/16W,CHIP,CS41002FB09",100K,1%,R0402,17907.38,838.67,90.000,NO,,,
R3807,"Q_RES_0402LF-0,5%,1/16W,CHIP,CS00002JB13",0,5%,R0402,3717.93,2394.52,0.000,YES,,,
R3816,"Q_RES_0402LF-100K,1%,1/16W,CHIP,CS41002FB09",100K,1%,R0402,3256.17,827.43,90.000,NO,,,
R3825,"Q_RES_0402LF-100K,1%,1/16W,CHIP,CS41002FB09",100K,1%,R0402,3256.17,753.63,270.000,NO,,,
R3826,"Q_RES_0402LF-100K,1%,1/16W,EMPTY,CS41002FB09",100K,1%,R0402,3446.70,2291.80,180.000,NO,,,
R3827,"Q_RES_0402LF-0,5%,1/16W,CHIP,CS00002JB13",0,5%,R0402,2601.00,1554.62,90.000,NO,,,
R3831,"Q_RES_0402LF-0,5%,1/16W,CHIP,CS00002JB13",0,5%,R0402,3240.42,698.63,0.000,NO,,,
R3832,"Q_RES_0402LF-0,5%,1/16W,EMPTY,CS00002JB13",0,5%,R0402,3466.95,2355.55,270.000,NO,,,
R3833,"Q_RES_0402LF-100K,1%,1/16W,CHIP,CS41002FB09",100K,1%,R0402,3447.16,2250.70,0.000,NO,,,
R3834,"Q_RES_0402LF-0,5%,1/16W,EMPTY,CS00002JB13",0,5%,R0402,17509.18,1266.67,270.000,NO,,,
R3836,"Q_RES_0402LF-10K,1%,1/16W,CHIP,CS31002FB08",10K,1%,R0402,6819.53,1158.68,0.000,NO,,,
R3845,"Q_RES_0402LF-0,5%,1/16W,EMPTY,CS00002JB13",0,5%,R0402,16537.90,4300.44,270.000,NO,,,
R3848,"Q_RES_0402LF-10K,1%,1/16W,CHIP,CS31002FB08",10K,1%,R0402,2487.97,1117.43,0.000,NO,,,
R3858,"Q_RES_0402LF-33.2,1%,1/16W,CHIP,CS03322FB03",33.2,1%,R0402,6709.64,317.42,270.000,YES,,,
R3859,"Q_RES_0402LF-0,5%,1/16W,EMPTY,CS00002JB13",0,5%,R0402,12265.43,1282.39,0.000,NO,,,
R3860,"Q_RES_0402LF-0,5%,1/16W,EMPTY,CS00002JB13",0,5%,R0402,12296.93,1282.39,180.000,NO,,,
R3861,"Q_RES_0402LF-0,5%,1/16W,CHIP,CS00002JB13",0,5%,R0402,12710.12,1760.51,0.000,NO,,,
R3862,"Q_RES_0402LF-0,5%,1/16W,EMPTY,CS00002JB13",0,5%,R0402,12741.62,1760.51,180.000,NO,,,
R3863,"Q_RES_0402LF-0,5%,1/16W,EMPTY,CS00002JB13",0,5%,R0402,12265.43,1327.39,0.000,NO,,,
R3864,"Q_RES_0402LF-0,5%,1/16W,EMPTY,CS00002JB13",0,5%,R0402,12296.93,1327.39,180.000,NO,,,
R3865,"Q_RES_0402LF-0,5%,1/16W,CHIP,CS00002JB13",0,5%,R0402,12741.62,1805.65,180.000,NO,,,
R3866,"Q_RES_0402LF-0,5%,1/16W,EMPTY,CS00002JB13",0,5%,R0402,12710.12,1805.65,0.000,NO,,,
R3867,"Q_RES_0402LF-0,5%,1/16W,EMPTY,CS00002JB13",0,5%,R0402,2382.97,1255.43,270.000,NO,,,
R3868,"Q_RES_0402LF-0,5%,1/16W,CHIP,CS00002JB13",0,5%,R0402,2367.22,1271.18,180.000,NO,,,
R3869,"Q_RES_0402LF-0,5%,1/16W,EMPTY,CS00002JB13",0,5%,R0402,17134.18,1266.67,270.000,NO,,,
R3870,"Q_RES_0402LF-0,5%,1/16W,CHIP,CS00002JB13",0,5%,R0402,17133.12,1397.22,90.000,NO,,,
R3871,"Q_RES_0402LF-0,5%,1/16W,CHIP,CS00002JB13",0,5%,R0402,17214.18,1266.67,90.000,NO,,,
R3872,"Q_RES_0402LF-0,5%,1/16W,EMPTY,CS00002JB13",0,5%,R0402,17174.18,1266.67,90.000,NO,,,
R3873,"Q_RES_0402LF-0,5%,1/16W,CHIP,CS00002JB13",0,5%,R0402,2462.97,1255.43,90.000,NO,,,
R3874,"Q_RES_0402LF-0,5%,1/16W,EMPTY,CS00002JB13",0,5%,R0402,2422.97,1255.43,90.000,NO,,,
R3907,"Q_RES_0402LF-33K,1%,1/16W,CHIP,CS33302FB00",33K,1%,R0402,10682.21,16584.20,90.000,NO,,,
R3909,"Q_RES_0402LF-33.2,1%,1/16W,CHIP,CS03322FB03",33.2,1%,R0402,7176.94,16032.28,90.000,YES,,,
R3923,"Q_RES_0402LF-63.4K,1%,1/16W,CHIP,CS36342FB04",63.4K,1%,R0402,10439.70,16520.82,0.000,NO,,,
R3924,"Q_RES_0402LF-0,5%,1/16W,CHIP,CS00002JB13",0,5%,R0402,7217.50,15907.53,180.000,YES,,,
R3925,"Q_RES_0402LF-1K,1%,1/16W,CHIP,CS21002FB06",1K,1%,R0402,7171.10,16010.23,90.000,NO,,,
R3933,"Q_RES_0402LF-16.9K,1%,1/16W,CHIP,CS31692FB03",16.9K,1%,R0402,7035.00,16085.00,0.000,NO,,,
R3934,"Q_RES_0402LF-22,1%,1/16W,CHIP,CS02202FB02",22,1%,R0402,7536.10,15760.23,0.000,NO,,,
R3936,"Q_RES_0402LF-4.7K,1%,1/16W,CHIP,CS24702FB06",4.7K,1%,R0402,7530.10,15775.98,90.000,YES,,,
R3939,"Q_RES_0402LF-0,5%,1/16W,EMPTY,CS00002JB13",0,5%,R0402,12820.28,1364.23,90.000,YES,,,
R3940,"Q_RES_0402LF-0,5%,1/16W,EMPTY,CS00002JB13",0,5%,R0402,12820.28,1332.73,270.000,YES,,,
R3941,"Q_RES_0402LF-0,5%,1/16W,CHIP,CS00002JB13",0,5%,R0402,12424.61,1588.10,270.000,YES,,,
R3942,"Q_RES_0402LF-0,5%,1/16W,EMPTY,CS00002JB13",0,5%,R0402,12424.61,1619.60,90.000,YES,,,
R3943,"Q_RES_0402LF-0,5%,1/16W,CHIP,CS00002JB13",0,5%,R0402,10153.20,1944.99,180.000,NO,,,
R3946,"Q_RES_0402LF-0,5%,1/16W,CHIP,CS00002JB13",0,5%,R0402,7897.66,2748.22,180.000,NO,,,
R3948,"Q_RES_0402LF-10K,1%,1/16W,CHIP,CS31002FB08",10K,1%,R0402,10013.95,2199.23,270.000,NO,,,
R3955,"Q_RES_0402LF-0,5%,1/16W,CHIP,CS00002JB13",0,5%,R0402,10151.95,2264.23,0.000,NO,,,
R3956,"Q_RES_0402LF-0,5%,1/16W,EMPTY,CS00002JB13",0,5%,R0402,10151.95,2224.23,0.000,NO,,,
R3958,"Q_RES_0402LF-0,5%,1/16W,CHIP,CS00002JB13",0,5%,R0402,9845.55,1789.83,90.000,YES,,,
R3959,"Q_RES_0402LF-0,5%,1/16W,CHIP,CS00002JB13",0,5%,R0402,8625.28,2663.82,270.000,YES,,,
R3972,"Q_RES_0402LF-0,5%,1/16W,CHIP,CS00002JB13",0,5%,R0402,9855.00,1537.99,270.000,NO,,,
R3973,"Q_RES_0402LF-0,5%,1/16W,CHIP,CS00002JB13",0,5%,R0402,8854.28,2674.07,0.000,NO,,,
R3974,"Q_RES_0402LF-0,5%,1/16W,EMPTY,CS00002JB13",0,5%,R0402,10151.95,2304.23,180.000,NO,,,
R3975,"Q_RES_0402LF-0,5%,1/16W,CHIP,CS00002JB13",0,5%,R0402,10167.70,2319.98,90.000,NO,,,
R3976,"Q_RES_0402LF-100K,1%,1/16W,CHIP,CS41002FB09",100K,1%,R0402,10000.00,1522.99,180.000,NO,,,
R3977,"Q_RES_0402LF-100K,1%,1/16W,CHIP,CS41002FB09",100K,1%,R0402,8865.03,2802.87,90.000,NO,,,
R3978,"Q_RES_0402LF-100K,1%,1/16W,CHIP,CS41002FB09",100K,1%,R0402,9930.00,1522.99,180.000,NO,,,
R3979,"Q_RES_0402LF-100K,1%,1/16W,CHIP,CS41002FB09",100K,1%,R0402,8865.03,2729.07,270.000,NO,,,
R3996,"Q_RES_0402LF-0,5%,1/16W,CHIP,CS00002JB13",0,5%,R0402,7762.89,1580.26,0.000,NO,,,
R3997,"Q_RES_0402LF-0,5%,1/16W,CHIP,CS00002JB13",0,5%,R0402,7497.35,1614.63,180.000,NO,,,
R3998,"Q_RES_0402LF-0,5%,1/16W,CHIP,CS00002JB13",0,5%,R0402,7089.53,1296.68,270.000,NO,,,
R4013,"Q_RES_0402LF-100K,1%,1/16W,CHIP,CS41002FB09",100K,1%,R0402,7601.93,1022.28,90.000,NO,,,
R4015,"Q_RES_0402LF-100K,1%,1/16W,CHIP,CS41002FB09",100K,1%,R0402,7601.93,948.48,270.000,NO,,,
R4058,"Q_RES_0402LF-10K,1%,1/16W,CHIP,CS31002FB08",10K,1%,R0402,3829.92,16764.46,270.000,NO,,,
R4059,"Q_RES_0402LF-0,5%,1/16W,EMPTY,CS00002JB13",0,5%,R0402,2581.61,1408.82,0.000,NO,,,
R4060,"Q_RES_0402LF-0,5%,1/16W,EMPTY,CS00002JB13",0,5%,R0402,2335.95,1535.71,90.000,NO,,,
R4061,"Q_RES_0402LF-0,5%,1/16W,EMPTY,CS00002JB13",0,5%,R0402,18462.91,1658.34,180.000,NO,,,
R4062,"Q_RES_0402LF-0,5%,1/16W,CHIP,CS00002JB13",0,5%,R0402,7764.20,1632.54,180.000,NO,,,
R4063,"Q_RES_0402LF-0,5%,1/16W,CHIP,CS00002JB13",0,5%,R0402,9864.55,2714.43,0.000,NO,,,
R4064,"Q_RES_0402LF-0,5%,1/16W,CHIP,CS00002JB13",0,5%,R0402,9864.55,2607.81,0.000,NO,,,
R4065,"Q_RES_0402LF-10K,1%,1/16W,CHIP,CS31002FB08",10K,1%,R0402,2357.00,1420.62,180.000,NO,,,
R4066,"Q_RES_0402LF-4.7K,5%,1/16W,EMPTY,CS24702JB10",4.7K,5%,R0402,2320.20,1590.71,180.000,NO,,,
R4067,"Q_RES_0402LF-10K,1%,1/16W,CHIP,CS31002FB08",10K,1%,R0402,2547.56,1583.02,90.000,NO,,,
R4068,"Q_RES_0402LF-10K,1%,1/16W,CHIP,CS31002FB08",10K,1%,R0402,18197.05,1583.72,270.000,NO,,,
R4069,"Q_RES_0402LF-4.7K,5%,1/16W,EMPTY,CS24702JB10",4.7K,5%,R0402,17913.90,1618.34,180.000,NO,,,
R4070,"Q_RES_0402LF-10K,1%,1/16W,CHIP,CS31002FB08",10K,1%,R0402,18197.05,1653.72,90.000,NO,,,
R4071,"Q_RES_0402LF-10K,1%,1/16W,CHIP,CS31002FB08",10K,1%,R0402,7497.00,1675.37,0.000,NO,,,
R4072,"Q_RES_0402LF-10K,1%,1/16W,CHIP,CS31002FB08",10K,1%,R0402,10148.28,2724.27,90.000,NO,,,
R4073,"Q_RES_0402LF-4.7K,5%,1/16W,CHIP,CS24702JB10",4.7K,5%,R0402,9864.55,2647.81,180.000,NO,,,
R4074,"Q_RES_0402LF-10K,1%,1/16W,CHIP,CS31002FB08",10K,1%,R0402,10148.28,2632.65,90.000,NO,,,
R4075,"Q_RES_0402LF-0,5%,1/16W,CHIP,CS00002JB13",0,5%,R0402,584.02,5060.85,90.000,NO,,,
R4076,"Q_RES_0402LF-0,5%,1/16W,CHIP,CS00002JB13",0,5%,R0402,631.48,5482.60,270.000,NO,,,
R4077,"Q_RES_0402LF-1,1%,1/16W,CHIP,CS-1002FB04",1,1%,R0402,607.72,5334.15,90.000,YES,,,
R4078,"Q_RES_0402LF-10K,1%,1/16W,EMPTY,CS31002FB08",10K,1%,R0402,532.99,5482.95,270.000,NO,,,
R4079,"Q_RES_0402LF-10K,1%,1/16W,CHIP,CS31002FB08",10K,1%,R0402,486.26,5482.60,90.000,NO,,,
R4080,"Q_RES_0402LF-10K,1%,1/16W,CHIP,CS31002FB08",10K,1%,R0402,583.65,5482.60,270.000,NO,,,
R4081,"Q_RES_0402LF-10K,1%,1/16W,CHIP,CS31002FB08",10K,1%,R0402,328.12,5170.25,0.000,NO,,,
R4082,"Q_RES_0402LF-10K,1%,1/16W,EMPTY,CS31002FB08",10K,1%,R0402,203.32,5169.51,180.000,NO,,,
R4087,"Q_RES_0402LF-0,5%,1/16W,CHIP,CS00002JB13",0,5%,R0402,5762.00,542.22,90.000,YES,,,
R4090,"Q_RES_0402LF-1K,1%,1/16W,CHIP,CS21002FB06",1K,1%,R0402,5925.23,2089.91,0.000,NO,,,
R4091,"Q_RES_0402LF-1K,1%,1/16W,CHIP,CS21002FB06",1K,1%,R0402,8393.60,1190.82,90.000,NO,,,
R4092,"Q_RES_0402LF-1K,1%,1/16W,CHIP,CS21002FB06",1K,1%,R0402,2685.50,1428.92,0.000,NO,,,
R4093,"Q_RES_0402LF-1K,1%,1/16W,CHIP,CS21002FB06",1K,1%,R0402,8375.00,2246.52,90.000,YES,,,
R4094,"Q_RES_0402LF-1K,1%,1/16W,CHIP,CS21002FB06",1K,1%,R0402,17662.20,3724.52,180.000,NO,,,
R4119,"Q_RES_0402LF-54.9K,1%,1/16W,EMPTY,CS35492FB03",54.9K,1%,R0402,6519.67,16415.22,180.000,YES,,,
R4120,"Q_RES_0402LF-100K,1%,1/16W,EMPTY,CS41002FB09",100K,1%,R0402,6519.67,16455.22,0.000,YES,,,
R4121,"Q_RES_0402LF-10K,1%,1/16W,CHIP,CS31002FB08",10K,1%,R0402,6432.58,17092.70,270.000,YES,,,
R4122,"Q_RES_0402LF-100K,1%,1/16W,EMPTY,CS41002FB09",100K,1%,R0402,6472.58,17092.70,90.000,YES,,,
R4123,"Q_RES_0402LF-54.9K,1%,1/16W,EMPTY,CS35492FB03",54.9K,1%,R0402,6472.58,16952.70,270.000,YES,,,
R4124,"Q_RES_0402LF-100K,1%,1/16W,EMPTY,CS41002FB09",100K,1%,R0402,6432.58,16952.70,90.000,YES,,,
R4125,"Q_RES_0402LF-4.7K,5%,1/16W,CHIP,CS24702JB10",4.7K,5%,R0402,6449.42,16368.15,0.000,YES,,,
R4126,"Q_RES_0402LF-4.7K,5%,1/16W,CHIP,CS24702JB10",4.7K,5%,R0402,6680.58,17159.52,90.000,YES,,,
R4127,"Q_RES_0402LF-4.7K,5%,1/16W,CHIP,CS24702JB10",4.7K,5%,R0402,6698.00,17001.64,0.000,YES,,,
R4128,"Q_RES_0402LF-100K,1%,1/16W,CHIP,CS41002FB09",100K,1%,R0402,6589.67,16455.22,0.000,YES,,,
R4129,"Q_RES_0402LF-100K,1%,1/16W,CHIP,CS41002FB09",100K,1%,R0402,6432.58,17162.70,90.000,YES,,,
R4130,"Q_RES_0402LF-100K,1%,1/16W,CHIP,CS41002FB09",100K,1%,R0402,6432.58,17022.70,90.000,YES,,,
R4131,"Q_RES_0402LF-54.9K,1%,1/16W,EMPTY,CS35492FB03",54.9K,1%,R0402,11980.37,16938.50,180.000,NO,,,
R4132,"Q_RES_0402LF-100K,1%,1/16W,EMPTY,CS41002FB09",100K,1%,R0402,11980.37,16978.50,0.000,NO,,,
R4133,"Q_RES_0402LF-54.9K,1%,1/16W,EMPTY,CS35492FB03",54.9K,1%,R0402,12102.54,17224.36,90.000,NO,,,
R4134,"Q_RES_0402LF-100K,1%,1/16W,EMPTY,CS41002FB09",100K,1%,R0402,12142.54,17224.36,270.000,NO,,,
R4135,"Q_RES_0402LF-10K,1%,1/16W,CHIP,CS31002FB08",10K,1%,R0402,12133.79,16938.59,180.000,NO,,,
R4136,"Q_RES_0402LF-100K,1%,1/16W,EMPTY,CS41002FB09",100K,1%,R0402,12133.79,16978.59,0.000,NO,,,
R4137,"Q_RES_0402LF-4.7K,5%,1/16W,CHIP,CS24702JB10",4.7K,5%,R0402,11913.55,16730.50,0.000,NO,,,
R4138,"Q_RES_0402LF-4.7K,5%,1/16W,CHIP,CS24702JB10",4.7K,5%,R0402,12014.77,17318.03,180.000,NO,,,
R4139,"Q_RES_0402LF-4.7K,5%,1/16W,CHIP,CS24702JB10",4.7K,5%,R0402,12066.97,16730.59,0.000,NO,,,
R4140,"Q_RES_0402LF-100K,1%,1/16W,CHIP,CS41002FB09",100K,1%,R0402,11910.37,16978.50,0.000,NO,,,
R4141,"Q_RES_0402LF-100K,1%,1/16W,CHIP,CS41002FB09",100K,1%,R0402,12142.54,17294.36,270.000,NO,,,
R4142,"Q_RES_0402LF-100K,1%,1/16W,CHIP,CS41002FB09",100K,1%,R0402,12063.79,16978.59,0.000,NO,,,
R4143,"Q_RES_0402LF-33.2,1%,1/16W,CHIP,CS03322FB03",33.2,1%,R0402,7766.52,4753.44,180.000,YES,,,
R4144,"Q_RES_0402LF-33.2,1%,1/16W,CHIP,CS03322FB03",33.2,1%,R0402,8080.46,4761.59,0.000,NO,,,
R4145,"Q_RES_0402LF-33.2,1%,1/16W,CHIP,CS03322FB03",33.2,1%,R0402,6873.10,5093.62,90.000,NO,,,
R4146,"Q_RES_0402LF-33.2,1%,1/16W,CHIP,CS03322FB03",33.2,1%,R0402,8080.46,4801.59,0.000,NO,,,
R4147,"Q_RES_0402LF-33.2,1%,1/16W,CHIP,CS03322FB03",33.2,1%,R0402,7766.52,4763.44,0.000,NO,,,
R4148,"Q_RES_0402LF-33.2,1%,1/16W,CHIP,CS03322FB03",33.2,1%,R0402,7911.52,4633.44,0.000,NO,,,
R4149,"Q_RES_0402LF-33.2,1%,1/16W,CHIP,CS03322FB03",33.2,1%,R0402,6396.45,700.40,180.000,YES,,,
R4150,"Q_RES_0402LF-33.2,1%,1/16W,CHIP,CS03322FB03",33.2,1%,R0402,6326.45,700.40,0.000,YES,,,
R4151,"Q_RES_0402LF-33.2,1%,1/16W,CHIP,CS03322FB03",33.2,1%,R0402,6396.45,660.40,180.000,YES,,,
R4152,"Q_RES_0402LF-33.2,1%,1/16W,CHIP,CS03322FB03",33.2,1%,R0402,6326.45,660.40,0.000,YES,,,
R4153,"Q_RES_0402LF-10K,1%,1/16W,CHIP,CS31002FB08",10K,1%,R0402,13996.33,16261.67,0.000,NO,,,
R4154,"Q_RES_0402LF-100K,1%,1/16W,EMPTY,CS41002FB09",100K,1%,R0402,13996.33,16221.67,180.000,NO,,,
R4155,"Q_RES_0402LF-4.7K,5%,1/16W,CHIP,CS24702JB10",4.7K,5%,R0402,14063.15,16469.67,180.000,NO,,,
R4156,"Q_RES_0402LF-100K,1%,1/16W,CHIP,CS41002FB09",100K,1%,R0402,14066.33,16261.67,180.000,NO,,,
R4157,"Q_RES_0402LF-33.2,1%,1/16W,CHIP,CS03322FB03",33.2,1%,R0402,7913.21,4676.46,0.000,NO,,,
R4158,"Q_RES_0402LF-54.9K,1%,1/16W,EMPTY,CS35492FB03",54.9K,1%,R0402,16545.13,17171.84,270.000,NO,,,
R4159,"Q_RES_0402LF-100K,1%,1/16W,EMPTY,CS41002FB09",100K,1%,R0402,16505.13,17171.84,90.000,NO,,,
R4160,"Q_RES_0402LF-54.9K,1%,1/16W,EMPTY,CS35492FB03",54.9K,1%,R0402,17286.33,17288.40,270.000,NO,,,
R4161,"Q_RES_0402LF-100K,1%,1/16W,EMPTY,CS41002FB09",100K,1%,R0402,17246.33,17288.40,90.000,NO,,,
R4162,"Q_RES_0402LF-54.9K,1%,1/16W,EMPTY,CS35492FB03",54.9K,1%,R0402,16893.83,17181.68,270.000,YES,,,
R4163,"Q_RES_0402LF-100K,1%,1/16W,EMPTY,CS41002FB09",100K,1%,R0402,16853.83,17181.68,90.000,YES,,,
R4164,"Q_RES_0402LF-4.7K,5%,1/16W,CHIP,CS24702JB10",4.7K,5%,R0402,16753.60,17105.02,90.000,NO,,,
R4165,"Q_RES_0402LF-4.7K,5%,1/16W,CHIP,CS24702JB10",4.7K,5%,R0402,17494.80,17221.58,90.000,NO,,,
R4166,"Q_RES_0402LF-4.7K,5%,1/16W,CHIP,CS24702JB10",4.7K,5%,R0402,17102.30,17248.50,90.000,YES,,,
R4167,"Q_RES_0402LF-100K,1%,1/16W,CHIP,CS41002FB09",100K,1%,R0402,16505.13,17101.84,90.000,NO,,,
R4168,"Q_RES_0402LF-100K,1%,1/16W,CHIP,CS41002FB09",100K,1%,R0402,17246.33,17218.40,90.000,NO,,,
R4169,"Q_RES_0402LF-100K,1%,1/16W,CHIP,CS41002FB09",100K,1%,R0402,16853.83,17251.68,90.000,YES,,,
R4170,"Q_RES_0402LF-33.2,1%,1/16W,CHIP,CS03322FB03",33.2,1%,R0402,7766.52,4633.44,180.000,YES,,,
R4171,"Q_RES_0402LF-33.2,1%,1/16W,CHIP,CS03322FB03",33.2,1%,R0402,7766.52,4553.44,0.000,NO,,,
R4172,"Q_RES_0402LF-33.2,1%,1/16W,CHIP,CS03322FB03",33.2,1%,R0402,7911.52,4513.44,0.000,NO,,,
R4173,"Q_RES_0402LF-100K,1%,1/16W,EMPTY,CS41002FB09",100K,1%,R0402,14203.15,16469.67,180.000,NO,,,
R4178,"Q_RES_0402LF-33.2,1%,1/16W,CHIP,CS03322FB03",33.2,1%,R0402,3898.24,16257.13,90.000,NO,,,
R4179,"Q_RES_0402LF-33.2,1%,1/16W,CHIP,CS03322FB03",33.2,1%,R0402,11346.38,565.12,0.000,NO,,,
R4180,"Q_RES_0402LF-33.2,1%,1/16W,CHIP,CS03322FB03",33.2,1%,R0402,14455.00,16285.00,90.000,NO,,,
R4181,"Q_RES_0402LF-33.2,1%,1/16W,CHIP,CS03322FB03",33.2,1%,R0402,3848.24,16257.13,90.000,NO,,,
R4182,"Q_RES_0402LF-33.2,1%,1/16W,CHIP,CS03322FB03",33.2,1%,R0402,11488.18,747.38,0.000,NO,,,
R4183,"Q_RES_0402LF-33.2,1%,1/16W,CHIP,CS03322FB03",33.2,1%,R0402,14405.00,16285.00,90.000,NO,,,
R4184,"Q_RES_0402LF-1K,1%,1/16W,EMPTY,CS21002FB06",1K,1%,R0402,4875.43,550.95,180.000,NO,,,
R4185,"Q_RES_0402LF-1K,1%,1/16W,CHIP,CS21002FB06",1K,1%,R0402,4737.83,551.35,0.000,NO,,,
R4186,"Q_RES_0402LF-1K,1%,1/16W,EMPTY,CS21002FB06",1K,1%,R0402,3973.24,16764.95,270.000,NO,,,
R4187,"Q_RES_0402LF-1K,1%,1/16W,CHIP,CS21002FB06",1K,1%,R0402,3998.24,16631.20,90.000,NO,,,
R4188,"Q_RES_0402LF-1K,1%,1/16W,EMPTY,CS21002FB06",1K,1%,R0402,11802.07,528.15,180.000,NO,,,
R4189,"Q_RES_0402LF-1K,1%,1/16W,CHIP,CS21002FB06",1K,1%,R0402,11943.07,528.15,0.000,NO,,,
R4190,"Q_RES_0402LF-1K,1%,1/16W,EMPTY,CS21002FB06",1K,1%,R0402,14617.02,16693.88,270.000,NO,,,
R4191,"Q_RES_0402LF-1K,1%,1/16W,CHIP,CS21002FB06",1K,1%,R0402,14575.79,16693.03,90.000,NO,,,
R4192,"Q_RES_0402LF-1K,1%,1/16W,EMPTY,CS21002FB06",1K,1%,R0402,4873.83,601.05,180.000,NO,,,
R4193,"Q_RES_0402LF-1K,1%,1/16W,CHIP,CS21002FB06",1K,1%,R0402,4738.53,600.29,0.000,NO,,,
R4194,"Q_RES_0402LF-1K,1%,1/16W,EMPTY,CS21002FB06",1K,1%,R0402,3923.24,16764.95,270.000,NO,,,
R4195,"Q_RES_0402LF-1K,1%,1/16W,CHIP,CS21002FB06",1K,1%,R0402,3948.24,16631.20,90.000,NO,,,
R4196,"Q_RES_0402LF-1K,1%,1/16W,EMPTY,CS21002FB06",1K,1%,R0402,11801.87,570.15,180.000,NO,,,
R4197,"Q_RES_0402LF-1K,1%,1/16W,CHIP,CS21002FB06",1K,1%,R0402,11943.87,570.15,0.000,NO,,,
R4198,"Q_RES_0402LF-1K,1%,1/16W,EMPTY,CS21002FB06",1K,1%,R0402,14490.70,16827.22,270.000,NO,,,
R4199,"Q_RES_0402LF-1K,1%,1/16W,CHIP,CS21002FB06",1K,1%,R0402,14525.79,16693.03,90.000,NO,,,
R4200,"Q_RES_0402LF-1K,1%,1/16W,EMPTY,CS21002FB06",1K,1%,R0402,4872.73,649.65,180.000,NO,,,
R4201,"Q_RES_0402LF-1K,1%,1/16W,CHIP,CS21002FB06",1K,1%,R0402,4738.53,649.75,0.000,NO,,,
R4202,"Q_RES_0402LF-1K,1%,1/16W,EMPTY,CS21002FB06",1K,1%,R0402,3873.24,16764.95,270.000,NO,,,
R4203,"Q_RES_0402LF-1K,1%,1/16W,CHIP,CS21002FB06",1K,1%,R0402,3898.24,16631.20,90.000,NO,,,
R4204,"Q_RES_0402LF-1K,1%,1/16W,EMPTY,CS21002FB06",1K,1%,R0402,11801.87,615.15,180.000,NO,,,
R4205,"Q_RES_0402LF-1K,1%,1/16W,CHIP,CS21002FB06",1K,1%,R0402,11942.87,615.15,0.000,NO,,,
R4206,"Q_RES_0402LF-1K,1%,1/16W,EMPTY,CS21002FB06",1K,1%,R0402,14450.79,16826.78,270.000,NO,,,
R4207,"Q_RES_0402LF-1K,1%,1/16W,CHIP,CS21002FB06",1K,1%,R0402,14475.79,16693.03,90.000,NO,,,
R4208,"Q_RES_0402LF-200K,1%,1/16W,EMPTY,CS42002FB05",200K,1%,R0402,4210.00,547.62,180.000,NO,,,
R4209,"Q_RES_0402LF-200K,1%,1/16W,EMPTY,CS42002FB05",200K,1%,R0402,11282.33,526.51,0.000,NO,,,
R4210,"Q_RES_0402LF-200K,1%,1/16W,EMPTY,CS42002FB05",200K,1%,R0402,3990.00,16257.13,270.000,NO,,,
R4211,"Q_RES_0402LF-200K,1%,1/16W,CHIP,CS42002FB05",200K,1%,R0402,14505.00,16190.00,90.000,NO,,,
R4212,"Q_RES_0402LF-0,5%,1/16W,CHIP,CS00002JB13",0,5%,R0402,4209.93,599.35,0.000,NO,,,
R4213,"Q_RES_0402LF-0,5%,1/16W,CHIP,CS00002JB13",0,5%,R0402,3948.24,16257.13,90.000,NO,,,
R4214,"Q_RES_0402LF-0,5%,1/16W,CHIP,CS00002JB13",0,5%,R0402,11354.06,525.99,0.000,NO,,,
R4215,"Q_RES_0402LF-0,5%,1/16W,CHIP,CS00002JB13",0,5%,R0402,14505.00,16285.00,90.000,NO,,,
R4264,"Q_RES_0402LF-4.7K,5%,1/16W,CHIP,CS24702JB10",4.7K,5%,R0402,11010.64,16960.29,180.000,NO,,,
R4265,"Q_RES_0402LF-4.7K,5%,1/16W,EMPTY,CS24702JB10",4.7K,5%,R0402,10931.14,16912.29,180.000,NO,,,
R4266,"Q_RES_0402LF-33.2,1%,1/16W,CHIP,CS03322FB03",33.2,1%,R0402,10931.14,16872.29,180.000,NO,,,
R4268,"Q_RES_0402LF-0,5%,1/16W,CHIP,CS00002JB13",0,5%,R0402,11098.64,17112.44,180.000,NO,,,
R4269,"Q_RES_0402LF-2.2K,5%,1/16W,EMPTY,CS22202JB07",2.2K,5%,R0402,10762.10,4837.82,180.000,NO,,,
R4270,"Q_RES_0402LF-2.2K,5%,1/16W,EMPTY,CS22202JB07",2.2K,5%,R0402,10762.10,4877.82,180.000,NO,,,
R4303,"Q_RES_0402LF-0,5%,1/16W,CHIP,CS00002JB13",0,5%,R0402,13524.21,11886.27,270.000,YES,,,
R4304,"Q_RES_0402LF-0,5%,1/16W,CHIP,CS00002JB13",0,5%,R0402,13484.21,11886.27,270.000,YES,,,
R4305,"Q_RES_0402LF-0,5%,1/16W,CHIP,CS00002JB13",0,5%,R0402,4835.00,12663.62,90.000,NO,,,
R4306,"Q_RES_0402LF-0,5%,1/16W,CHIP,CS00002JB13",0,5%,R0402,4875.00,12663.62,90.000,NO,,,
R4419,"Q_RES_0402LF-49.9,1%,1/16W,EMPTY,CS04992FB07",49.9,1%,R0402,561.63,4155.03,90.000,NO,,,
R4420,"Q_RES_0402LF-49.9,1%,1/16W,EMPTY,CS04992FB07",49.9,1%,R0402,695.23,4155.03,90.000,NO,,,
R4450,"Q_RES_0402LF-0,5%,1/16W,CHIP,CS00002JB13",0,5%,R0402,5541.96,1862.56,90.000,NO,,,
R4451,"Q_RES_0402LF-33.2,1%,1/16W,CHIP,CS03322FB03",33.2,1%,R0402,4906.82,1895.16,0.000,NO,,,
R4452,"Q_RES_0402LF-10K,1%,1/16W,EMPTY,CS31002FB08",10K,1%,R0402,4906.82,1935.16,0.000,NO,,,
R4453,"Q_RES_0402LF-47K,0.1%,1/16W,EMPTY,CS34702BB05",47K,0.1%,R0402,4906.82,1975.16,180.000,NO,,,
R4475,"Q_RES_0603LF-1,1%,1/10W,CHIP,CS-1003F900",1,1%,R0603_H24,11100.00,16780.00,270.000,NO,,,
R4476,"Q_RES_0402LF-10K,1%,1/16W,CHIP,CS31002FB08",10K,1%,R0402,11090.00,16670.00,270.000,NO,,,
R4482,"Q_RES_0402LF-49.9,1%,1/16W,EMPTY,CS04992FB07",49.9,1%,R0402,586.07,4237.46,180.000,NO,,,
R4483,"Q_RES_0402LF-49.9,1%,1/16W,EMPTY,CS04992FB07",49.9,1%,R0402,671.08,4237.46,0.000,NO,,,
R4489,"Q_RES_0402LF-4.75K,1%,1/16W,CHIP,CS24752FB03",4.75K,1%,R0402,11005.00,16390.00,0.000,NO,,,
R4490,"Q_RES_0402LF-4.75K,1%,1/16W,EMPTY,CS24752FB03",4.75K,1%,R0402,11005.00,16425.00,180.000,NO,,,
R4491,"Q_RES_0402LF-10K,1%,1/16W,CHIP,CS31002FB08",10K,1%,R0402,11125.00,16670.00,270.000,NO,,,
R4492,"Q_RES_0402LF-10K,1%,1/16W,CHIP,CS31002FB08",10K,1%,R0402,11160.00,16670.00,90.000,NO,,,
R4493,"Q_RES_0603LF-1,1%,1/10W,CHIP,CS-1003F900",1,1%,R0603_H24,11152.17,16779.75,270.000,NO,,,
R4501,"Q_RES_0402LF-0,5%,1/16W,CHIP,CS00002JB13",0,5%,R0402,363.72,5327.95,90.000,NO,,,
R4506,"Q_RES_0402LF-33.2,1%,1/16W,CHIP,CS03322FB03",33.2,1%,R0402,6985.97,541.82,90.000,YES,,,
R4507,"Q_RES_0402LF-33.2,1%,1/16W,CHIP,CS03322FB03",33.2,1%,R0402,6944.00,541.82,90.000,YES,,,
R4508,"Q_RES_0402LF-33.2,1%,1/16W,CHIP,CS03322FB03",33.2,1%,R0402,6397.22,537.47,180.000,YES,,,
R4509,"Q_RES_0402LF-33.2,1%,1/16W,CHIP,CS03322FB03",33.2,1%,R0402,6342.20,604.65,90.000,YES,,,
R4514,"Q_RES_0402LF-4.7K,1%,1/16W,EMPTY,CS24702FB06",4.7K,1%,R0402,1429.92,5269.97,0.000,NO,,,
R4515,"Q_RES_0402LF-100K,1%,1/16W,CHIP,CS41002FB09",100K,1%,R0402,14196.22,16117.67,270.000,NO,,,
R4518,"Q_RES_0402LF-10K,1%,1/16W,CHIP,CS31002FB08",10K,1%,R0402,11441.07,16670.66,90.000,NO,,,
R4519,"Q_RES_0402LF-10K,1%,1/16W,CHIP,CS31002FB08",10K,1%,R0402,11360.97,16249.68,270.000,NO,,,
R4520,"Q_RES_0402LF-10K,1%,1/16W,CHIP,CS31002FB08",10K,1%,R0402,11321.68,16249.65,270.000,NO,,,
R4521,"Q_RES_0402LF-1K,1%,1/16W,CHIP,CS21002FB06",1K,1%,R0402,644.42,5059.65,270.000,NO,,,
R4532,"Q_RES_0402LF-10K,1%,1/16W,CHIP,CS31002FB08",10K,1%,R0402,17239.18,1128.67,0.000,NO,,,
R4535,"Q_RES_0402LF-0,5%,1/16W,CHIP,CS00002JB13",0,5%,R0402,14655.59,8445.82,90.000,YES,,,
R4536,"Q_RES_0402LF-0,5%,1/16W,CHIP,CS00002JB13",0,5%,R0402,14611.59,8445.82,90.000,YES,,,
R4537,"Q_RES_0402LF-0,5%,1/16W,CHIP,CS00002JB13",0,5%,R0402,1513.53,16920.87,90.000,NO,,,
R4543,"Q_RES_0402LF-1K,1%,1/16W,CHIP,CS21002FB06",1K,1%,R0402,4120.00,16375.00,90.000,YES,,,
R4544,"Q_RES_0402LF-100K,1%,1/16W,EMPTY,CS41002FB09",100K,1%,R0402,4080.00,16375.00,270.000,YES,,,
R4545,"Q_RES_0402LF-4.7K,5%,1/16W,CHIP,CS24702JB10",4.7K,5%,R0402,4385.00,16415.00,180.000,YES,,,
R4546,"Q_RES_0402LF-100K,1%,1/16W,EMPTY,CS41002FB09",100K,1%,R0402,4116.36,16253.24,90.000,YES,,,
R4547,"Q_RES_0402LF-100K,1%,1/16W,EMPTY,CS41002FB09",100K,1%,R0402,13838.04,17331.18,0.000,NO,,,
R4548,"Q_RES_0402LF-100K,1%,1/16W,CHIP,CS41002FB09",100K,1%,R0402,13886.04,17283.18,180.000,NO,,,
R4549,"Q_RES_0402LF-4.7K,5%,1/16W,EMPTY,CS24702JB10",4.7K,5%,R0402,13860.45,17040.38,0.000,NO,,,
R4550,"Q_RES_0402LF-49.9,1%,1/16W,CHIP,CS04992FB07",49.9,1%,R0402,13860.45,17000.38,180.000,NO,,,
R4551,"Q_RES_0402LF-54.9K,1%,1/16W,EMPTY,CS35492FB03",54.9K,1%,R0402,10985.14,17244.16,270.000,NO,,,
R4552,"Q_RES_0402LF-100K,1%,1/16W,CHIP,CS41002FB09",100K,1%,R0402,10945.14,17244.16,90.000,NO,,,
R4553,"Q_RES_0402LF-4.7K,5%,1/16W,CHIP,CS24702JB10",4.7K,5%,R0402,11193.61,17177.34,90.000,NO,,,
R4554,"Q_RES_0402LF-100K,1%,1/16W,CHIP,CS41002FB09",100K,1%,R0402,10985.14,17174.16,90.000,NO,,,
R4555,"Q_RES_0402LF-4.7K,5%,1/16W,EMPTY,CS24702JB10",4.7K,5%,R0402,13860.45,17080.38,180.000,NO,,,
R4556,"Q_RES_0402LF-33.2,1%,1/16W,CHIP,CS03322FB03",33.2,1%,R0402,8077.14,4498.02,0.000,NO,,,
R4557,"Q_RES_0402LF-33.2,1%,1/16W,CHIP,CS03322FB03",33.2,1%,R0402,8079.33,4593.44,180.000,NO,,,
R4558,"Q_RES_0402LF-33.2,1%,1/16W,CHIP,CS03322FB03",33.2,1%,R0402,7766.52,4713.44,180.000,YES,,,
R4559,"Q_RES_0402LF-100K,1%,1/16W,CHIP,CS41002FB09",100K,1%,R0402,13834.93,16703.91,180.000,NO,,,
R4560,"Q_RES_0402LF-4.7K,5%,1/16W,CHIP,CS24702JB10",4.7K,5%,R0402,13901.75,16952.38,180.000,NO,,,
R4561,"Q_RES_0402LF-100K,1%,1/16W,CHIP,CS41002FB09",100K,1%,R0402,13904.93,16743.91,180.000,NO,,,
R4562,"Q_RES_0402LF-100K,1%,1/16W,EMPTY,CS41002FB09",100K,1%,R0402,13834.93,16743.91,0.000,NO,,,
R4563,"Q_RES_0402LF-33.2,1%,1/16W,CHIP,CS03322FB03",33.2,1%,R0402,7911.52,4793.44,180.000,YES,,,
R4567,"Q_RES_0402LF-5.11K,1%,1/16W,CHIP,CS25112FB04",5.11K,1%,R0402,12741.11,1540.30,180.000,NO,,,
R4568,"Q_RES_0402LF-4.7K,1%,1/16W,CHIP,CS24702FB06",4.7K,1%,R0402,12741.11,1500.30,0.000,NO,,,
R4569,"Q_RES_0402LF-0,5%,1/16W,EMPTY,CS00002JB13",0,5%,R0402,16585.13,17133.34,270.000,NO,,,
R4570,"Q_RES_0402LF-0,5%,1/16W,EMPTY,CS00002JB13",0,5%,R0402,16933.83,17220.18,270.000,YES,,,
R4571,"Q_RES_0402LF-0,5%,1/16W,EMPTY,CS00002JB13",0,5%,R0402,17326.33,17249.90,270.000,NO,,,
R4572,"Q_RES_0402LF-0,5%,1/16W,EMPTY,CS00002JB13",0,5%,R0402,6512.58,16991.20,270.000,YES,,,
R4573,"Q_RES_0402LF-0,5%,1/16W,EMPTY,CS00002JB13",0,5%,R0402,6512.58,17131.20,270.000,YES,,,
R4574,"Q_RES_0402LF-0,5%,1/16W,EMPTY,CS00002JB13",0,5%,R0402,14034.83,16301.67,0.000,NO,,,
R4575,"Q_RES_0402LF-0,5%,1/16W,EMPTY,CS00002JB13",0,5%,R0402,6558.17,16375.22,180.000,YES,,,
R4576,"Q_RES_0402LF-0,5%,1/16W,EMPTY,CS00002JB13",0,5%,R0402,12062.54,17262.86,90.000,NO,,,
R4577,"Q_RES_0402LF-0,5%,1/16W,EMPTY,CS00002JB13",0,5%,R0402,11941.87,16898.50,180.000,NO,,,
R4578,"Q_RES_0402LF-0,5%,1/16W,EMPTY,CS00002JB13",0,5%,R0402,12095.29,16898.59,180.000,NO,,,
R4601,"Q_RES_0402LF-0,5%,1/16W,CHIP,CS00002JB13",0,5%,R0402,15159.42,1308.13,180.000,NO,,,
R4602,"Q_RES_0402LF-0,5%,1/16W,CHIP,CS00002JB13",0,5%,R0402,3398.11,1246.77,90.000,NO,,,
R4603,"Q_RES_0402LF-10K,1%,1/16W,CHIP,CS31002FB08",10K,1%,R0402,1160.00,17124.50,0.000,NO,,,
R4604,"Q_RES_0402LF-4.7K,5%,1/16W,CHIP,CS24702JB10",4.7K,5%,R0402,12477.85,3017.32,90.000,YES,,,
R4605,"Q_RES_0402LF-1K,1%,1/16W,CHIP,CS21002FB06",1K,1%,R0402,12220.94,3101.41,90.000,YES,,,
R4608,"Q_RES_0402LF-33.2,1%,1/16W,CHIP,CS03322FB03",33.2,1%,R0402,8224.19,4498.02,180.000,NO,,,
R4620,"Q_RES_0402LF-1K,1%,1/16W,EMPTY,CS21002FB06",1K,1%,R0402,5920.21,4796.31,0.000,NO,,,
R4638,"Q_RES_1206LF-243,1%,1/4W,CHIP,CS12436F201",243,1%,R1206XN,15679.13,5995.70,270.000,YES,,,
R4639,"Q_RES_1206LF-243,1%,1/4W,CHIP,CS12436F201",243,1%,R1206XN,15928.13,5995.70,270.000,YES,,,
R4640,"Q_RES_1206LF-243,1%,1/4W,CHIP,CS12436F201",243,1%,R1206XN,15762.13,5995.70,270.000,YES,,,
R4641,"Q_RES_1206LF-243,1%,1/4W,CHIP,CS12436F201",243,1%,R1206XN,15845.13,5995.70,270.000,YES,,,
R4809,"Q_RES_0402LF-0,5%,1/16W,CHIP,CS00002JB13",0,5%,R0402,5486.10,532.35,270.000,YES,,,
R4901,"Q_RES_0402LF-82K,1%,1/16W,CHIP,CS38202FB01",82K,1%,R0402,10441.02,16462.05,0.000,NO,,,
R5004,"Q_RES_0402LF-10K,1%,1/16W,CHIP,CS31002FB08",10K,1%,R0402,9050.00,9140.00,90.000,YES,,,
R5006,"Q_RES_0402LF-1K,1%,1/16W,EMPTY,CS21002FB06",1K,1%,R0402,11705.32,5806.02,0.000,NO,,,
R5007,"Q_RES_0402LF-1K,1%,1/16W,EMPTY,CS21002FB06",1K,1%,R0402,11705.92,5846.22,0.000,NO,,,
R5008,"Q_RES_0402LF-1K,1%,1/16W,EMPTY,CS21002FB06",1K,1%,R0402,17113.34,6622.38,0.000,NO,,,
R5009,"Q_RES_0402LF-1K,1%,1/16W,EMPTY,CS21002FB06",1K,1%,R0402,17113.34,6662.38,0.000,NO,,,
R5010,"Q_RES_0402LF-1K,1%,1/16W,EMPTY,CS21002FB06",1K,1%,R0402,1364.77,6752.90,0.000,NO,,,
R5011,"Q_RES_0402LF-1K,1%,1/16W,EMPTY,CS21002FB06",1K,1%,R0402,1364.77,6792.90,0.000,NO,,,
R5012,"Q_RES_0402LF-1K,1%,1/16W,EMPTY,CS21002FB06",1K,1%,R0402,7181.29,6626.67,270.000,NO,,,
R5013,"Q_RES_0402LF-1K,1%,1/16W,EMPTY,CS21002FB06",1K,1%,R0402,7221.29,6626.67,270.000,NO,,,
R5014,"Q_RES_0402LF-1K,1%,1/16W,EMPTY,CS21002FB06",1K,1%,R0402,12011.12,5824.43,180.000,NO,,,
R5015,"Q_RES_0402LF-1K,1%,1/16W,EMPTY,CS21002FB06",1K,1%,R0402,12011.12,5874.43,180.000,NO,,,
R5016,"Q_RES_0402LF-1K,1%,1/16W,EMPTY,CS21002FB06",1K,1%,R0402,17410.77,6642.16,180.000,NO,,,
R5017,"Q_RES_0402LF-1K,1%,1/16W,EMPTY,CS21002FB06",1K,1%,R0402,17410.77,6682.16,180.000,NO,,,
R5018,"Q_RES_0402LF-1K,1%,1/16W,EMPTY,CS21002FB06",1K,1%,R0402,1678.66,6807.99,180.000,NO,,,
R5019,"Q_RES_0402LF-1K,1%,1/16W,EMPTY,CS21002FB06",1K,1%,R0402,1678.66,6847.99,180.000,NO,,,
R5020,"Q_RES_0402LF-1K,1%,1/16W,EMPTY,CS21002FB06",1K,1%,R0402,7167.21,6322.67,90.000,NO,,,
R5021,"Q_RES_0402LF-1K,1%,1/16W,EMPTY,CS21002FB06",1K,1%,R0402,7207.87,6323.31,90.000,NO,,,
R5026,"Q_RES_0402LF-4.7K,5%,1/16W,EMPTY,CS24702JB10",4.7K,5%,R0402,16075.46,13075.53,180.000,YES,,,
R5027,"Q_RES_0402LF-4.7K,5%,1/16W,EMPTY,CS24702JB10",4.7K,5%,R0402,15839.47,12683.88,0.000,YES,,,
R5028,"Q_RES_0402LF-4.7K,5%,1/16W,EMPTY,CS24702JB10",4.7K,5%,R0402,16012.51,13028.95,0.000,YES,,,
R5029,"Q_RES_0402LF-4.7K,5%,1/16W,EMPTY,CS24702JB10",4.7K,5%,R0402,15839.47,12566.88,0.000,YES,,,
R5030,"Q_RES_0402LF-4.7K,5%,1/16W,EMPTY,CS24702JB10",4.7K,5%,R0402,5631.55,12459.27,180.000,YES,,,
R5031,"Q_RES_0402LF-4.7K,5%,1/16W,EMPTY,CS24702JB10",4.7K,5%,R0402,3719.31,11996.48,180.000,YES,,,
R5032,"Q_RES_0402LF-4.7K,5%,1/16W,EMPTY,CS24702JB10",4.7K,5%,R0402,3720.00,11878.62,0.000,YES,,,
R5051,"Q_RES_0402LF-0,5%,1/16W,EMPTY,CS00002JB13",0,5%,R0402,11865.87,996.94,180.000,NO,,,
R5052,"Q_RES_0402LF-0,5%,1/16W,CHIP,CS00002JB13",0,5%,R0402,12759.81,891.14,270.000,NO,,,
R5053,"Q_RES_0402LF-1K,1%,1/16W,EMPTY,CS21002FB06",1K,1%,R0402,12847.64,938.04,270.000,NO,,,
R5054,"Q_RES_0402LF-0,5%,1/16W,CHIP,CS00002JB13",0,5%,R0402,12807.64,938.04,270.000,NO,,,
R5055,"Q_RES_0402LF-10K,5%,1/16W,CHIP,CS31002JB08",10K,5%,R0402,16086.52,12991.63,90.000,YES,,,
R5056,"Q_RES_0402LF-10K,5%,1/16W,EMPTY,CS31002JB08",10K,5%,R0402,16086.52,12908.13,90.000,YES,,,
R5071,"Q_RES_0402LF-100,1%,1/16W,CHIP,CS11002FB07",100,1%,R0402,16565.25,1617.62,0.000,NO,,,
R5099,"Q_RES_0402LF-0,5%,1/16W,CHIP,CS00002JB13",0,5%,R0402,8224.19,4435.52,180.000,NO,,,
R5101,"Q_RES_0402LF-10K,5%,1/16W,CHIP,CS31002JB08",10K,5%,R0402,12037.56,1287.48,0.000,NO,,,
R5102,"Q_RES_0402LF-49.9,1%,1/16W,CHIP,CS04992FB07",49.9,1%,R0402,15666.77,12341.62,0.000,YES,,,
R5103,"Q_RES_0402LF-49.9,1%,1/16W,CHIP,CS04992FB07",49.9,1%,R0402,5901.59,12340.75,0.000,YES,,,
R5234,"Q_RES_0402LF-0,5%,1/16W,CHIP,CS00002JB13",0,5%,R0402,1996.81,16484.54,180.000,YES,,,
R5236,"Q_RES_0402LF-0,5%,1/16W,CHIP,CS00002JB13",0,5%,R0402,1996.81,16524.54,180.000,YES,,,
R5238,"Q_RES_0402LF-3.9K,5%,1/16W,EMPTY,CS23902JB04",3.9K,5%,R0402,322.55,4455.19,0.000,YES,,,
R5377,"Q_RES_0402LF-0,5%,1/16W,CHIP,CS00002JB13",0,5%,R0402,5846.23,4118.46,0.000,NO,,,
R5487,"Q_RES_0402LF-0,5%,1/16W,EMPTY,CS00002JB13",0,5%,R0402,17913.90,1658.34,0.000,NO,,,
R6000,"Q_RES_0402LF-0,5%,1/16W,CHIP,CS00002JB13",0,5%,R0402,7494.78,535.45,270.000,YES,,,
R6001,"Q_RES_0402LF-0,5%,1/16W,CHIP,CS00002JB13",0,5%,R0402,7454.75,535.45,270.000,YES,,,
R6002,"Q_RES_0402LF-0,5%,1/16W,CHIP,CS00002JB13",0,5%,R0402,7413.78,535.45,270.000,YES,,,
R6003,"Q_RES_0402LF-0,5%,1/16W,CHIP,CS00002JB13",0,5%,R0402,7375.96,535.45,270.000,YES,,,
R6004,"Q_RES_0402LF-0,5%,1/16W,CHIP,CS00002JB13",0,5%,R0402,7336.43,535.45,270.000,YES,,,
R6005,"Q_RES_0402LF-0,5%,1/16W,CHIP,CS00002JB13",0,5%,R0402,7292.94,535.45,270.000,YES,,,
R6006,"Q_RES_0402LF-0,5%,1/16W,CHIP,CS00002JB13",0,5%,R0402,7246.45,535.45,270.000,YES,,,
R6007,"Q_RES_0402LF-0,5%,1/16W,CHIP,CS00002JB13",0,5%,R0402,7199.50,535.45,270.000,YES,,,
R6008,"Q_RES_0402LF-0,5%,1/16W,CHIP,CS00002JB13",0,5%,R0402,6835.00,3948.62,270.000,NO,,,
R6009,"Q_RES_0402LF-0,5%,1/16W,CHIP,CS00002JB13",0,5%,R0402,6848.00,3733.62,270.000,NO,,,
R6010,"Q_RES_0402LF-0,5%,1/16W,CHIP,CS00002JB13",0,5%,R0402,6181.82,916.73,270.000,NO,,,
R6011,"Q_RES_0402LF-0,5%,1/16W,CHIP,CS00002JB13",0,5%,R0402,6755.00,3948.62,270.000,NO,,,
R6012,"Q_RES_0402LF-0,5%,1/16W,CHIP,CS00002JB13",0,5%,R0402,6795.00,3948.62,270.000,NO,,,
R6013,"Q_RES_0402LF-0,5%,1/16W,CHIP,CS00002JB13",0,5%,R0402,6768.00,3733.62,270.000,NO,,,
R6014,"Q_RES_0402LF-0,5%,1/16W,CHIP,CS00002JB13",0,5%,R0402,6022.80,916.73,270.000,NO,,,
R6015,"Q_RES_0402LF-0,5%,1/16W,CHIP,CS00002JB13",0,5%,R0402,6808.00,3733.62,270.000,NO,,,
R6016,"Q_RES_0402LF-2K,5%,1/16W,EMPTY,TMP_QCS22002JB29",2K,5%,R0402,6835.00,3948.62,270.000,YES,,,
R6017,"Q_RES_0402LF-2K,5%,1/16W,EMPTY,TMP_QCS22002JB29",2K,5%,R0402,6835.00,3863.62,90.000,YES,,,
R6018,"Q_RES_0402LF-2K,5%,1/16W,EMPTY,TMP_QCS22002JB29",2K,5%,R0402,6182.56,1050.70,270.000,NO,,,
R6019,"Q_RES_0402LF-2K,5%,1/16W,EMPTY,TMP_QCS22002JB29",2K,5%,R0402,6755.00,3948.62,270.000,YES,,,
R6020,"Q_RES_0402LF-2K,5%,1/16W,EMPTY,TMP_QCS22002JB29",2K,5%,R0402,6795.00,3948.62,270.000,YES,,,
R6021,"Q_RES_0402LF-2K,5%,1/16W,EMPTY,TMP_QCS22002JB29",2K,5%,R0402,6755.00,3863.62,90.000,YES,,,
R6022,"Q_RES_0402LF-2K,5%,1/16W,EMPTY,TMP_QCS22002JB29",2K,5%,R0402,6023.28,1050.70,270.000,NO,,,
R6023,"Q_RES_0402LF-2K,5%,1/16W,EMPTY,TMP_QCS22002JB29",2K,5%,R0402,6795.00,3863.62,90.000,YES,,,
R6024,"Q_RES_0402LF-4.7K,5%,1/16W,EMPTY,CS24702JB10",4.7K,5%,R0402,5905.12,1050.70,270.000,NO,,,
R6025,"Q_RES_0402LF-0,5%,1/16W,CHIP,CS00002JB13",0,5%,R0402,6728.00,3733.62,270.000,NO,,,
R6026,"Q_RES_0402LF-0,5%,1/16W,CHIP,CS00002JB13",0,5%,R0402,5905.01,916.73,270.000,NO,,,
R6027,"Q_RES_0402LF-4.7K,5%,1/16W,EMPTY,CS24702JB10",4.7K,5%,R0402,6705.00,3863.62,270.000,YES,,,
R6028,"Q_RES_0402LF-0,5%,1/16W,CHIP,CS00002JB13",0,5%,R0402,6819.44,756.27,0.000,YES,,,
R6029,"Q_RES_0402LF-33,5%,1/16W,CHIP,CS03302JB10",33,5%,R0402,6740.00,4778.62,0.000,NO,,,
R6030,"Q_RES_0402LF-33,5%,1/16W,CHIP,CS03302JB10",33,5%,R0402,6740.00,4828.62,0.000,NO,,,
R6031,"Q_RES_0402LF-33,5%,1/16W,CHIP,CS03302JB10",33,5%,R0402,6446.61,4739.05,0.000,NO,,,
R6032,"Q_RES_0402LF-0,5%,1/16W,CHIP,CS00002JB13",0,5%,R0402,5602.00,541.88,90.000,YES,,,
R6033,"Q_RES_0402LF-0,5%,1/16W,CHIP,CS00002JB13",0,5%,R0402,5682.00,541.93,90.000,YES,,,
R6034,"Q_RES_0402LF-1K,1%,1/16W,CHIP,CS21002FB06",1K,1%,R0402,5463.50,355.85,90.000,YES,,,
R6035,"Q_RES_0402LF-4.7K,5%,1/16W,EMPTY,CS24702JB10",4.7K,5%,R0402,5427.23,355.76,270.000,YES,,,
R6036,"Q_RES_0402LF-2K,1%,1/16W,EMPTY,CS22002FB07",2K,1%,R0402,6406.70,789.61,90.000,YES,,,
R6037,"Q_RES_0402LF-2K,1%,1/16W,EMPTY,CS22002FB07",2K,1%,R0402,6274.96,789.61,90.000,YES,,,
R6038,"Q_RES_0402LF-0,5%,1/16W,CHIP,CS00002JB13",0,5%,R0402,6445.00,4538.62,180.000,NO,,,
R6039,"Q_RES_0402LF-0,5%,1/16W,CHIP,CS00002JB13",0,5%,R0402,6445.00,4498.62,180.000,NO,,,
R6040,"Q_RES_0402LF-10K,5%,1/16W,CHIP,CS31002JB08",10K,5%,R0402,16792.75,1217.62,0.000,YES,,,
R6041,"Q_RES_0402LF-100K,1%,1/16W,CHIP,CS41002FB09",100K,1%,R0402,16889.25,1187.62,180.000,YES,,,
R6042,"Q_RES_0402LF-10K,5%,1/16W,CHIP,CS31002JB08",10K,5%,R0402,16565.25,1467.62,0.000,NO,,,
R6043,"Q_RES_0402LF-100K,1%,1/16W,CHIP,CS41002FB09",100K,1%,R0402,16889.25,1497.62,180.000,YES,,,
R6044,"Q_RES_0402LF-10K,5%,1/16W,CHIP,CS31002JB08",10K,5%,R0402,16889.25,1617.62,0.000,YES,,,
R6045,"Q_RES_0402LF-4.7K,5%,1/16W,EMPTY,CS24702JB10",4.7K,5%,R0402,18462.91,1618.34,0.000,NO,,,
R6046,"Q_RES_0402LF-100,1%,1/16W,CHIP,CS11002FB07",100,1%,R0402,8224.19,4273.44,180.000,NO,,,
R6047,"Q_RES_0402LF-0,5%,1/16W,CHIP,CS00002JB13",0,5%,R0402,7911.02,4313.44,180.000,NO,,,
R6048,"Q_RES_0402LF-0,5%,1/16W,CHIP,CS00002JB13",0,5%,R0402,7839.74,4573.78,270.000,YES,,,
R6049,"Q_RES_0402LF-4.7K,5%,1/16W,CHIP,CS24702JB10",4.7K,5%,R0402,9864.55,2754.43,180.000,NO,,,
R6050,"Q_RES_0402LF-100K,1%,1/16W,EMPTY,CS41002FB09",100K,1%,R0402,8080.00,5040.00,0.000,NO,,,
R6051,"Q_RES_0402LF-0,5%,1/16W,CHIP,CS00002JB13",0,5%,R0402,8224.19,4153.44,0.000,NO,,,
R6052,"Q_RES_0402LF-0,5%,1/16W,CHIP,CS00002JB13",0,5%,R0402,7590.00,3653.62,270.000,NO,,,
R6053,"Q_RES_0402LF-0,5%,1/16W,CHIP,CS00002JB13",0,5%,R0402,7355.00,3948.62,90.000,NO,,,
R6054,"Q_RES_0402LF-0,5%,1/16W,CHIP,CS00002JB13",0,5%,R0402,7275.64,3783.62,90.000,NO,,,
R6055,"Q_RES_0402LF-0,5%,1/16W,CHIP,CS00002JB13",0,5%,R0402,8224.19,4313.44,180.000,NO,,,
R6056,"Q_RES_0402LF-0,5%,1/16W,CHIP,CS00002JB13",0,5%,R0402,3276.46,1601.20,180.000,NO,,,
R6057,"Q_RES_0402LF-0,5%,1/16W,CHIP,CS00002JB13",0,5%,R0402,3276.46,1561.20,180.000,NO,,,
R6058,"Q_RES_0402LF-0,5%,1/16W,CHIP,CS00002JB13",0,5%,R0402,3276.46,1471.20,180.000,NO,,,
R6059,"Q_RES_0402LF-0,5%,1/16W,CHIP,CS00002JB13",0,5%,R0402,3276.46,1521.20,180.000,NO,,,
R6060,"Q_RES_0402LF-4.7K,5%,1/16W,EMPTY,CS24702JB10",4.7K,5%,R0402,2613.11,1448.82,0.000,NO,,,
R6061,"Q_RES_0402LF-4.7K,5%,1/16W,EMPTY,CS24702JB10",4.7K,5%,R0402,8081.19,4953.44,0.000,NO,,,
R6062,"Q_RES_0402LF-4.7K,5%,1/16W,EMPTY,CS24702JB10",4.7K,5%,R0402,7675.00,3823.62,90.000,YES,,,
R6063,"Q_RES_0402LF-33,5%,1/16W,CHIP,CS03302JB10",33,5%,R0402,6187.05,2943.05,90.000,NO,,,
R6064,"Q_RES_0402LF-0,5%,1/16W,EMPTY,CS00002JB13",0,5%,R0402,7343.80,765.18,90.000,NO,,,
R6065,"Q_RES_0402LF-0,5%,1/16W,EMPTY,CS00002JB13",0,5%,R0402,7293.80,765.18,90.000,NO,,,
R6066,"Q_RES_0402LF-0,5%,1/16W,EMPTY,CS00002JB13",0,5%,R0402,5143.98,1948.93,270.000,YES,,,
R6067,"Q_RES_0402LF-0,5%,1/16W,CHIP,CS00002JB13",0,5%,R0402,5143.98,1980.43,90.000,YES,,,
R6068,"Q_RES_0402LF-0,5%,1/16W,EMPTY,CS00002JB13",0,5%,R0402,6085.72,373.25,90.000,YES,,,
R6069,"Q_RES_0402LF-0,5%,1/16W,CHIP,CS00002JB13",0,5%,R0402,6085.72,341.75,270.000,YES,,,
R6070,"Q_RES_0402LF-4.7K,5%,1/16W,EMPTY,CS24702JB10",4.7K,5%,R0402,10755.26,4259.64,270.000,NO,,,
R6071,"Q_RES_0402LF-4.7K,5%,1/16W,EMPTY,CS24702JB10",4.7K,5%,R0402,5821.93,846.73,90.000,NO,,,
R6073,"Q_RES_0402LF-0,5%,1/16W,CHIP,CS00002JB13",0,5%,R0402,7475.00,3783.62,90.000,NO,,,
R6074,"Q_RES_0402LF-0,5%,1/16W,CHIP,CS00002JB13",0,5%,R0402,7235.00,3648.62,90.000,NO,,,
R6075,"Q_RES_0402LF-0,5%,1/16W,CHIP,CS00002JB13",0,5%,R0402,7315.00,3648.62,90.000,NO,,,
R6076,"Q_RES_0402LF-33,5%,1/16W,CHIP,CS03302JB10",33,5%,R0402,15278.53,5642.64,270.000,NO,,,
R6077,"Q_RES_0402LF-33,5%,1/16W,CHIP,CS03302JB10",33,5%,R0402,15378.53,5642.64,270.000,NO,,,
R6078,"Q_RES_0402LF-0,5%,1/16W,CHIP,CS00002JB13",0,5%,R0402,8078.86,4313.44,0.000,NO,,,
R6081,"Q_RES_0402LF-4.7K,5%,1/16W,CHIP,CS24702JB10",4.7K,5%,R0402,12299.34,7788.82,270.000,YES,,,
R6082,"Q_RES_0402LF-4.7K,5%,1/16W,CHIP,CS24702JB10",4.7K,5%,R0402,12259.34,7788.82,270.000,YES,,,
R6083,"Q_RES_0402LF-4.7K,5%,1/16W,CHIP,CS24702JB10",4.7K,5%,R0402,15418.77,7971.85,0.000,YES,,,
R6084,"Q_RES_0402LF-4.7K,5%,1/16W,CHIP,CS24702JB10",4.7K,5%,R0402,15418.77,8011.85,0.000,YES,,,
R6085,"Q_RES_0402LF-10K,1%,1/16W,CHIP,CS31002FB08",10K,1%,R0402,7720.00,5258.62,270.000,NO,,,
R6086,"Q_RES_0402LF-10K,1%,1/16W,EMPTY,CS31002FB08",10K,1%,R0402,11338.46,14579.48,270.000,NO,,,
R6087,"Q_RES_0402LF-10K,1%,1/16W,EMPTY,CS31002FB08",10K,1%,R0402,3807.71,5356.38,270.000,NO,,,
R6088,"Q_RES_0402LF-10K,1%,1/16W,EMPTY,CS31002FB08",10K,1%,R0402,723.78,14106.55,270.000,NO,,,
R6089,"Q_RES_0402LF-10K,1%,1/16W,EMPTY,CS31002FB08",10K,1%,R0402,14475.27,5353.18,0.000,YES,,,
R6090,"Q_RES_0402LF-4.7K,5%,1/16W,CHIP,CS24702JB10",4.7K,5%,R0402,5430.26,2521.13,270.000,YES,,,
R6092,"Q_RES_0402LF-0,5%,1/16W,CHIP,CS00002JB13",0,5%,R0402,6459.17,4698.27,0.000,YES,,,
R6093,"Q_RES_0402LF-0,5%,1/16W,CHIP,CS00002JB13",0,5%,R0402,6459.55,4738.77,0.000,YES,,,
R6094,"Q_RES_0402LF-0,5%,1/16W,EMPTY,CS00002JB13",0,5%,R0402,6445.00,4378.62,180.000,NO,,,
R6095,"Q_RES_0402LF-0,5%,1/16W,CHIP,CS00002JB13",0,5%,R0402,6740.00,4338.62,180.000,NO,,,
R6096,"Q_RES_0402LF-0,5%,1/16W,CHIP,CS00002JB13",0,5%,R0402,6580.00,4298.62,180.000,NO,,,
R6097,"Q_RES_0402LF-0,5%,1/16W,CHIP,CS00002JB13",0,5%,R0402,16121.19,5427.33,0.000,NO,,,
R6098,"Q_RES_0402LF-10K,5%,1/16W,EMPTY,CS31002JB08",10K,5%,R0402,10412.54,5210.74,180.000,NO,,,
R6099,"Q_RES_0402LF-0,5%,1/16W,CHIP,CS00002JB13",0,5%,R0402,18117.11,1790.44,270.000,NO,,,
R6100,"Q_RES_0402LF-49.9,1%,1/16W,CHIP,CS04992FB07",49.9,1%,R0402,15689.06,13576.78,270.000,YES,,,
R6101,"Q_RES_0402LF-0,5%,1/16W,CHIP,CS00002JB13",0,5%,R0402,4673.96,2227.64,180.000,NO,,,
R6102,"Q_RES_0402LF-0,5%,1/16W,CHIP,CS00002JB13",0,5%,R0402,5449.88,2264.41,180.000,NO,,,
R6103,"Q_RES_0402LF-0,5%,1/16W,CHIP,CS00002JB13",0,5%,R0402,5027.76,2201.66,180.000,NO,,,
R6104,"Q_RES_0402LF-0,5%,1/16W,CHIP,CS00002JB13",0,5%,R0402,9037.81,6069.15,0.000,NO,,,
R6105,"Q_RES_0402LF-0,5%,1/16W,CHIP,CS00002JB13",0,5%,R0402,9038.00,6021.82,180.000,NO,,,
R6106,"Q_RES_0402LF-10K,5%,1/16W,CHIP,CS31002JB08",10K,5%,R0402,16889.25,1227.62,180.000,YES,,,
R6107,"Q_RES_0402LF-10K,5%,1/16W,CHIP,CS31002JB08",10K,5%,R0402,16889.25,1457.62,180.000,YES,,,
R6108,"Q_RES_0402LF-0,5%,1/16W,CHIP,CS00002JB13",0,5%,R0402,4754.35,2081.35,90.000,NO,,,
R6109,"Q_RES_0402LF-0,5%,1/16W,CHIP,CS00002JB13",0,5%,R0402,5097.76,2024.04,0.000,NO,,,
R6110,"Q_RES_0402LF-0,5%,1/16W,CHIP,CS00002JB13",0,5%,R0402,9460.56,6286.62,0.000,NO,,,
R6111,"Q_RES_0402LF-0,5%,1/16W,CHIP,CS00002JB13",0,5%,R0402,4941.44,2172.27,90.000,NO,,,
R6112,"Q_RES_0402LF-33.2,1%,1/16W,CHIP,CS03322FB03",33.2,1%,R0402,7911.52,4553.44,0.000,NO,,,
R6113,"Q_RES_0402LF-33.2,1%,1/16W,CHIP,CS03322FB03",33.2,1%,R0402,7766.52,4953.44,180.000,YES,,,
R6114,"Q_RES_0402LF-2K,1%,1/16W,CHIP,CS22002FB07",2K,1%,R0402,8079.33,4553.44,180.000,NO,,,
R6115,"Q_RES_0402LF-2K,1%,1/16W,CHIP,CS22002FB07",2K,1%,R0402,7769.52,4916.44,180.000,YES,,,
R6116,"Q_RES_0402LF-0,5%,1/16W,CHIP,CS00002JB13",0,5%,R0402,6310.03,4378.81,180.000,NO,,,
R6117,"Q_RES_0402LF-100,1%,1/16W,CHIP,CS11002FB07",100,1%,R0402,6740.25,4733.62,180.000,YES,,,
R6118,"Q_RES_0402LF-0,5%,1/16W,CHIP,CS00002JB13",0,5%,R0402,8224.19,4193.44,0.000,NO,,,
R6119,"Q_RES_0402LF-0,5%,1/16W,CHIP,CS00002JB13",0,5%,R0402,8542.62,5244.13,180.000,NO,,,
R6120,"Q_RES_0402LF-1K,1%,1/16W,CHIP,CS21002FB06",1K,1%,R0402,15996.57,13748.41,270.000,YES,,,
R6121,"Q_RES_0402LF-1K,1%,1/16W,EMPTY,CS21002FB06",1K,1%,R0402,15907.23,13748.66,270.000,YES,,,
R6122,"Q_RES_0402LF-1K,1%,1/16W,EMPTY,CS21002FB06",1K,1%,R0402,15954.38,13747.86,270.000,YES,,,
R6123,"Q_RES_0402LF-1K,1%,1/16W,EMPTY,CS21002FB06",1K,1%,R0402,15860.00,13748.76,270.000,YES,,,
R6124,"Q_RES_0402LF-1K,1%,1/16W,EMPTY,CS21002FB06",1K,1%,R0402,15811.81,13748.73,270.000,YES,,,
R6125,"Q_RES_0402LF-1K,1%,1/16W,EMPTY,CS21002FB06",1K,1%,R0402,15976.74,13954.32,270.000,YES,,,
R6126,"Q_RES_0402LF-1K,1%,1/16W,CHIP,CS21002FB06",1K,1%,R0402,15880.99,13954.32,270.000,YES,,,
R6127,"Q_RES_0402LF-1K,1%,1/16W,CHIP,CS21002FB06",1K,1%,R0402,15927.88,13954.32,270.000,YES,,,
R6128,"Q_RES_0402LF-1K,1%,1/16W,CHIP,CS21002FB06",1K,1%,R0402,15834.11,13954.32,270.000,YES,,,
R6129,"Q_RES_0402LF-1K,1%,1/16W,CHIP,CS21002FB06",1K,1%,R0402,15785.99,13954.32,270.000,YES,,,
R6130,"Q_RES_0402LF-1K,1%,1/16W,CHIP,CS21002FB06",1K,1%,R0402,15487.46,8041.33,0.000,YES,,,
R6131,"Q_RES_0402LF-1K,1%,1/16W,EMPTY,CS21002FB06",1K,1%,R0402,15599.17,8026.77,270.000,YES,,,
R6132,"Q_RES_0402LF-1K,1%,1/16W,EMPTY,CS21002FB06",1K,1%,R0402,15561.11,8026.87,270.000,YES,,,
R6133,"Q_RES_0402LF-1K,1%,1/16W,EMPTY,CS21002FB06",1K,1%,R0402,15504.32,7903.26,90.000,YES,,,
R6134,"Q_RES_0402LF-1K,1%,1/16W,CHIP,CS21002FB06",1K,1%,R0402,15596.18,7903.74,90.000,YES,,,
R6135,"Q_RES_0402LF-1K,1%,1/16W,CHIP,CS21002FB06",1K,1%,R0402,15556.03,7904.08,90.000,YES,,,
R6136,"Q_RES_0402LF-1K,1%,1/16W,CHIP,CS21002FB06",1K,1%,R0402,6579.23,4577.55,0.000,NO,,,
R6137,"Q_RES_0402LF-1K,1%,1/16W,EMPTY,CS21002FB06",1K,1%,R0402,6579.40,4618.18,0.000,NO,,,
R6138,"Q_RES_0402LF-1K,1%,1/16W,EMPTY,CS21002FB06",1K,1%,R0402,6629.55,4869.41,0.000,NO,,,
R6139,"Q_RES_0402LF-1K,1%,1/16W,EMPTY,CS21002FB06",1K,1%,R0402,6628.17,4951.26,0.000,NO,,,
R6140,"Q_RES_0402LF-1K,1%,1/16W,EMPTY,CS21002FB06",1K,1%,R0402,6458.44,4395.18,180.000,YES,,,
R6141,"Q_RES_0402LF-1K,1%,1/16W,EMPTY,CS21002FB06",1K,1%,R0402,6445.11,4577.46,180.000,NO,,,
R6142,"Q_RES_0402LF-1K,1%,1/16W,CHIP,CS21002FB06",1K,1%,R0402,6446.24,4618.53,180.000,NO,,,
R6143,"Q_RES_0402LF-1K,1%,1/16W,CHIP,CS21002FB06",1K,1%,R0402,6740.32,4869.42,180.000,NO,,,
R6144,"Q_RES_0402LF-1K,1%,1/16W,CHIP,CS21002FB06",1K,1%,R0402,6742.89,4950.84,180.000,NO,,,
R6145,"Q_RES_0402LF-1K,1%,1/16W,CHIP,CS21002FB06",1K,1%,R0402,6471.02,4449.36,0.000,YES,,,
R6146,"Q_RES_0402LF-1K,1%,1/16W,CHIP,CS21002FB06",1K,1%,R0402,7075.45,3648.21,90.000,NO,,,
R6147,"Q_RES_0402LF-1K,1%,1/16W,EMPTY,CS21002FB06",1K,1%,R0402,6739.98,4046.46,180.000,YES,,,
R6148,"Q_RES_0402LF-1K,1%,1/16W,EMPTY,CS21002FB06",1K,1%,R0402,7153.95,3648.52,90.000,NO,,,
R6149,"Q_RES_0402LF-1K,1%,1/16W,EMPTY,CS21002FB06",1K,1%,R0402,7114.58,3648.60,270.000,NO,,,
R6150,"Q_RES_0402LF-1K,1%,1/16W,CHIP,CS21002FB06",1K,1%,R0402,6740.21,4092.22,180.000,YES,,,
R6151,"Q_RES_0402LF-1K,1%,1/16W,CHIP,CS21002FB06",1K,1%,R0402,7193.34,3648.62,270.000,NO,,,
R6152,"Q_RES_0201LF-0,5%,1/20W,CHIP,CS00001JE10",0,5%,R0201,1547.61,16616.55,180.000,NO,,,
R6153,"Q_RES_0201LF-0,5%,1/20W,CHIP,CS00001JE10",0,5%,R0201,1547.61,16662.10,180.000,NO,,,
R6154,"Q_RES_0201LF-0,5%,1/20W,CHIP,CS00001JE10",0,5%,R0201,1568.61,16616.55,0.000,NO,,,
R6155,"Q_RES_0201LF-0,5%,1/20W,CHIP,CS00001JE10",0,5%,R0201,1568.61,16662.10,0.000,NO,,,
R6156,"Q_RES_0201LF-0,5%,1/20W,CHIP,CS00001JE10",0,5%,R0201,1103.19,16880.13,0.000,NO,,,
R6157,"Q_RES_0201LF-0,5%,1/20W,CHIP,CS00001JE10",0,5%,R0201,1103.19,16835.13,0.000,NO,,,
R6158,"Q_RES_0201LF-0,5%,1/20W,CHIP,CS00001JE10",0,5%,R0201,1082.19,16880.13,180.000,NO,,,
R6159,"Q_RES_0201LF-0,5%,1/20W,CHIP,CS00001JE10",0,5%,R0201,1082.19,16835.13,180.000,NO,,,
R6160,"Q_RES_0402LF-1K,1%,1/16W,CHIP,CS21002FB06",1K,1%,R0402,741.27,16833.87,90.000,NO,,,
R6162,"Q_RES_0402LF-0,5%,1/16W,CHIP,CS00002JB13",0,5%,R0402,466.27,16816.45,180.000,NO,,,
R6163,"Q_RES_0402LF-1K,1%,1/16W,EMPTY,CS21002FB06",1K,1%,R0402,821.27,16833.87,270.000,NO,,,
R6164,"Q_RES_0402LF-1K,1%,1/16W,CHIP,CS21002FB06",1K,1%,R0402,781.27,16833.87,90.000,NO,,,
R6165,"Q_RES_0402LF-1K,1%,1/16W,EMPTY,CS21002FB06",1K,1%,R0402,901.27,16833.87,270.000,NO,,,
R6166,"Q_RES_0402LF-1K,1%,1/16W,EMPTY,CS21002FB06",1K,1%,R0402,861.27,16833.87,90.000,NO,,,
R6167,"Q_RES_0402LF-1K,1%,1/16W,EMPTY,CS21002FB06",1K,1%,R0402,606.27,16820.16,180.000,NO,,,
R6168,"Q_RES_0402LF-1K,1%,1/16W,CHIP,CS21002FB06",1K,1%,R0402,536.27,16814.89,180.000,NO,,,
R6169,"Q_RES_0402LF-1K,1%,1/16W,EMPTY,CS21002FB06",1K,1%,R0402,661.27,16833.87,270.000,NO,,,
R6170,"Q_RES_0402LF-1K,1%,1/16W,CHIP,CS21002FB06",1K,1%,R0402,701.27,16833.87,90.000,NO,,,
R6171,"Q_RES_0402LF-1K,1%,1/16W,EMPTY,CS21002FB06",1K,1%,R0402,369.27,16685.87,0.000,NO,,,
R6172,"Q_RES_0402LF-1K,1%,1/16W,CHIP,CS21002FB06",1K,1%,R0402,459.27,16685.87,180.000,NO,,,
R6173,"Q_RES_0402LF-1K,1%,1/16W,EMPTY,CS21002FB06",1K,1%,R0402,369.27,16635.87,0.000,NO,,,
R6174,"Q_RES_0402LF-1K,1%,1/16W,EMPTY,CS21002FB06",1K,1%,R0402,459.27,16635.87,180.000,NO,,,
R6175,"Q_RES_0402LF-1K,1%,1/16W,EMPTY,CS21002FB06",1K,1%,R0402,774.27,16483.87,90.000,NO,,,
R6176,"Q_RES_0402LF-1K,1%,1/16W,EMPTY,CS21002FB06",1K,1%,R0402,734.27,16483.87,270.000,NO,,,
R6177,"Q_RES_0402LF-1K,1%,1/16W,CHIP,CS21002FB06",1K,1%,R0402,554.27,16483.87,90.000,NO,,,
R6178,"Q_RES_0402LF-1K,1%,1/16W,EMPTY,CS21002FB06",1K,1%,R0402,594.27,16483.87,270.000,NO,,,
R6179,"Q_RES_0402LF-1K,1%,1/16W,CHIP,CS21002FB06",1K,1%,R0402,644.27,16483.87,90.000,NO,,,
R6180,"Q_RES_0402LF-1K,1%,1/16W,EMPTY,CS21002FB06",1K,1%,R0402,684.27,16483.87,270.000,NO,,,
R6181,"Q_RES_0402LF-4.7K,5%,1/16W,CHIP,CS24702JB10",4.7K,5%,R0402,1150.16,2961.97,270.000,NO,,,
R6182,"Q_RES_0402LF-4.7K,5%,1/16W,CHIP,CS24702JB10",4.7K,5%,R0402,1150.16,3166.31,270.000,NO,,,
R6183,"Q_RES_0402LF-0,5%,1/16W,CHIP,CS00002JB13",0,5%,R0402,6740.45,4054.88,0.000,NO,,,
R6184,"Q_RES_0402LF-0,5%,1/16W,CHIP,CS00002JB13",0,5%,R0402,6740.45,4015.67,0.000,NO,,,
R6185,"Q_RES_0402LF-10K,1%,1/16W,CHIP,CS31002FB08",10K,1%,R0402,6668.85,4067.55,90.000,NO,,,
R6186,"Q_RES_0402LF-4.7K,5%,1/16W,EMPTY,CS24702JB10",4.7K,5%,R0402,6440.24,4054.49,180.000,NO,,,
R6187,"Q_RES_0402LF-10K,1%,1/16W,EMPTY,CS31002FB08",10K,1%,R0402,6669.48,3996.87,270.000,NO,,,
R6188,"Q_RES_0402LF-4.7K,5%,1/16W,EMPTY,CS24702JB10",4.7K,5%,R0402,6440.80,4015.80,180.000,NO,,,
R6190,"Q_RES_0201LF-0,5%,1/20W,CHIP,CS00001JE10",0,5%,R0201,5137.70,1083.70,90.000,NO,,,
R6191,"Q_RES_0201LF-0,5%,1/20W,CHIP,CS00001JE10",0,5%,R0201,5182.70,1083.70,90.000,NO,,,
R6192,"Q_RES_0201LF-0,5%,1/20W,CHIP,CS00001JE10",0,5%,R0201,5137.70,1062.70,270.000,NO,,,
R6193,"Q_RES_0201LF-0,5%,1/20W,CHIP,CS00001JE10",0,5%,R0201,5182.70,1062.70,270.000,NO,,,
R6194,"Q_RES_0201LF-0,5%,1/20W,CHIP,CS00001JE10",0,5%,R0201,5374.20,1142.30,270.000,NO,,,
R6195,"Q_RES_0201LF-0,5%,1/20W,CHIP,CS00001JE10",0,5%,R0201,5329.20,1142.30,270.000,NO,,,
R6196,"Q_RES_0201LF-0,5%,1/20W,CHIP,CS00001JE10",0,5%,R0201,5374.20,1121.30,90.000,NO,,,
R6197,"Q_RES_0201LF-0,5%,1/20W,CHIP,CS00001JE10",0,5%,R0201,5329.20,1121.30,90.000,NO,,,
R6200,"Q_RES_0402LF-0,5%,1/16W,CHIP,CS00002JB13",0,5%,R0402,11004.48,4753.55,180.000,NO,,,
R6201,"Q_RES_0402LF-0,5%,1/16W,CHIP,CS00002JB13",0,5%,R0402,10919.38,4721.05,180.000,NO,,,
R6202,"Q_RES_0402LF-200,1%,1/16W,CHIP,CS12002FB06",200,1%,R0402,4992.32,1895.16,0.000,NO,,,
R6203,"Q_RES_0402LF-6.04K,1%,1/16W,CHIP,CS26042FB04",6.04K,1%,R0402,5431.31,1248.30,90.000,NO,,,
R6204,"Q_RES_0402LF-10K,1%,1/16W,CHIP,CS31002FB08",10K,1%,R0402,5075.07,1855.16,0.000,NO,,,
R6205,"Q_RES_0402LF-10K,1%,1/16W,CHIP,CS31002FB08",10K,1%,R0402,4992.32,1855.16,0.000,NO,,,
R6206,"Q_RES_0402LF-10K,1%,1/16W,CHIP,CS31002FB08",10K,1%,R0402,5431.96,1902.56,180.000,NO,,,
R6207,"Q_RES_0402LF-10K,1%,1/16W,CHIP,CS31002FB08",10K,1%,R0402,5501.96,1862.56,270.000,NO,,,
R6208,"Q_RES_0402LF-10K,1%,1/16W,CHIP,CS31002FB08",10K,1%,R0402,5528.36,1566.67,180.000,NO,,,
R6209,"Q_RES_0402LF-10K,1%,1/16W,CHIP,CS31002FB08",10K,1%,R0402,5528.36,1527.42,0.000,NO,,,
R6210,"Q_RES_0402LF-0,5%,1/16W,CHIP,CS00002JB13",0,5%,R0402,6979.46,16583.37,0.000,YES,,,
R6211,"Q_RES_0402LF-2.2K,5%,1/16W,CHIP,CS22202JB07",2.2K,5%,R0402,10849.38,4721.05,0.000,NO,,,
R6212,"Q_RES_0402LF-2.2K,5%,1/16W,CHIP,CS22202JB07",2.2K,5%,R0402,10929.48,4778.55,270.000,NO,,,
R6213,"Q_RES_0402LF-10K,1%,1/16W,CHIP,CS31002FB08",10K,1%,R0402,4992.32,1935.16,0.000,NO,,,
R6214,"Q_RES_0402LF-10K,1%,1/16W,EMPTY,CS31002FB08",10K,1%,R0402,4992.32,1975.16,180.000,NO,,,
R6215,"Q_RES_0402LF-10K,1%,1/16W,CHIP,CS31002FB08",10K,1%,R0402,5431.96,1992.56,180.000,NO,,,
R6216,"Q_RES_0402LF-10K,1%,1/16W,EMPTY,CS31002FB08",10K,1%,R0402,5431.96,1952.56,0.000,NO,,,
R6217,"Q_RES_0402LF-10K,1%,1/16W,EMPTY,CS31002FB08",10K,1%,R0402,4167.15,2701.65,180.000,NO,,,
R6218,"Q_RES_0402LF-10K,1%,1/16W,EMPTY,CS31002FB08",10K,1%,R0402,4167.15,2581.65,0.000,NO,,,
R6219,"Q_RES_0402LF-10K,1%,1/16W,CHIP,CS31002FB08",10K,1%,R0402,4167.15,2621.65,180.000,NO,,,
R6220,"Q_RES_0402LF-10K,1%,1/16W,EMPTY,CS31002FB08",10K,1%,R0402,4167.15,2501.65,0.000,NO,,,
R6221,"Q_RES_0402LF-10K,1%,1/16W,CHIP,CS31002FB08",10K,1%,R0402,4167.15,2541.65,180.000,NO,,,
R6222,"Q_RES_0402LF-10K,1%,1/16W,CHIP,CS31002FB08",10K,1%,R0402,4167.15,2661.65,0.000,NO,,,
R6223,"Q_RES_0402LF-1K,1%,1/16W,CHIP,CS21002FB06",1K,1%,R0402,4337.10,2441.65,90.000,YES,,,
R6224,"Q_RES_0402LF-33.2,1%,1/16W,EMPTY,CS03322FB03",33.2,1%,R0402,4377.10,2441.65,270.000,YES,,,
R6225,"Q_RES_0402LF-33.2,1%,1/16W,EMPTY,CS03322FB03",33.2,1%,R0402,4477.10,2431.65,270.000,YES,,,
R6226,"Q_RES_0402LF-10K,1%,1/16W,EMPTY,CS31002FB08",10K,1%,R0402,4417.10,2441.65,270.000,YES,,,
R6227,"Q_RES_0402LF-10K,1%,1/16W,EMPTY,CS31002FB08",10K,1%,R0402,4517.10,2431.65,270.000,YES,,,
R6228,"Q_RES_0402LF-0,5%,1/16W,CHIP,CS00002JB13",0,5%,R0402,10762.10,4579.59,0.000,NO,,,
R6229,"Q_RES_0402LF-0,5%,1/16W,CHIP,CS00002JB13",0,5%,R0402,10672.94,4625.25,0.000,NO,,,
R6230,"Q_RES_0402LF-2.2K,5%,1/16W,CHIP,CS22202JB07",2.2K,5%,R0402,11087.47,15303.80,90.000,NO,,,
R6231,"Q_RES_0402LF-2.2K,5%,1/16W,CHIP,CS22202JB07",2.2K,5%,R0402,11146.17,15303.80,90.000,NO,,,
R6232,"Q_RES_0402LF-160K,1%,1/16W,EMPTY,CS41602FB05",160K,1%,R0402,7216.32,16758.83,270.000,YES,,,
R6233,"Q_RES_0402LF-10K,1%,1/16W,EMPTY,CS31002FB08",10K,1%,R0402,7159.27,16807.04,270.000,YES,,,
R6234,"Q_RES_0402LF-160K,1%,1/16W,EMPTY,CS41602FB05",160K,1%,R0402,7200.01,16708.30,0.000,YES,,,
R6235,"Q_RES_0402LF-10K,1%,1/16W,EMPTY,CS31002FB08",10K,1%,R0402,7177.49,16589.59,90.000,YES,,,
R6236,"Q_RES_0402LF-10K,1%,1/16W,EMPTY,CS31002FB08",10K,1%,R0402,6770.72,16847.39,180.000,YES,,,
R6237,"Q_RES_0402LF-0,5%,1/16W,EMPTY,CS00002JB13",0,5%,R0402,6839.10,16847.60,180.000,YES,,,
R6238,"Q_RES_0402LF-0,5%,1/16W,EMPTY,CS00002JB13",0,5%,R0402,6909.70,16623.41,180.000,YES,,,
R6239,"Q_RES_0402LF-10K,1%,1/16W,CHIP,CS31002FB08",10K,1%,R0402,6909.73,16583.31,180.000,YES,,,
R6240,"Q_RES_0402LF-0,5%,1/16W,CHIP,CS00002JB13",0,5%,R0402,4764.18,2856.93,0.000,YES,,,
R6241,"Q_RES_0402LF-0,5%,1/16W,CHIP,CS00002JB13",0,5%,R0402,4899.98,2858.93,180.000,YES,,,
R6242,"Q_RES_0402LF-0,5%,1/16W,CHIP,CS00002JB13",0,5%,R0402,5645.73,3219.93,0.000,YES,,,
R6243,"Q_RES_0402LF-10K,1%,1/16W,CHIP,CS31002FB08",10K,1%,R0402,5741.07,2957.29,90.000,NO,,,
R6244,"Q_RES_0402LF-10K,1%,1/16W,CHIP,CS31002FB08",10K,1%,R0402,4871.07,2867.29,90.000,NO,,,
R6245,"Q_RES_0402LF-0,5%,1/16W,CHIP,CS00002JB13",0,5%,R0402,4766.39,3139.27,90.000,YES,,,
R6246,"Q_RES_0402LF-130,1%,1/16W,CHIP,CS11302FB03",130,1%,R0402,12140.94,2626.33,90.000,YES,,,
R6247,"Q_RES_0402LF-4.7K,1%,1/16W,CHIP,CS24702FB06",4.7K,1%,R0402,16924.15,16677.40,90.000,NO,,,
R6250,"Q_RES_0402LF-4.7K,1%,1/16W,CHIP,CS24702FB06",4.7K,1%,R0402,16798.16,16678.03,90.000,NO,,,
R6251,"Q_RES_0402LF-4.7K,1%,1/16W,EMPTY,CS24702FB06",4.7K,1%,R0402,16882.43,16678.02,90.000,NO,,,
R6252,"Q_RES_0402LF-33.2,1%,1/16W,CHIP,CS03322FB03",33.2,1%,R0402,14455.00,16190.00,270.000,NO,,,
R6253,"Q_RES_0402LF-33.2,1%,1/16W,CHIP,CS03322FB03",33.2,1%,R0402,14405.00,16190.00,270.000,NO,,,
R6254,"Q_RES_0402LF-0,5%,1/16W,CHIP,CS00002JB13",0,5%,R0402,16840.12,16677.41,270.000,NO,,,
R6257,"Q_RES_0402LF-1M,1%,1/16W,CHIP,CS51002FB05",1M,1%,R0402,4182.51,1041.48,0.000,NO,,,
R6258,"Q_RES_0402LF-4.7K,5%,1/16W,EMPTY,CS24702JB10",4.7K,5%,R0402,4779.97,1621.25,270.000,NO,,,
R6259,"Q_RES_0402LF-0,5%,1/16W,CHIP,CS00002JB13",0,5%,R0402,4819.97,1621.25,270.000,NO,,,
R6260,"Q_RES_0402LF-0,5%,1/16W,CHIP,CS00002JB13",0,5%,R0402,4386.73,787.00,270.000,NO,,,
R6261,"Q_RES_0402LF-0,5%,1/16W,CHIP,CS00002JB13",0,5%,R0402,4386.73,857.00,270.000,NO,,,
R6262,"Q_RES_0402LF-0,5%,1/16W,CHIP,CS00002JB13",0,5%,R0402,4426.73,857.00,270.000,NO,,,
R6263,"Q_RES_0402LF-0,5%,1/16W,CHIP,CS00002JB13",0,5%,R0402,4751.25,955.74,0.000,NO,,,
R6264,"Q_RES_0402LF-0,5%,1/16W,CHIP,CS00002JB13",0,5%,R0402,4751.25,1005.74,0.000,NO,,,
R6265,"Q_RES_0402LF-0,5%,1/16W,CHIP,CS00002JB13",0,5%,R0402,4751.25,1055.74,0.000,NO,,,
R6266,"Q_RES_0402LF-0,5%,1/16W,CHIP,CS00002JB13",0,5%,R0402,4751.25,1105.74,0.000,NO,,,
R6267,"Q_RES_0402LF-0,5%,1/16W,CHIP,CS00002JB13",0,5%,R0402,4751.90,1156.44,0.000,NO,,,
R6268,"Q_RES_0402LF-0,5%,1/16W,CHIP,CS00002JB13",0,5%,R0402,4751.90,1196.44,0.000,NO,,,
R6269,"Q_RES_0402LF-0,5%,1/16W,CHIP,CS00002JB13",0,5%,R0402,4751.90,1236.44,0.000,NO,,,
R6270,"Q_RES_0402LF-0,5%,1/16W,CHIP,CS00002JB13",0,5%,R0402,4666.00,1443.75,90.000,NO,,,
R6271,"Q_RES_0402LF-0,5%,1/16W,CHIP,CS00002JB13",0,5%,R0402,4336.73,857.00,270.000,NO,,,
R6272,"Q_RES_0402LF-200K,1%,1/16W,CHIP,CS42002FB05",200K,1%,R0402,4296.73,787.00,270.000,NO,,,
R6273,"Q_RES_0402LF-200K,1%,1/16W,EMPTY,CS42002FB05",200K,1%,R0402,4336.73,787.00,90.000,NO,,,
R6274,"Q_RES_0402LF-0,5%,1/16W,CHIP,CS00002JB13",0,5%,R0402,4751.25,905.74,0.000,NO,,,
R6275,"Q_RES_0402LF-0,5%,1/16W,CHIP,CS00002JB13",0,5%,R0402,4899.97,1621.25,90.000,NO,,,
R6276,"Q_RES_0402LF-0,5%,1/16W,CHIP,CS00002JB13",0,5%,R0402,4859.97,1621.25,90.000,NO,,,
R6277,"Q_RES_0402LF-10K,1%,1/16W,EMPTY,CS31002FB08",10K,1%,R0402,4914.97,1676.25,180.000,NO,,,
R6278,"Q_RES_0402LF-10K,1%,1/16W,EMPTY,CS31002FB08",10K,1%,R0402,4914.97,1716.25,0.000,NO,,,
R6279,"Q_RES_0402LF-0,5%,1/16W,CHIP,CS00002JB13",0,5%,R0402,4739.97,1621.25,270.000,NO,,,
R6280,"Q_RES_0402LF-0,5%,1/16W,CHIP,CS00002JB13",0,5%,R0402,4699.97,1621.25,270.000,NO,,,
R6281,"Q_RES_0402LF-1K,1%,1/16W,CHIP,CS21002FB06",1K,1%,R0402,4659.97,1621.25,90.000,NO,,,
R6282,"Q_RES_0402LF-1K,1%,1/16W,EMPTY,CS21002FB06",1K,1%,R0402,4619.97,1621.25,270.000,NO,,,
R6283,"Q_RES_0402LF-1K,1%,1/16W,EMPTY,CS21002FB06",1K,1%,R0402,4539.97,1621.25,270.000,NO,,,
R6284,"Q_RES_0402LF-1K,1%,1/16W,CHIP,CS21002FB06",1K,1%,R0402,4579.97,1621.25,90.000,NO,,,
R6285,"Q_RES_0402LF-0,5%,1/16W,CHIP,CS00002JB13",0,5%,R0402,4459.97,1551.25,270.000,NO,,,
R6286,"Q_RES_0402LF-0,5%,1/16W,CHIP,CS00002JB13",0,5%,R0402,4499.97,1551.25,270.000,NO,,,
R6287,"Q_RES_0402LF-1K,1%,1/16W,CHIP,CS21002FB06",1K,1%,R0402,4459.97,1621.25,270.000,NO,,,
R6288,"Q_RES_0402LF-1K,1%,1/16W,EMPTY,CS21002FB06",1K,1%,R0402,4419.97,1621.25,90.000,NO,,,
R6289,"Q_RES_0402LF-10K,1%,1/16W,CHIP,CS31002FB08",10K,1%,R0402,4499.97,1621.25,270.000,NO,,,
R6290,"Q_RES_0402LF-0,5%,1/16W,CHIP,CS00002JB13",0,5%,R0402,4339.97,1551.25,90.000,NO,,,
R6291,"Q_RES_0402LF-0,5%,1/16W,CHIP,CS00002JB13",0,5%,R0402,4379.97,1551.25,90.000,NO,,,
R6292,"Q_RES_0402LF-1K,1%,1/16W,EMPTY,CS21002FB06",1K,1%,R0402,4339.97,1621.25,270.000,NO,,,
R6293,"Q_RES_0402LF-4.7K,1%,1/16W,CHIP,CS24702FB06",4.7K,1%,R0402,4299.97,1621.25,90.000,NO,,,
R6294,"Q_RES_0402LF-10K,1%,1/16W,CHIP,CS31002FB08",10K,1%,R0402,4379.97,1621.25,270.000,NO,,,
R6295,"Q_RES_0402LF-0,5%,1/16W,CHIP,CS00002JB13",0,5%,R0402,4527.99,2066.20,180.000,NO,,,
R6296,"Q_RES_0402LF-0,5%,1/16W,CHIP,CS00002JB13",0,5%,R0402,4527.99,2106.20,180.000,NO,,,
R6297,"Q_RES_0402LF-10K,1%,1/16W,CHIP,CS31002FB08",10K,1%,R0402,4669.99,2066.20,180.000,NO,,,
R6298,"Q_RES_0402LF-10K,1%,1/16W,CHIP,CS31002FB08",10K,1%,R0402,4669.99,2106.20,180.000,NO,,,
R6299,"Q_RES_0402LF-0,5%,1/16W,CHIP,CS00002JB13",0,5%,R0402,4432.99,2081.20,270.000,NO,,,
R6300,"Q_RES_0402LF-0,5%,1/16W,CHIP,CS00002JB13",0,5%,R0402,4472.99,2081.20,270.000,NO,,,
R6301,"Q_RES_0402LF-10K,1%,1/16W,CHIP,CS31002FB08",10K,1%,R0402,4432.99,2160.71,270.000,NO,,,
R6302,"Q_RES_0402LF-200K,1%,1/16W,CHIP,CS42002FB05",200K,1%,R0402,4512.99,2160.71,90.000,NO,,,
R6303,"Q_RES_0402LF-200K,1%,1/16W,EMPTY,CS42002FB05",200K,1%,R0402,4472.99,2160.71,270.000,NO,,,
R6304,"Q_RES_0402LF-0,5%,1/16W,CHIP,CS00002JB13",0,5%,R0402,4352.99,2081.20,270.000,NO,,,
R6305,"Q_RES_0402LF-0,5%,1/16W,CHIP,CS00002JB13",0,5%,R0402,4392.99,2081.20,270.000,NO,,,
R6306,"Q_RES_0402LF-4.7K,1%,1/16W,CHIP,CS24702FB06",4.7K,1%,R0402,4312.99,2160.71,270.000,NO,,,
R6307,"Q_RES_0402LF-4.7K,1%,1/16W,EMPTY,CS24702FB06",4.7K,1%,R0402,4312.99,2081.20,270.000,NO,,,
R6308,"Q_RES_0402LF-200K,1%,1/16W,EMPTY,CS42002FB05",200K,1%,R0402,4352.99,2160.71,270.000,NO,,,
R6309,"Q_RES_0402LF-200K,1%,1/16W,CHIP,CS42002FB05",200K,1%,R0402,4392.99,2160.71,90.000,NO,,,
R6310,"Q_RES_0402LF-0,5%,1/16W,CHIP,CS00002JB13",0,5%,R0402,4272.99,2081.20,270.000,NO,,,
R6311,"Q_RES_0402LF-0,5%,1/16W,CHIP,CS00002JB13",0,5%,R0402,4232.99,2081.20,270.000,NO,,,
R6312,"Q_RES_0402LF-10K,1%,1/16W,CHIP,CS31002FB08",10K,1%,R0402,4272.99,2160.71,270.000,NO,,,
R6313,"Q_RES_0402LF-0,5%,1/16W,CHIP,CS00002JB13",0,5%,R0402,4152.99,2081.20,270.000,NO,,,
R6314,"Q_RES_0402LF-0,5%,1/16W,CHIP,CS00002JB13",0,5%,R0402,4192.99,2081.20,270.000,NO,,,
R6315,"Q_RES_0402LF-10K,1%,1/16W,CHIP,CS31002FB08",10K,1%,R0402,4152.99,2160.71,270.000,NO,,,
R6316,"Q_RES_0402LF-0,5%,1/16W,CHIP,CS00002JB13",0,5%,R0402,4072.99,2081.20,270.000,NO,,,
R6317,"Q_RES_0402LF-0,5%,1/16W,CHIP,CS00002JB13",0,5%,R0402,4032.99,2081.20,270.000,NO,,,
R6318,"Q_RES_0402LF-90.9K,1%,1/16W,CHIP,CS39092FB04",90.9K,1%,R0402,4112.99,2081.20,90.000,NO,,,
R6319,"Q_RES_0402LF-10K,1%,1/16W,CHIP,CS31002FB08",10K,1%,R0402,4112.99,2160.71,90.000,NO,,,
R6320,"Q_RES_0402LF-10K,1%,1/16W,EMPTY,CS31002FB08",10K,1%,R0402,4072.99,2160.71,270.000,NO,,,
R6321,"Q_RES_0402LF-47K,0.1%,1/16W,EMPTY,CS34702BB05",47K,0.1%,R0402,3992.99,2160.71,90.000,NO,,,
R6322,"Q_RES_0402LF-0,5%,1/16W,CHIP,CS00002JB13",0,5%,R0402,4032.99,2160.71,270.000,NO,,,
R6323,"Q_RES_0402LF-0,5%,1/16W,CHIP,CS00002JB13",0,5%,R0402,4141.41,1443.00,0.000,NO,,,
R6324,"Q_RES_0402LF-0,5%,1/16W,CHIP,CS00002JB13",0,5%,R0402,4141.41,1483.00,0.000,NO,,,
R6325,"Q_RES_0402LF-10K,1%,1/16W,CHIP,CS31002FB08",10K,1%,R0402,4006.32,1427.25,90.000,NO,,,
R6326,"Q_RES_0402LF-4.7K,1%,1/16W,CHIP,CS24702FB06",4.7K,1%,R0402,4071.41,1443.00,180.000,NO,,,
R6327,"Q_RES_0402LF-4.7K,1%,1/16W,EMPTY,CS24702FB06",4.7K,1%,R0402,4071.41,1483.00,0.000,NO,,,
R6328,"Q_RES_0402LF-0,5%,1/16W,CHIP,CS00002JB13",0,5%,R0402,3992.64,1251.44,90.000,NO,,,
R6329,"Q_RES_0402LF-10K,1%,1/16W,EMPTY,CS31002FB08",10K,1%,R0402,3950.48,1251.78,90.000,NO,,,
R6330,"Q_RES_0402LF-4.7K,1%,1/16W,CHIP,CS24702FB06",4.7K,1%,R0402,4062.43,1040.76,90.000,NO,,,
R6331,"Q_RES_0402LF-9.53K,1%,1/16W,CHIP,CS29532FB06",9.53K,1%,R0402,4296.85,926.57,270.000,NO,,,
R6332,"Q_RES_0402LF-12K,1%,1/16W,CHIP,CS31202FB04",12K,1%,R0402,4336.85,926.57,270.000,NO,,,
R6333,"Q_RES_0402LF-47K,0.1%,1/16W,EMPTY,CS34702BB05",47K,0.1%,R0402,3908.59,1253.84,270.000,NO,,,
R6500,"Q_RES_0402LF-0,5%,1/16W,CHIP,CS00002JB13",0,5%,R0402,4395.00,4950.00,90.000,NO,,,
R6501,"Q_RES_0402LF-100K,1%,1/16W,CHIP,CS41002FB09",100K,1%,R0402,4395.00,4880.00,270.000,NO,,,
R6502,"Q_RES_0402LF-2.2K,5%,1/16W,CHIP,CS22202JB07",2.2K,5%,R0402,12507.97,7873.97,0.000,YES,,,
R6503,"Q_RES_0402LF-2.2K,5%,1/16W,CHIP,CS22202JB07",2.2K,5%,R0402,2645.71,7754.10,0.000,YES,,,
R6504,"Q_RES_0402LF-10K,1%,1/16W,CHIP,CS31002FB08",10K,1%,R0402,3933.76,4706.97,90.000,NO,,,
R6505,"Q_RES_0402LF-10K,5%,1/16W,CHIP,CS31002JB08",10K,5%,R0402,9382.32,11450.58,180.000,YES,,,
R6506,"Q_RES_0402LF-33,5%,1/16W,CHIP,CS03302JB10",33,5%,R0402,9467.32,11380.58,90.000,YES,,,
R6701,"Q_RES_0402LF-0,5%,1/16W,EMPTY,CS00002JB13",0,5%,R0402,2781.99,15122.20,180.000,NO,,,
R6702,"Q_RES_0402LF-0,5%,1/16W,EMPTY,CS00002JB13",0,5%,R0402,2750.49,15161.20,180.000,NO,,,
R6703,"Q_RES_0402LF-0,5%,1/16W,EMPTY,CS00002JB13",0,5%,R0402,2750.49,15122.20,180.000,NO,,,
R6704,"Q_RES_0603LF-0,5%,1/4W,EMPTY,CS00006J900",0,5%,R0603,1756.82,15724.90,0.000,NO,,,
R6705,"Q_RES_0603LF-0,5%,1/4W,CHIP,CS00006J900",0,5%,R0603,1814.82,15724.90,0.000,NO,,,
R6706,"Q_RES_0201LF-1K,1%,1/20W,CHIP,CS21001FE07",1K,1%,R0201,4060.86,15538.90,90.000,NO,,,
R6707,"Q_RES_0201LF-1K,1%,1/20W,CHIP,CS21001FE07",1K,1%,R0201,4029.83,15539.29,90.000,NO,,,
R6708,"Q_RES_0201LF-0,5%,1/20W,CHIP,CS00001JE10",0,5%,R0201,2683.80,15576.00,270.000,NO,,,
R6709,"Q_RES_0201LF-0,5%,1/20W,CHIP,CS00001JE10",0,5%,R0201,1636.00,15348.00,180.000,NO,,,
R6710,"Q_RES_0402LF-0,5%,1/16W,CHIP,CS00002JB13",0,5%,R0402,7046.66,5093.17,270.000,NO,,,
R6711,"Q_RES_0402LF-0,5%,1/16W,CHIP,CS00002JB13",0,5%,R0402,7046.52,4993.44,90.000,YES,,,
R6712,"Q_RES_0201LF-1K,1%,1/20W,CHIP,CS21001FE07",1K,1%,R0201,2830.00,15178.00,90.000,NO,,,
R6713,"Q_RES_0201LF-1K,1%,1/20W,EMPTY,CS21001FE07",1K,1%,R0201,2830.00,15228.00,90.000,NO,,,
R6714,"Q_RES_0201LF-1K,1%,1/20W,EMPTY,CS21001FE07",1K,1%,R0201,2862.00,15178.00,90.000,NO,,,
R6715,"Q_RES_0201LF-20K,1%,1/20W,CHIP,CS32001FE00",20K,1%,R0201,2862.00,15228.00,90.000,NO,,,
R6716,"Q_RES_0201LF-1K,1%,1/20W,EMPTY,CS21001FE07",1K,1%,R0201,2794.00,15066.00,180.000,NO,,,
R6717,"Q_RES_0201LF-1K,1%,1/20W,CHIP,CS21001FE07",1K,1%,R0201,2846.00,15050.00,0.000,NO,,,
R6718,"Q_RES_0201LF-1K,1%,1/20W,CHIP,CS21001FE07",1K,1%,R0201,8505.00,13145.00,270.000,YES,,,
R6719,"Q_RES_0201LF-1K,1%,1/20W,CHIP,CS21001FE07",1K,1%,R0201,8505.00,13195.00,90.000,YES,,,
R6720,"Q_RES_0201LF-10K,1%,1/20W,CHIP,CS31001FE17",10K,1%,R0201,2683.80,15526.00,270.000,NO,,,
R6721,"Q_RES_0201LF-10K,1%,1/20W,CHIP,CS31001FE17",10K,1%,R0201,1636.00,15316.00,0.000,NO,,,
R6722,"Q_RES_0201LF-4.7K,5%,1/20W,EMPTY,CS24701JE04",4.7K,5%,R0201,1703.38,15066.40,180.000,YES,,,
R6723,"Q_RES_0201LF-200,1%,1/20W,CHIP,CS12001FE12",200,1%,R0201,1703.38,15098.40,180.000,YES,,,
R6724,"Q_RES_0201LF-4.7K,5%,1/20W,EMPTY,CS24701JE04",4.7K,5%,R0201,1590.00,15316.00,270.000,NO,,,
R6725,"Q_RES_0201LF-4.7K,5%,1/20W,EMPTY,CS24701JE04",4.7K,5%,R0201,1590.00,15424.00,270.000,NO,,,
R6730,"Q_RES_0201LF-1K,1%,1/20W,EMPTY,CS21001FE07",1K,1%,R0201,3900.82,15576.00,270.000,NO,,,
R6731,"Q_RES_0201LF-200,1%,1/20W,CHIP,CS12001FE12",200,1%,R0201,3900.82,15526.00,270.000,NO,,,
R6732,"Q_RES_0201LF-0,5%,1/20W,CHIP,CS00001JE10",0,5%,R0201,3996.42,15526.00,270.000,NO,,,
R6733,"Q_RES_0201LF-0,5%,1/20W,CHIP,CS00001JE10",0,5%,R0201,4038.62,15074.00,180.000,YES,,,
R6734,"Q_RES_0201LF-1K,1%,1/20W,CHIP,CS21001FE07",1K,1%,R0201,4299.63,15581.97,90.000,NO,,,
R6735,"Q_RES_0201LF-1K,1%,1/20W,CHIP,CS21001FE07",1K,1%,R0201,4268.50,15581.46,90.000,NO,,,
R6736,"Q_RES_0201LF-0,5%,1/20W,CHIP,CS00001JE10",0,5%,R0201,8585.00,13240.00,180.000,YES,,,
R6737,"Q_RES_0201LF-0,5%,1/20W,CHIP,CS00001JE10",0,5%,R0201,8585.00,13280.00,180.000,YES,,,
R6738,"Q_RES_0201LF-1K,1%,1/20W,CHIP,CS21001FE07",1K,1%,R0201,8540.00,13235.00,270.000,YES,,,
R6739,"Q_RES_0201LF-1K,1%,1/20W,CHIP,CS21001FE07",1K,1%,R0201,8540.00,13285.00,90.000,YES,,,
R6740,"Q_RES_0402LF-0,5%,1/16W,CHIP,CS00002JB13",0,5%,R0402,7104.64,5509.73,270.000,NO,,,
R6741,"Q_RES_0402LF-0,5%,1/16W,CHIP,CS00002JB13",0,5%,R0402,7085.09,5253.45,270.000,NO,,,
R6742,"Q_RES_0402LF-1K,1%,1/16W,EMPTY,CS21002FB06",1K,1%,R0402,7035.20,3649.04,90.000,NO,,,
R6743,"Q_RES_0402LF-1K,1%,1/16W,EMPTY,CS21002FB06",1K,1%,R0402,6894.40,3649.04,90.000,NO,,,
R6744,"Q_RES_0402LF-1K,1%,1/16W,CHIP,CS21002FB06",1K,1%,R0402,6995.20,3649.04,270.000,NO,,,
R6745,"Q_RES_0402LF-1K,1%,1/16W,CHIP,CS21002FB06",1K,1%,R0402,6933.67,3649.04,270.000,NO,,,
R6746,"Q_RES_0201LF-0,5%,1/20W,CHIP,CS00001JE10",0,5%,R0201,8570.00,13330.00,180.000,YES,,,
R6747,"Q_RES_0201LF-0,5%,1/20W,CHIP,CS00001JE10",0,5%,R0201,8570.00,13370.00,180.000,YES,,,
R6748,"Q_RES_0201LF-0,5%,1/20W,CHIP,CS00001JE10",0,5%,R0201,8585.00,13420.00,180.000,YES,,,
R6749,"Q_RES_0201LF-0,5%,1/20W,CHIP,CS00001JE10",0,5%,R0201,8585.00,13460.00,180.000,YES,,,
R6750,"Q_RES_0201LF-1K,1%,1/20W,CHIP,CS21001FE07",1K,1%,R0201,8505.00,13325.00,270.000,YES,,,
R6751,"Q_RES_0201LF-1K,1%,1/20W,CHIP,CS21001FE07",1K,1%,R0201,8505.00,13375.00,90.000,YES,,,
R6752,"Q_RES_0201LF-1K,1%,1/20W,CHIP,CS21001FE07",1K,1%,R0201,8540.00,13415.00,270.000,YES,,,
R6753,"Q_RES_0201LF-1K,1%,1/20W,CHIP,CS21001FE07",1K,1%,R0201,8540.00,13465.00,90.000,YES,,,
R6754,"Q_RES_0201LF-0,5%,1/20W,CHIP,CS00001JE10",0,5%,R0201,9049.00,13460.00,180.000,YES,,,
R6755,"Q_RES_0201LF-0,5%,1/20W,CHIP,CS00001JE10",0,5%,R0201,9049.00,13420.00,180.000,YES,,,
R6756,"Q_RES_0201LF-0,5%,1/20W,CHIP,CS00001JE10",0,5%,R0201,9082.00,13370.00,180.000,YES,,,
R6757,"Q_RES_0201LF-0,5%,1/20W,CHIP,CS00001JE10",0,5%,R0201,9082.00,13330.00,180.000,YES,,,
R6758,"Q_RES_0201LF-0,5%,1/20W,CHIP,CS00001JE10",0,5%,R0201,9049.00,13280.00,180.000,YES,,,
R6759,"Q_RES_0201LF-0,5%,1/20W,CHIP,CS00001JE10",0,5%,R0201,9049.00,13240.00,180.000,YES,,,
R6760,"Q_RES_0201LF-0,5%,1/20W,CHIP,CS00001JE10",0,5%,R0201,9082.00,13190.00,180.000,YES,,,
R6761,"Q_RES_0201LF-0,5%,1/20W,CHIP,CS00001JE10",0,5%,R0201,9082.00,13150.00,180.000,YES,,,
R6762,"Q_RES_0201LF-1K,1%,1/20W,CHIP,CS21001FE07",1K,1%,R0201,9120.00,13465.00,90.000,YES,,,
R6763,"Q_RES_0201LF-1K,1%,1/20W,CHIP,CS21001FE07",1K,1%,R0201,9120.00,13415.00,270.000,YES,,,
R6764,"Q_RES_0201LF-1K,1%,1/20W,CHIP,CS21001FE07",1K,1%,R0201,9155.00,13375.00,90.000,YES,,,
R6765,"Q_RES_0201LF-1K,1%,1/20W,CHIP,CS21001FE07",1K,1%,R0201,9155.00,13325.00,270.000,YES,,,
R6766,"Q_RES_0201LF-1K,1%,1/20W,CHIP,CS21001FE07",1K,1%,R0201,9120.00,13285.00,90.000,YES,,,
R6767,"Q_RES_0201LF-1K,1%,1/20W,CHIP,CS21001FE07",1K,1%,R0201,9120.00,13235.00,270.000,YES,,,
R6768,"Q_RES_0201LF-1K,1%,1/20W,CHIP,CS21001FE07",1K,1%,R0201,9155.00,13195.00,90.000,YES,,,
R6769,"Q_RES_0201LF-1K,1%,1/20W,CHIP,CS21001FE07",1K,1%,R0201,9155.00,13145.00,270.000,YES,,,
R6770,"Q_RES_0201LF-4.7K,5%,1/20W,EMPTY,CS24701JE04",4.7K,5%,R0201,9090.00,13100.00,0.000,YES,,,
R6771,"Q_RES_0201LF-4.7K,5%,1/20W,EMPTY,CS24701JE04",4.7K,5%,R0201,8550.00,13060.00,180.000,YES,,,
R6772,"Q_RES_0201LF-4.7K,5%,1/20W,EMPTY,CS24701JE04",4.7K,5%,R0201,8550.00,13020.00,180.000,YES,,,
R6773,"Q_RES_0201LF-4.7K,5%,1/20W,CHIP,CS24701JE04",4.7K,5%,R0201,9205.00,13100.00,180.000,YES,,,
R6774,"Q_RES_0201LF-4.7K,5%,1/20W,CHIP,CS24701JE04",4.7K,5%,R0201,8460.00,13060.00,0.000,YES,,,
R6775,"Q_RES_0201LF-4.7K,5%,1/20W,CHIP,CS24701JE04",4.7K,5%,R0201,8460.00,13020.00,0.000,YES,,,
R6776,"Q_RES_0201LF-0,5%,1/20W,CHIP,CS00001JE10",0,5%,R0201,8550.00,13100.00,180.000,YES,,,
R6777,"Q_RES_0402LF-0,5%,1/16W,CHIP,CS00002JB13",0,5%,R0402,7918.79,4795.11,0.000,NO,,,
R6778,"Q_RES_0201LF-10K,1%,1/20W,CHIP,CS31001FE17",10K,1%,R0201,8460.00,13100.00,0.000,YES,,,
R6779,"Q_RES_0201LF-33.2,1%,1/20W,CHIP,CS03321FE09",33.2,1%,R0201,9090.00,13020.00,180.000,YES,,,
R6780,"Q_RES_0201LF-33.2,1%,1/20W,CHIP,CS03321FE09",33.2,1%,R0201,9090.00,13060.00,180.000,YES,,,
R6781,"Q_RES_0402LF-0,5%,1/16W,CHIP,CS00002JB13",0,5%,R0402,8545.91,4988.61,0.000,NO,,,
R6782,"Q_RES_0402LF-33,5%,1/16W,CHIP,CS03302JB10",33,5%,R0402,10928.81,16299.45,0.000,NO,,,
R6783,"Q_RES_0402LF-33,5%,1/16W,CHIP,CS03302JB10",33,5%,R0402,10928.39,16337.26,0.000,NO,,,
R6784,"Q_RES_0402LF-0,5%,1/16W,CHIP,CS00002JB13",0,5%,R0402,9200.00,13060.00,180.000,YES,,,
R6785,"Q_RES_0402LF-0,5%,1/16W,CHIP,CS00002JB13",0,5%,R0402,9200.00,13020.00,180.000,YES,,,
R6786,"Q_RES_0402LF-1K,1%,1/16W,CHIP,CS21002FB06",1K,1%,R0402,17284.63,16769.65,180.000,NO,,,
R6787,"Q_RES_0402LF-1K,1%,1/16W,CHIP,CS21002FB06",1K,1%,R0402,784.06,16062.07,270.000,NO,,,
R6788,"Q_RES_0201LF-1K,1%,1/20W,CHIP,CS21001FE07",1K,1%,R0201,4019.55,15985.60,180.000,NO,,,
R6789,"Q_RES_0201LF-1K,1%,1/20W,CHIP,CS21001FE07",1K,1%,R0201,4304.41,15969.83,180.000,NO,,,
R6790,"Q_RES_0201LF-1K,1%,1/20W,CHIP,CS21001FE07",1K,1%,R0201,6424.05,16859.70,180.000,NO,,,
R6791,"Q_RES_0201LF-1K,1%,1/20W,CHIP,CS21001FE07",1K,1%,R0201,6662.62,16890.63,180.000,NO,,,
R6792,"Q_RES_0402LF-0,5%,1/16W,CHIP,CS00002JB13",0,5%,R0402,7373.24,5255.03,270.000,NO,,,
R6793,"Q_RES_0402LF-0,5%,1/16W,CHIP,CS00002JB13",0,5%,R0402,7183.81,5269.41,90.000,YES,,,
R6794,"Q_RES_0201LF-1K,1%,1/20W,EMPTY,CS21001FE07",1K,1%,R0201,6542.55,15576.00,270.000,NO,,,
R6795,"Q_RES_0201LF-200,1%,1/20W,CHIP,CS12001FE12",200,1%,R0201,6542.55,15526.00,270.000,NO,,,
R6796,"Q_RES_0201LF-0,5%,1/20W,CHIP,CS00001JE10",0,5%,R0201,6638.15,15526.00,270.000,NO,,,
R6797,"Q_RES_0201LF-0,5%,1/20W,CHIP,CS00001JE10",0,5%,R0201,6645.03,15090.72,180.000,YES,,,
R6798,"Q_RES_0402LF-0,5%,1/16W,CHIP,CS00002JB13",0,5%,R0402,7331.91,5179.39,90.000,YES,,,
R6799,"Q_RES_0402LF-0,5%,1/16W,CHIP,CS00002JB13",0,5%,R0402,7331.60,5244.41,90.000,YES,,,
R6800,"Q_RES_0402LF-0,5%,1/16W,CHIP,CS00002JB13",0,5%,R0402,806.67,16299.05,0.000,YES,,,
R6801,"Q_RES_0402LF-0,5%,1/16W,CHIP,CS00002JB13",0,5%,R0402,17284.29,16544.56,180.000,YES,,,
R6802,"Q_RES_0402LF-10K,1%,1/16W,CHIP,CS31002FB08",10K,1%,R0402,11401.17,16671.52,90.000,NO,,,
R6803,"Q_RES_0402LF-10K,1%,1/16W,CHIP,CS31002FB08",10K,1%,R0402,4400.00,16042.00,0.000,NO,,,
R6804,"Q_RES_0402LF-0,5%,1/16W,CHIP,CS00002JB13",0,5%,R0402,6739.16,4742.68,0.000,NO,,,
R6805,"Q_RES_0402LF-0,5%,1/16W,CHIP,CS00002JB13",0,5%,R0402,7254.24,5267.38,90.000,YES,,,
R6806,"Q_RES_0402LF-0,5%,1/16W,CHIP,CS00002JB13",0,5%,R0402,7267.93,5258.49,270.000,NO,,,
R6807,"Q_RES_0402LF-0,5%,1/16W,CHIP,CS00002JB13",0,5%,R0402,8076.62,5081.66,0.000,YES,,,
R6808,"Q_RES_0201LF-1K,1%,1/20W,EMPTY,CS21001FE07",1K,1%,R0201,12691.53,15874.60,90.000,NO,,,
R6809,"Q_RES_0201LF-200,1%,1/20W,CHIP,CS12001FE12",200,1%,R0201,12622.53,15872.50,270.000,NO,,,
R6810,"Q_RES_0201LF-0,5%,1/20W,CHIP,CS00001JE10",0,5%,R0201,8570.00,13150.00,180.000,YES,,,
R6811,"Q_RES_0201LF-0,5%,1/20W,CHIP,CS00001JE10",0,5%,R0201,8570.00,13190.00,180.000,YES,,,
R6812,"Q_RES_0201LF-0,5%,1/20W,CHIP,CS00001JE10",0,5%,R0201,8430.00,13190.00,0.000,YES,,,
R6813,"Q_RES_0201LF-0,5%,1/20W,CHIP,CS00001JE10",0,5%,R0201,8430.00,13150.00,0.000,YES,,,
R6820,"Q_RES_0201LF-0,5%,1/20W,CHIP,CS00001JE10",0,5%,R0201,12794.53,15863.00,270.000,NO,,,
R6821,"Q_RES_0201LF-0,5%,1/20W,CHIP,CS00001JE10",0,5%,R0201,12836.73,15404.00,180.000,YES,,,
R6822,"Q_RES_0201LF-1K,1%,1/20W,CHIP,CS21001FE07",1K,1%,R0201,11856.76,16940.30,90.000,NO,,,
R6823,"Q_RES_0402LF-0,5%,1/16W,CHIP,CS00002JB13",0,5%,R0402,8076.79,5042.61,180.000,YES,,,
R6824,"Q_RES_0402LF-0,5%,1/16W,CHIP,CS00002JB13",0,5%,R0402,7480.07,4997.40,270.000,YES,,,
R6825,"Q_RES_0402LF-0,5%,1/16W,CHIP,CS00002JB13",0,5%,R0402,8543.25,5031.54,0.000,NO,,,
R6826,"Q_RES_0402LF-0,5%,1/16W,CHIP,CS00002JB13",0,5%,R0402,8545.19,4945.85,0.000,NO,,,
R6850,"Q_RES_0402LF-33,5%,1/16W,CHIP,CS03302JB10",33,5%,R0402,6762.86,5048.95,0.000,NO,,,
R6851,"Q_RES_0402LF-33,5%,1/16W,CHIP,CS03302JB10",33,5%,R0402,6682.86,5048.95,0.000,NO,,,
R6852,"Q_RES_0402LF-0,5%,1/16W,CHIP,CS00002JB13",0,5%,R0402,6895.00,4970.00,180.000,YES,,,
R6853,"Q_RES_0402LF-0,5%,1/16W,CHIP,CS00002JB13",0,5%,R0402,6962.83,5422.87,270.000,NO,,,
R6854,"Q_RES_0402LF-33,5%,1/16W,CHIP,CS03302JB10",33,5%,R0402,7755.00,4425.00,0.000,YES,,,
R6855,"Q_RES_0402LF-33,5%,1/16W,CHIP,CS03302JB10",33,5%,R0402,7687.00,5420.00,90.000,NO,,,
R6856,"Q_RES_0402LF-33,5%,1/16W,CHIP,CS03302JB10",33,5%,R0402,16536.14,14538.39,90.000,NO,,,
R6857,"Q_RES_0402LF-33,5%,1/16W,CHIP,CS03302JB10",33,5%,R0402,16578.92,14538.60,90.000,NO,,,
R6858,"Q_RES_0402LF-0,5%,1/16W,CHIP,CS00002JB13",0,5%,R0402,537.75,15899.81,180.000,YES,,,
R6859,"Q_RES_0402LF-0,5%,1/16W,CHIP,CS00002JB13",0,5%,R0402,537.75,15859.81,180.000,YES,,,
R6860,"Q_RES_0402LF-1K,1%,1/16W,CHIP,CS21002FB06",1K,1%,R0402,17254.23,16886.56,270.000,NO,,,
R6861,"Q_RES_0402LF-1K,1%,1/16W,CHIP,CS21002FB06",1K,1%,R0402,810.06,15979.07,90.000,NO,,,
R6862,"Q_RES_0402LF-33,5%,1/16W,CHIP,CS03302JB10",33,5%,R0402,4029.69,16243.24,90.000,NO,,,
R6863,"Q_RES_0402LF-33,5%,1/16W,CHIP,CS03302JB10",33,5%,R0402,4060.06,16312.19,0.000,NO,,,
R6864,"Q_RES_0402LF-33,5%,1/16W,CHIP,CS03302JB10",33,5%,R0402,11012.16,16301.23,0.000,NO,,,
R6865,"Q_RES_0402LF-33,5%,1/16W,CHIP,CS03302JB10",33,5%,R0402,11010.23,16344.00,0.000,NO,,,
R6900,"Q_RES_0201LF-1K,1%,1/20W,EMPTY,CS21001FE07",1K,1%,R0201,5261.93,15576.00,270.000,NO,,,
R6901,"Q_RES_0201LF-200,1%,1/20W,CHIP,CS12001FE12",200,1%,R0201,5284.70,15525.50,270.000,NO,,,
R6902,"Q_RES_0201LF-0,5%,1/20W,CHIP,CS00001JE10",0,5%,R0201,5385.97,15395.72,0.000,NO,,,
R6903,"Q_RES_0201LF-0,5%,1/20W,CHIP,CS00001JE10",0,5%,R0201,5399.73,15074.00,180.000,YES,,,
R8000,"Q_RES_0402LF-33.2,1%,1/16W,CHIP,CS03322FB03",33.2,1%,R0402,7910.00,3990.00,180.000,NO,,,
R8001,"Q_RES_0402LF-100K,1%,1/16W,EMPTY,CS41002FB09",100K,1%,R0402,3842.17,16700.46,0.000,YES,,,
R8002,"Q_RES_0402LF-4.7K,5%,1/16W,CHIP,CS24702JB10",4.7K,5%,R0402,4115.00,16725.00,0.000,YES,,,
R8003,"Q_RES_0402LF-4.7K,5%,1/16W,CHIP,CS24702JB10",4.7K,5%,R0402,3842.17,16778.74,180.000,YES,,,
R8004,"Q_RES_0402LF-0,5%,1/16W,CHIP,CS00002JB13",0,5%,R0402,7287.23,16285.20,90.000,NO,,,
R8005,"Q_RES_0402LF-33,5%,1/16W,CHIP,CS03302JB10",33,5%,R0402,10440.00,5380.00,180.000,NO,,,
R8006,"Q_RES_0402LF-33,5%,1/16W,CHIP,CS03302JB10",33,5%,R0402,10433.31,5536.41,180.000,NO,,,
R8007,"Q_RES_0402LF-33,5%,1/16W,CHIP,CS03302JB10",33,5%,R0402,10355.00,5590.00,270.000,NO,,,
R8008,"Q_RES_0402LF-33,5%,1/16W,CHIP,CS03302JB10",33,5%,R0402,10300.00,5590.00,270.000,NO,,,
R8009,"Q_RES_0402LF-10K,5%,1/16W,CHIP,CS31002JB08",10K,5%,R0402,2978.15,5844.54,90.000,NO,,,
R8010,"Q_RES_0402LF-0,5%,1/16W,EMPTY,CS00002JB13",0,5%,R0402,6572.22,13633.94,180.000,NO,,,
R8011,"Q_RES_0402LF-1K,1%,1/16W,EMPTY,CS21002FB06",1K,1%,R0402,6586.03,13685.04,90.000,YES,,,
R8012,"Q_RES_0402LF-0,5%,1/16W,CHIP,CS00002JB13",0,5%,R0402,6815.00,1185.00,270.000,YES,,,
R8013,"Q_RES_0402LF-0,5%,1/16W,EMPTY,CS00002JB13",0,5%,R0402,435.00,3195.00,90.000,YES,,,
R8014,"Q_RES_0402LF-0,5%,1/16W,EMPTY,CS00002JB13",0,5%,R0402,330.00,3195.00,90.000,YES,,,
R8015,"Q_RES_0402LF-0,5%,1/16W,EMPTY,CS00002JB13",0,5%,R0402,365.00,2885.00,0.000,NO,,,
R8016,"Q_RES_0402LF-0,5%,1/16W,EMPTY,CS00002JB13",0,5%,R0402,455.00,3035.00,0.000,NO,,,
R8017,"Q_RES_0402LF-0,5%,1/16W,EMPTY,CS00002JB13",0,5%,R0402,16930.00,2300.00,270.000,NO,,,
R8018,"Q_RES_0402LF-0,5%,1/16W,CHIP,CS00002JB13",0,5%,R0402,16890.00,2300.00,270.000,NO,,,
R8019,"Q_RES_0402LF-100,1%,1/16W,EMPTY,CS11002FB07",100,1%,R0402,16620.00,2195.00,90.000,NO,,,
R8021,"Q_RES_0402LF-0,5%,1/16W,CHIP,CS00002JB13",0,5%,R0402,7915.00,5070.00,0.000,NO,,,
R8022,"Q_RES_0402LF-560,1%,1/16W,CHIP,CS15602FB03",560,1%,R0402,14336.19,2444.50,0.000,NO,,,
R8023,"Q_RES_0402LF-560,1%,1/16W,CHIP,CS15602FB03",560,1%,R0402,14466.19,2444.50,0.000,NO,,,
R8024,"Q_RES_0402LF-560,1%,1/16W,CHIP,CS15602FB03",560,1%,R0402,7500.00,1755.00,180.000,NO,,,
R8025,"Q_RES_0402LF-560,1%,1/16W,CHIP,CS15602FB03",560,1%,R0402,1503.18,2199.58,270.000,NO,,,
R8026,"Q_RES_0402LF-560,1%,1/16W,CHIP,CS15602FB03",560,1%,R0402,1503.18,2119.58,270.000,NO,,,
R8027,"Q_RES_0402LF-560,1%,1/16W,CHIP,CS15602FB03",560,1%,R0402,7268.61,16147.43,0.000,NO,,,
R8028,"Q_RES_0402LF-4.7K,5%,1/16W,CHIP,CS24702JB10",4.7K,5%,R0402,7560.54,2282.01,180.000,NO,,,
R8029,"Q_RES_0402LF-249,1%,1/16W,CHIP,CS12492FB02",249,1%,R0402,7610.00,2140.00,90.000,NO,,,
R8030,"Q_RES_0402LF-0,5%,1/16W,CHIP,CS00002JB13",0,5%,R0402,7605.00,1110.00,270.000,NO,,,
R8031,"Q_RES_0402LF-0,5%,1/16W,CHIP,CS00002JB13",0,5%,R0402,7455.00,2010.00,90.000,NO,,,
R8032,"Q_RES_0402LF-0,5%,1/16W,CHIP,CS00002JB13",0,5%,R0402,7325.00,5420.00,90.000,NO,,,
R8033,"Q_RES_0402LF-1K,1%,1/16W,CHIP,CS21002FB06",1K,1%,R0402,7405.00,5640.00,180.000,YES,,,
R8034,"Q_RES_0402LF-0,5%,1/16W,CHIP,CS00002JB13",0,5%,R0402,7310.27,5820.36,180.000,YES,,,
R8035,"Q_RES_0402LF-4.7K,5%,1/16W,EMPTY,CS24702JB10",4.7K,5%,R0402,7475.56,5731.71,0.000,YES,,,
R8036,"Q_RES_0402LF-4.7K,5%,1/16W,EMPTY,CS24702JB10",4.7K,5%,R0402,7185.00,5730.00,90.000,YES,,,
R8037,"Q_RES_0402LF-10K,1%,1/16W,CHIP,CS31002FB08",10K,1%,R0402,8285.00,4095.00,180.000,NO,,,
R8038,"Q_RES_0402LF-10K,1%,1/16W,CHIP,CS31002FB08",10K,1%,R0402,8140.00,3925.00,180.000,NO,,,
R8039,"Q_RES_0402LF-10K,1%,1/16W,CHIP,CS31002FB08",10K,1%,R0402,5715.00,4755.00,0.000,NO,,,
R8040,"Q_RES_0402LF-10K,1%,1/16W,CHIP,CS31002FB08",10K,1%,R0402,7735.00,3640.00,0.000,NO,,,
R8042,"Q_RES_0402LF-1K,1%,1/16W,EMPTY,CS21002FB06",1K,1%,R0402,11985.00,14010.00,180.000,YES,,,
R8043,"Q_RES_0402LF-1K,1%,1/16W,EMPTY,CS21002FB06",1K,1%,R0402,11895.00,14010.00,180.000,YES,,,
R8045,"Q_RES_0402LF-1K,1%,1/16W,EMPTY,CS21002FB06",1K,1%,R0402,11895.00,14100.00,180.000,YES,,,
R8047,"Q_RES_0402LF-0,5%,1/16W,CHIP,CS00002JB13",0,5%,R0402,11298.46,14579.48,90.000,NO,,,
R8048,"Q_RES_0402LF-1K,1%,1/16W,EMPTY,CS21002FB06",1K,1%,R0402,11895.00,14055.00,180.000,YES,,,
R8056,"Q_RES_0402LF-1K,1%,1/16W,CHIP,CS21002FB06",1K,1%,R0402,11896.00,14285.00,0.000,NO,,,
R8057,"Q_RES_0402LF-33,5%,1/16W,CHIP,CS03302JB10",33,5%,R0402,11896.00,14330.00,0.000,NO,,,
R8058,"Q_RES_0402LF-0,5%,1/16W,CHIP,CS00002JB13",0,5%,R0402,11985.00,14240.00,180.000,YES,,,
R8063,"Q_RES_0402LF-100,1%,1/16W,CHIP,CS11002FB07",100,1%,R0402,11985.00,14240.00,0.000,NO,,,
R8064,"Q_RES_0402LF-0,5%,1/16W,CHIP,CS00002JB13",0,5%,R0402,12470.00,14105.00,180.000,NO,,,
R8065,"Q_RES_0402LF-1K,1%,1/16W,CHIP,CS21002FB06",1K,1%,R0402,11985.00,14145.00,180.000,YES,,,
R8066,"Q_RES_0402LF-33,5%,1/16W,CHIP,CS03302JB10",33,5%,R0402,11985.00,14100.00,180.000,YES,,,
R8070,"Q_RES_0402LF-1K,1%,1/16W,CHIP,CS21002FB06",1K,1%,R0402,11985.00,14190.00,180.000,YES,,,
R8071,"Q_RES_0402LF-0,5%,1/16W,CHIP,CS00002JB13",0,5%,R0402,11985.00,14425.00,0.000,NO,,,
R8072,"Q_RES_0402LF-0,5%,1/16W,CHIP,CS00002JB13",0,5%,R0402,11985.00,14475.00,0.000,NO,,,
R8073,"Q_RES_0402LF-33,5%,1/16W,CHIP,CS03302JB10",33,5%,R0402,11985.00,14375.00,0.000,NO,,,
R8075,"Q_RES_0402LF-1K,1%,1/16W,CHIP,CS21002FB06",1K,1%,R0402,12470.00,14145.00,180.000,NO,,,
R8080,"Q_RES_0402LF-0,5%,1/16W,CHIP,CS00002JB13",0,5%,R0402,8215.00,4095.00,180.000,NO,,,
R8081,"Q_RES_0402LF-0,5%,1/16W,CHIP,CS00002JB13",0,5%,R0402,7910.00,4115.00,180.000,NO,,,
R8082,"Q_RES_0402LF-10K,1%,1/16W,EMPTY,CS31002FB08",10K,1%,R0402,7910.00,4075.00,0.000,NO,,,
R8083,"Q_RES_0402LF-0,5%,1/16W,CHIP,CS00002JB13",0,5%,R0402,8070.00,3925.00,180.000,NO,,,
R8084,"Q_RES_0402LF-0,5%,1/16W,CHIP,CS00002JB13",0,5%,R0402,7910.00,4030.00,180.000,NO,,,
R8085,"Q_RES_0402LF-10K,1%,1/16W,EMPTY,CS31002FB08",10K,1%,R0402,8000.00,3925.00,0.000,NO,,,
R8086,"Q_RES_0402LF-0,5%,1/16W,CHIP,CS00002JB13",0,5%,R0402,5785.00,4755.00,0.000,NO,,,
R8087,"Q_RES_0402LF-0,5%,1/16W,CHIP,CS00002JB13",0,5%,R0402,5955.00,4935.00,0.000,NO,,,
R8088,"Q_RES_0402LF-10K,1%,1/16W,EMPTY,CS31002FB08",10K,1%,R0402,5785.00,4795.00,0.000,NO,,,
R8089,"Q_RES_0402LF-0,5%,1/16W,CHIP,CS00002JB13",0,5%,R0402,7805.00,3640.00,0.000,NO,,,
R8090,"Q_RES_0402LF-0,5%,1/16W,CHIP,CS00002JB13",0,5%,R0402,7805.00,3675.00,180.000,NO,,,
R8091,"Q_RES_0402LF-10K,1%,1/16W,EMPTY,CS31002FB08",10K,1%,R0402,7805.00,3710.00,0.000,NO,,,
R8092,"Q_RES_0402LF-10K,5%,1/16W,EMPTY,CS31002JB08",10K,5%,R0402,16290.00,3875.00,90.000,NO,,,
R8093,"Q_RES_0402LF-100K,1%,1/16W,CHIP,CS41002FB09",100K,1%,R0402,16290.00,3945.00,90.000,NO,,,
R8094,"Q_RES_0402LF-0,5%,1/16W,CHIP,CS00002JB13",0,5%,R0402,16250.00,3875.00,270.000,NO,,,
R8095,"Q_RES_0402LF-10K,5%,1/16W,EMPTY,CS31002JB08",10K,5%,R0402,3025.00,2520.00,90.000,NO,,,
R8096,"Q_RES_0402LF-100K,1%,1/16W,CHIP,CS41002FB09",100K,1%,R0402,3105.00,2630.00,180.000,NO,,,
R8097,"Q_RES_0402LF-0,5%,1/16W,CHIP,CS00002JB13",0,5%,R0402,3175.00,2630.00,0.000,NO,,,
R8098,"Q_RES_0402LF-10K,5%,1/16W,EMPTY,CS31002JB08",10K,5%,R0402,8715.00,3180.00,90.000,NO,,,
R8099,"Q_RES_0402LF-100K,1%,1/16W,CHIP,CS41002FB09",100K,1%,R0402,8790.00,3260.00,180.000,NO,,,
R8100,"Q_RES_0402LF-0,5%,1/16W,CHIP,CS00002JB13",0,5%,R0402,8865.00,3260.00,0.000,NO,,,
R8101,"Q_RES_0402LF-0,5%,1/16W,CHIP,CS00002JB13",0,5%,R0402,5784.54,846.39,270.000,NO,,,
R8102,"Q_RES_0402LF-0,5%,1/16W,CHIP,CS00002JB13",0,5%,R0402,7673.68,16640.62,90.000,NO,,,
R8103,"Q_RES_0402LF-8.45K,1%,1/16W,EMPTY,CS28452FB06",8.45K,1%,R0402,7810.00,5680.00,270.000,YES,,,
R8104,"Q_RES_0402LF-0,5%,1/16W,EMPTY,CS00002JB13",0,5%,R0402,7890.00,5680.00,90.000,YES,,,
R8105,"Q_RES_0402LF-0,5%,1/16W,EMPTY,CS00002JB13",0,5%,R0402,7855.00,5380.00,90.000,YES,,,
R8106,"Q_RES_0402LF-1K,1%,1/16W,CHIP,CS21002FB06",1K,1%,R0402,7855.00,5310.00,270.000,YES,,,
R8107,"Q_RES_0402LF-10K,1%,1/16W,EMPTY,CS31002FB08",10K,1%,R0402,7435.00,16630.00,0.000,YES,,,
R8108,"Q_RES_0402LF-160K,1%,1/16W,EMPTY,CS41602FB05",160K,1%,R0402,7226.30,16653.98,90.000,YES,,,
R8109,"Q_RES_0402LF-10K,1%,1/16W,EMPTY,CS31002FB08",10K,1%,R0402,7303.02,16622.38,90.000,YES,,,
R8110,"Q_RES_0402LF-33.2,1%,1/16W,EMPTY,CS03322FB03",33.2,1%,R0402,7271.18,16856.60,0.000,YES,,,
R8111,"Q_RES_0402LF-10K,1%,1/16W,EMPTY,CS31002FB08",10K,1%,R0402,6908.15,16847.35,0.000,YES,,,
R8112,"Q_RES_0402LF-1M,1%,1/16W,EMPTY,CS51002FB05",1M,1%,R0402,7272.42,16750.69,270.000,YES,,,
R8113,"Q_RES_0402LF-10K,1%,1/16W,CHIP,CS31002FB08",10K,1%,R0402,5015.00,4210.00,90.000,NO,,,
R8114,"Q_RES_0402LF-17.8K,1%,1/16W,CHIP,CS31782FB04",17.8K,1%,R0402,5120.00,4310.00,90.000,NO,,,
R8115,"Q_RES_0402LF-5.11K,1%,1/16W,CHIP,CS25112FB04",5.11K,1%,R0402,5225.00,4310.00,270.000,NO,,,
R8116,"Q_RES_0402LF-0,5%,1/16W,EMPTY,CS00002JB13",0,5%,R0402,16678.35,14167.10,0.000,YES,,,
R8117,"Q_RES_0402LF-1M,1%,1/16W,CHIP,CS51002FB05",1M,1%,R0402,5280.00,4325.00,0.000,NO,,,
R8118,"Q_RES_0402LF-33.2,1%,1/16W,CHIP,CS03322FB03",33.2,1%,R0402,5852.06,4542.42,0.000,NO,,,
R8119,"Q_RES_0402LF-1K,1%,1/16W,CHIP,CS21002FB06",1K,1%,R0402,5922.06,4542.42,0.000,NO,,,
R8120,"Q_RES_0402LF-10K,1%,1/16W,CHIP,CS31002FB08",10K,1%,R0402,5520.00,4510.00,0.000,NO,,,
R8121,"Q_RES_0402LF-17.8K,1%,1/16W,CHIP,CS31782FB04",17.8K,1%,R0402,5735.00,4545.00,180.000,NO,,,
R8122,"Q_RES_0402LF-5.11K,1%,1/16W,CHIP,CS25112FB04",5.11K,1%,R0402,5735.00,4620.00,0.000,NO,,,
R8123,"Q_RES_0402LF-1M,1%,1/16W,CHIP,CS51002FB05",1M,1%,R0402,5605.00,4735.00,180.000,NO,,,
R8124,"Q_RES_0402LF-33.2,1%,1/16W,CHIP,CS03322FB03",33.2,1%,R0402,5605.00,4775.00,0.000,NO,,,
R8125,"Q_RES_0402LF-1K,1%,1/16W,CHIP,CS21002FB06",1K,1%,R0402,5715.00,4715.00,0.000,NO,,,
R8146,"Q_RES_0402LF-0,5%,1/16W,EMPTY,CS00002JB13",0,5%,R0402,6208.59,13671.66,0.000,NO,,,
R8153,"Q_RES_0402LF-1K,1%,1/16W,EMPTY,CS21002FB06",1K,1%,R0402,3471.57,5864.15,0.000,YES,,,
R8156,"Q_RES_0402LF-1K,1%,1/16W,EMPTY,CS21002FB06",1K,1%,R0402,3551.57,5784.15,180.000,NO,,,
R8160,"Q_RES_0402LF-1K,1%,1/16W,EMPTY,CS21002FB06",1K,1%,R0402,3551.57,5824.15,180.000,NO,,,
R8165,"Q_RES_0402LF-1K,1%,1/16W,CHIP,CS21002FB06",1K,1%,R0402,3551.57,5704.15,0.000,NO,,,
R8166,"Q_RES_0402LF-33,5%,1/16W,CHIP,CS03302JB10",33,5%,R0402,3551.57,5744.15,0.000,NO,,,
R8167,"Q_RES_0402LF-1K,1%,1/16W,CHIP,CS21002FB06",1K,1%,R0402,3535.82,5567.90,90.000,NO,,,
R8168,"Q_RES_0402LF-0,5%,1/16W,CHIP,CS00002JB13",0,5%,R0402,3991.57,5734.15,0.000,YES,,,
R8171,"Q_RES_0402LF-49.9,1%,1/16W,CHIP,CS04992FB07",49.9,1%,R0402,3551.57,5864.15,180.000,YES,,,
R8176,"Q_RES_0402LF-0,5%,1/16W,CHIP,CS00002JB13",0,5%,R0402,3621.57,5519.15,270.000,YES,,,
R8177,"Q_RES_0402LF-33,5%,1/16W,CHIP,CS03302JB10",33,5%,R0402,3551.57,5544.15,180.000,YES,,,
R8178,"Q_RES_0402LF-33,5%,1/16W,CHIP,CS03302JB10",33,5%,R0402,3575.82,5567.90,90.000,NO,,,
R8179,"Q_RES_0402LF-0,5%,1/16W,CHIP,CS00002JB13",0,5%,R0402,3551.57,5624.15,0.000,NO,,,
R8180,"Q_RES_0402LF-1K,1%,1/16W,CHIP,CS21002FB06",1K,1%,R0402,4006.73,5723.53,270.000,NO,,,
R8182,"Q_RES_0402LF-49.9,1%,1/16W,CHIP,CS04992FB07",49.9,1%,R0402,3551.57,5664.15,180.000,YES,,,
R8184,"Q_RES_0402LF-1K,1%,1/16W,CHIP,CS21002FB06",1K,1%,R0402,3551.57,5664.15,0.000,NO,,,
R8219,"Q_RES_0402LF-1K,1%,1/16W,EMPTY,CS21002FB06",1K,1%,R0402,975.00,14125.00,180.000,YES,,,
R8220,"Q_RES_0402LF-1K,1%,1/16W,EMPTY,CS21002FB06",1K,1%,R0402,885.00,14125.00,180.000,YES,,,
R8222,"Q_RES_0402LF-1K,1%,1/16W,EMPTY,CS21002FB06",1K,1%,R0402,885.00,14215.00,180.000,YES,,,
R8224,"Q_RES_0402LF-0,5%,1/16W,CHIP,CS00002JB13",0,5%,R0402,803.78,14106.55,90.000,NO,,,
R8225,"Q_RES_0402LF-1K,1%,1/16W,EMPTY,CS21002FB06",1K,1%,R0402,885.00,14170.00,180.000,YES,,,
R8233,"Q_RES_0402LF-1K,1%,1/16W,CHIP,CS21002FB06",1K,1%,R0402,990.00,14455.00,90.000,YES,,,
R8234,"Q_RES_0402LF-33,5%,1/16W,CHIP,CS03302JB10",33,5%,R0402,975.00,14400.00,180.000,YES,,,
R8235,"Q_RES_0402LF-0,5%,1/16W,CHIP,CS00002JB13",0,5%,R0402,975.00,14355.00,180.000,YES,,,
R8238,"Q_RES_0402LF-49.9,1%,1/16W,CHIP,CS04992FB07",49.9,1%,R0402,975.00,14125.00,0.000,NO,,,
R8241,"Q_RES_0402LF-0,5%,1/16W,CHIP,CS00002JB13",0,5%,R0402,1465.00,14215.00,180.000,NO,,,
R8242,"Q_RES_0402LF-1K,1%,1/16W,CHIP,CS21002FB06",1K,1%,R0402,975.00,14260.00,180.000,YES,,,
R8243,"Q_RES_0402LF-33,5%,1/16W,CHIP,CS03302JB10",33,5%,R0402,975.00,14215.00,180.000,YES,,,
R8247,"Q_RES_0402LF-1K,1%,1/16W,CHIP,CS21002FB06",1K,1%,R0402,975.00,14305.00,180.000,YES,,,
R8248,"Q_RES_0402LF-0,5%,1/16W,CHIP,CS00002JB13",0,5%,R0402,975.00,14445.00,0.000,NO,,,
R8249,"Q_RES_0402LF-0,5%,1/16W,CHIP,CS00002JB13",0,5%,R0402,975.00,14485.00,0.000,NO,,,
R8250,"Q_RES_0402LF-33,5%,1/16W,CHIP,CS03302JB10",33,5%,R0402,885.00,14400.00,0.000,NO,,,
R8252,"Q_RES_0402LF-1K,1%,1/16W,CHIP,CS21002FB06",1K,1%,R0402,1465.00,14255.00,180.000,NO,,,
R8282,"Q_RES_0402LF-0,5%,1/16W,CHIP,CS00002JB13",0,5%,R0402,14475.27,5313.18,180.000,YES,,,
R8286,"Q_RES_0402LF-1K,1%,1/16W,EMPTY,CS21002FB06",1K,1%,R0402,14602.57,5769.77,180.000,NO,,,
R8287,"Q_RES_0402LF-1K,1%,1/16W,EMPTY,CS21002FB06",1K,1%,R0402,14682.57,5769.77,180.000,NO,,,
R8289,"Q_RES_0402LF-1K,1%,1/16W,EMPTY,CS21002FB06",1K,1%,R0402,14682.57,5689.77,180.000,NO,,,
R8293,"Q_RES_0402LF-1K,1%,1/16W,EMPTY,CS21002FB06",1K,1%,R0402,14682.57,5729.77,180.000,NO,,,
R8298,"Q_RES_0402LF-1K,1%,1/16W,CHIP,CS21002FB06",1K,1%,R0402,14682.57,5609.77,0.000,NO,,,
R8299,"Q_RES_0402LF-33,5%,1/16W,CHIP,CS03302JB10",33,5%,R0402,14682.57,5649.77,0.000,NO,,,
R8300,"Q_RES_0402LF-1K,1%,1/16W,CHIP,CS21002FB06",1K,1%,R0402,14682.57,5449.77,0.000,NO,,,
R8301,"Q_RES_0402LF-0,5%,1/16W,CHIP,CS00002JB13",0,5%,R0402,15122.57,5639.77,0.000,YES,,,
R8304,"Q_RES_0402LF-49.9,1%,1/16W,CHIP,CS04992FB07",49.9,1%,R0402,14682.57,5769.77,180.000,YES,,,
R8305,"Q_RES_0402LF-0,5%,1/16W,CHIP,CS00002JB13",0,5%,R0402,14212.11,12603.66,90.000,NO,,,
R8306,"Q_RES_0402LF-0,5%,1/16W,CHIP,CS00002JB13",0,5%,R0402,14177.11,12603.66,90.000,NO,,,
R8308,"Q_RES_0402LF-0,5%,1/16W,CHIP,CS00002JB13",0,5%,R0402,14698.32,5394.02,270.000,YES,,,
R8309,"Q_RES_0402LF-0,5%,1/16W,CHIP,CS00002JB13",0,5%,R0402,14752.57,5424.77,270.000,YES,,,
R8310,"Q_RES_0402LF-33,5%,1/16W,CHIP,CS03302JB10",33,5%,R0402,14682.57,5449.77,180.000,YES,,,
R8311,"Q_RES_0402LF-33,5%,1/16W,CHIP,CS03302JB10",33,5%,R0402,14682.57,5489.77,0.000,NO,,,
R8312,"Q_RES_0402LF-0,5%,1/16W,CHIP,CS00002JB13",0,5%,R0402,14682.57,5529.77,0.000,NO,,,
R8313,"Q_RES_0402LF-1K,1%,1/16W,CHIP,CS21002FB06",1K,1%,R0402,15122.57,5639.77,180.000,NO,,,
R8317,"Q_RES_0402LF-1K,1%,1/16W,CHIP,CS21002FB06",1K,1%,R0402,14682.57,5569.77,0.000,NO,,,
R8350,"Q_RES_0402LF-0,5%,1/16W,CHIP,CS00002JB13",0,5%,R0402,4785.00,12665.00,90.000,NO,,,
R8351,"Q_RES_0402LF-0,5%,1/16W,CHIP,CS00002JB13",0,5%,R0402,4745.00,12665.00,90.000,NO,,,
R8380,"Q_RES_0402LF-1K,1%,1/16W,CHIP,CS21002FB06",1K,1%,R0402,6207.77,13867.32,0.000,NO,,,
R8381,"Q_RES_0402LF-0,5%,1/16W,CHIP,CS00002JB13",0,5%,R0402,6301.95,13884.57,270.000,NO,,,
R8382,"Q_RES_0402LF-0,5%,1/16W,CHIP,CS00002JB13",0,5%,R0402,6340.95,13884.57,270.000,NO,,,
R8383,"Q_RES_0402LF-33,5%,1/16W,CHIP,CS03302JB10",33,5%,R0402,6262.95,13884.57,270.000,NO,,,
R8385,"Q_RES_0402LF-0,5%,1/16W,CHIP,CS00002JB13",0,5%,R0402,6236.20,13880.57,180.000,YES,,,
R8386,"Q_RES_0402LF-0,5%,1/16W,CHIP,CS00002JB13",0,5%,R0402,6182.16,13790.93,180.000,YES,,,
R8413,"Q_RES_0402LF-100K,1%,1/16W,CHIP,CS41002FB09",100K,1%,R0402,3117.16,443.65,270.000,YES,,,
R8420,"Q_RES_0402LF-1K,1%,1/16W,CHIP,CS21002FB06",1K,1%,R0402,17819.90,417.55,90.000,YES,,,
R8421,"Q_RES_0402LF-10K,1%,1/16W,CHIP,CS31002FB08",10K,1%,R0402,17777.54,418.69,90.000,YES,,,
R8422,"Q_RES_0402LF-10K,1%,1/16W,CHIP,CS31002FB08",10K,1%,R0402,17735.54,417.09,90.000,YES,,,
R8423,"Q_RES_0402LF-1K,1%,1/16W,CHIP,CS21002FB06",1K,1%,R0402,17699.00,417.09,90.000,YES,,,
R8458,"Q_RES_0402LF-0,5%,1/16W,EMPTY,CS00002JB13",0,5%,R0402,16312.49,14204.50,0.000,NO,,,
R8465,"Q_RES_0402LF-10K,5%,1/16W,CHIP,CS31002JB08",10K,5%,R0402,13056.42,5372.99,0.000,NO,,,
R8563,"Q_RES_0402LF-0,5%,1/16W,CHIP,CS00002JB13",0,5%,R0402,15007.59,8445.82,90.000,YES,,,
R8564,"Q_RES_0402LF-0,5%,1/16W,CHIP,CS00002JB13",0,5%,R0402,14963.59,8445.82,90.000,YES,,,
R8565,"Q_RES_0402LF-0,5%,1/16W,CHIP,CS00002JB13",0,5%,R0402,14831.59,8445.82,90.000,YES,,,
R8566,"Q_RES_0402LF-0,5%,1/16W,CHIP,CS00002JB13",0,5%,R0402,14787.59,8445.82,90.000,YES,,,
R9000,"Q_RES_0402LF-1K,1%,1/16W,CHIP,CS21002FB06",1K,1%,R0402,9517.98,16567.20,270.000,YES,,,
R9001,"Q_RES_0402LF-0,5%,1/16W,CHIP,CS00002JB13",0,5%,R0402,7327.23,16285.20,90.000,NO,,,
R9002,"Q_RES_0402LF-10K,1%,1/16W,CHIP,CS31002FB08",10K,1%,R0402,14252.97,16195.04,0.000,NO,,,
R9003,"Q_RES_0402LF-100K,1%,1/16W,EMPTY,CS41002FB09",100K,1%,R0402,14252.97,16233.66,180.000,NO,,,
R9004,"Q_RES_0402LF-4.7K,5%,1/16W,CHIP,CS24702JB10",4.7K,5%,R0402,14303.86,16470.87,180.000,NO,,,
R9005,"Q_RES_0402LF-4.7K,5%,1/16W,CHIP,CS24702JB10",4.7K,5%,R0402,14344.97,16195.66,0.000,NO,,,
R9006,"Q_RES_0402LF-10K,1%,1/16W,CHIP,CS31002FB08",10K,1%,R0402,6792.93,16439.04,0.000,NO,,,
R9007,"Q_RES_0402LF-100K,1%,1/16W,EMPTY,CS41002FB09",100K,1%,R0402,6793.05,16478.42,180.000,NO,,,
R9008,"Q_RES_0402LF-4.7K,5%,1/16W,CHIP,CS24702JB10",4.7K,5%,R0402,7056.88,16489.42,270.000,NO,,,
R9009,"Q_RES_0402LF-4.7K,5%,1/16W,CHIP,CS24702JB10",4.7K,5%,R0402,6792.93,16397.04,0.000,NO,,,
R9010,"Q_RES_0402LF-0,5%,1/16W,CHIP,CS00002JB13",0,5%,R0402,7453.82,16887.70,270.000,NO,,,
R9011,"Q_RES_0402LF-0,5%,1/16W,CHIP,CS00002JB13",0,5%,R0402,7367.23,16285.20,90.000,NO,,,
R9012,"Q_RES_0402LF-0,5%,1/16W,CHIP,CS00002JB13",0,5%,R0402,7407.23,16285.20,90.000,NO,,,
R9013,"Q_RES_0402LF-0,5%,1/16W,CHIP,CS00002JB13",0,5%,R0402,7455.37,16786.42,270.000,NO,,,
R9014,"Q_RES_0402LF-10K,1%,1/16W,CHIP,CS31002FB08",10K,1%,R0402,14252.97,16139.66,0.000,NO,,,
R9015,"Q_RES_0402LF-100K,1%,1/16W,EMPTY,CS41002FB09",100K,1%,R0402,14252.97,16099.04,180.000,NO,,,
R9016,"Q_RES_0402LF-4.7K,5%,1/16W,CHIP,CS24702JB10",4.7K,5%,R0402,14156.23,16006.59,270.000,NO,,,
R9017,"Q_RES_0402LF-4.7K,5%,1/16W,CHIP,CS24702JB10",4.7K,5%,R0402,14343.09,16099.66,0.000,NO,,,
R9018,"Q_RES_0402LF-0,5%,1/16W,CHIP,CS00002JB13",0,5%,R0402,7153.09,16785.43,270.000,NO,,,
R9019,"Q_RES_0402LF-0,5%,1/16W,CHIP,CS00002JB13",0,5%,R0402,7219.09,16828.71,270.000,NO,,,
R9020,"Q_RES_0402LF-1K,1%,1/16W,EMPTY,CS21002FB06",1K,1%,R0402,7137.71,16589.65,270.000,YES,,,
R9021,"Q_RES_0402LF-1K,1%,1/16W,EMPTY,CS21002FB06",1K,1%,R0402,5865.00,4660.00,270.000,NO,,,
R9022,"Q_RES_0402LF-33.2,1%,1/16W,CHIP,CS03322FB03",33.2,1%,R0402,8485.00,4565.00,90.000,NO,,,
R9023,"Q_RES_0402LF-33.2,1%,1/16W,CHIP,CS03322FB03",33.2,1%,R0402,8335.00,4710.00,0.000,NO,,,
R9024,"Q_RES_0402LF-54.9K,1%,1/16W,EMPTY,CS35492FB03",54.9K,1%,R0402,6485.00,4185.00,180.000,NO,,,
R9025,"Q_RES_0402LF-100K,1%,1/16W,EMPTY,CS41002FB09",100K,1%,R0402,6380.00,4170.00,270.000,NO,,,
R9026,"Q_RES_0402LF-4.7K,5%,1/16W,CHIP,CS24702JB10",4.7K,5%,R0402,6295.00,4270.00,180.000,NO,,,
R9027,"Q_RES_0402LF-100K,1%,1/16W,CHIP,CS41002FB09",100K,1%,R0402,6485.00,4225.00,180.000,NO,,,
R9028,"Q_RES_0402LF-0,5%,1/16W,EMPTY,CS00002JB13",0,5%,R0402,6425.00,4205.00,90.000,NO,,,
R9029,"Q_RES_0402LF-0,5%,1/16W,EMPTY,CS00002JB13",0,5%,R0402,8577.21,3840.30,0.000,NO,,,
R9030,"Q_RES_0402LF-0,5%,1/16W,EMPTY,CS00002JB13",0,5%,R0402,8390.00,3875.00,90.000,NO,,,
R9031,"Q_RES_0402LF-33.2,1%,1/16W,CHIP,CS03322FB03",33.2,1%,R0402,8500.00,3850.00,180.000,NO,,,
R9032,"Q_RES_0402LF-10K,1%,1/16W,CHIP,CS31002FB08",10K,1%,R0402,8375.00,3930.00,0.000,NO,,,
R9033,"Q_RES_0402LF-33.2,1%,1/16W,CHIP,CS03322FB03",33.2,1%,R0402,8520.00,4875.00,90.000,NO,,,
R9034,"Q_RES_0402LF-33.2,1%,1/16W,CHIP,CS03322FB03",33.2,1%,R0402,8605.00,3915.00,180.000,NO,,,
R9043,"Q_RES_0402LF-4.7K,5%,1/16W,CHIP,CS24702JB10",4.7K,5%,R0402,17503.80,17118.08,90.000,NO,,,
R9044,"Q_RES_0402LF-4.7K,1%,1/16W,EMPTY,CS24702FB06",4.7K,1%,R0402,17246.33,17066.90,90.000,NO,,,
R9273,"Q_RES_0402LF-0,5%,1/16W,CHIP,CS00002JB13",0,5%,R0402,14743.59,8445.82,90.000,YES,,,
R9274,"Q_RES_0402LF-0,5%,1/16W,CHIP,CS00002JB13",0,5%,R0402,14699.59,8445.82,90.000,YES,,,
R9275,"Q_RES_0402LF-0,5%,1/16W,CHIP,CS00002JB13",0,5%,R0402,14919.59,8445.82,90.000,YES,,,
R9276,"Q_RES_0402LF-0,5%,1/16W,CHIP,CS00002JB13",0,5%,R0402,14875.59,8445.82,90.000,YES,,,
R9446,"Q_RES_0402LF-33.2,1%,1/16W,CHIP,CS03322FB03",33.2,1%,R0402,12260.94,3101.41,270.000,YES,,,
R10287,"Q_RES_0402LF-10K,1%,1/16W,CHIP,CS31002FB08",10K,1%,R0402,8827.25,1874.49,0.000,NO,,,
R10296,"Q_RES_0402LF-1K,1%,1/16W,CHIP,CS21002FB06",1K,1%,R0402,9299.25,2016.12,0.000,YES,,,
R11667,"Q_RES_0402LF-33.2,1%,1/16W,CHIP,CS03322FB03",33.2,1%,R0402,7766.52,4873.44,0.000,NO,,,
SW1,"SW20S_DHNF10FQTR-SW20S_DHNF-10F-Q-T/R,SMLF,MECH,DHA",,,SW20S_DHNF10FTVTR,16841.00,1442.62,0.000,NO,,,
TP1,"TP_TP-NA,TP26",,,TP26,16613.17,6890.93,0.000,YES,,,
TP2,"TP_TP-NA,TP30",,,TP30,10506.39,13111.49,0.000,NO,,,
TP3,"TP_TP-NA,TP30",,,TP30,14109.61,12807.51,180.000,NO,,,
TP4,"TP_TP-NA,TP30",,,TP30,11956.45,6018.73,180.000,NO,,,
TP5,"TP_TP-NA,TP30",,,TP30,10506.39,13071.49,0.000,NO,,,
TP6,"TP_TP-NA,TP30",,,TP30,12076.00,13940.00,180.000,YES,,,
TP7,"TP_TP-NA,TP30",,,TP30,13372.57,6787.65,0.000,NO,,,
TP8,"TP_TP-NA,TP30",,,TP30,16298.33,13120.91,0.000,NO,,,
TP9,"TP_TP-NA,TP30",,,TP30,11956.45,6059.73,180.000,NO,,,
TP10,"TP_TP-NA,TP26",,,TP26,16610.07,7002.43,0.000,YES,,,
TP11,"TP_TP-NA,TP30",,,TP30,5558.97,6576.05,0.000,NO,,,
TP12,"TP_TP-NA,TP30",,,TP30,787.60,13121.86,180.000,NO,,,
TP13,"TP_TP-NA,TP30",,,TP30,6661.00,13080.48,180.000,NO,,,
TP14,"TP_TP-NA,TP30",,,TP30,2486.25,7621.82,0.000,NO,,,
TP15,"TP_TP-NA,TP30",,,TP30,787.60,13071.06,180.000,NO,,,
TP16,"TP_TP-NA,TP30",,,TP30,4355.80,12799.86,180.000,NO,,,
TP17,"TP_TP-NA,TP30",,,TP30,2271.57,7159.15,0.000,NO,,,
TP18,"TP_TP-NA,TP30",,,TP30,6661.00,13125.02,0.000,NO,,,
TP19,"TP_TP-NA,TP30",,,TP30,2436.25,7621.82,0.000,NO,,,
TP20,"TP_TP-NA,TP30",,,TP30,5558.97,6626.05,0.000,NO,,,
U25_BP,"TP_TP-EMPTY,TP30",,,TP30,1579.39,-765.54,270.000,NO,,,
U25_SRM,"TP_TP-EMPTY,TP30",,,TP30,1465.39,-765.54,270.000,NO,,,
U26_BP,"TP_TP-EMPTY,TP30",,,TP30,1351.39,-765.54,270.000,NO,,,
U26_SRM,"TP_TP-EMPTY,TP30",,,TP30,1237.39,-765.54,270.000,NO,,,
U1,"M24128BWMN6TP-M24128-BWMN6TP,SMLF,IC,AKE30Z00613",,,SOIC8XH,12154.18,4393.75,0.000,NO,,,
U2,"PCA9617ADP-PCA9617ADP,SMLF,IC,AL009617K02",,,TSSOP8_3XB,9080.75,8781.18,270.000,YES,,,
U3,"SN74LVC1G07DBVR_SMLF-SN74LVC1G07DBVR,IC,AL1G0007024",,,SOT23-5,15843.55,7972.46,0.000,YES,,,
U4,"PI3CSW12ZUAEX-PI3CSW12ZUAEX,SMLF,IC,AL3CSW12000",,,UQFN10_0-5_2X1-5,9167.63,9784.75,0.000,YES,,,
U5,"PCA9617ADP-PCA9617ADP,SMLF,EMPTY,AL009617K02",,,TSSOP8_3XB,9399.23,8783.55,90.000,YES,,,
U6,"PI3CSW12ZUAEX-PI3CSW12ZUAEX,SMLF,IC,AL3CSW12000",,,UQFN10_0-5_2X1-5,9396.44,9339.79,270.000,YES,,,
U7,"74CBTLV3126PW-74CBTLV3126PW,SMLF,IC,AL003126K08",,,TSSOP14,8300.75,2737.42,0.000,YES,,,
U8,"74LVC2G07DW7-74LVC2G07DW-7,SMLF,IC,AL002G07003",,,SOT363_0-65_2X1-25XC,18019.19,4080.56,0.000,NO,,,
U9,"TPS71715DCKR-TPS71715DCKR,SMLF,EMPTY,AL071715001",,,SC70-5XB,12005.18,1008.75,0.000,NO,,,
U10,"9ZXL0451EKILFT-9ZXL0451EKILFT,SMLF,IC,AL000451003",,,VFQFPN32_TH_0-5_5X5XD,4182.93,16127.25,270.000,NO,,,
U11,"M24M02DRMN6TP-M24M02-DRMN6TP,SMLF,IC,AKE33Z00600",,,SOIC8XH,11766.87,16723.95,270.000,NO,,,
U12,"M24M02DRMN6TP-M24M02-DRMN6TP,SMLF,IC,AKE33Z00600",,,SOIC8XH,4078.79,15800.39,270.000,NO,,,
U13,"SN74AUC2G66DCTR-SN74AUC2G66DCTR,SMLF,IC,AL2G0066C00",,,SSOP8,9241.72,6009.12,180.000,NO,,,
U14,"SN74AUC2G66DCTR-SN74AUC2G66DCTR,SMLF,IC,AL2G0066C00",,,SSOP8,9241.72,6154.12,180.000,NO,,,
U15,"M24M02DRMN6TP-M24M02-DRMN6TP,SMLF,IC,AKE33Z00600",,,SOIC8XH,11433.06,15869.53,0.000,NO,,,
U16,"M24M02DRMN6TP-M24M02-DRMN6TP,SMLF,IC,AKE33Z00600",,,SOIC8XH,16586.01,16861.63,270.000,NO,,,
U17,"M24M02DRMN6TP-M24M02-DRMN6TP,SMLF,IC,AKE33Z00600",,,SOIC8XH,14723.49,16713.54,0.000,YES,,,
U18,"LCMXO3LF9400C5BG484C-LCMXO3LF-9400C-5BG484C,SMLF,IA",,,BGA484_0-8_19X19_H67,7304.02,4529.64,90.000,NO,,,
U19,"M24M02DRMN6TP-M24M02-DRMN6TP,SMLF,IC,AKE33Z00600",,,SOIC8XH,4328.74,15800.39,270.000,NO,,,
U20,"M24M02DRMN6TP-M24M02-DRMN6TP,SMLF,IC,AKE33Z00600",,,SOIC8XH,6467.84,16685.69,270.000,NO,,,
U21,"M24M02DRMN6TP-M24M02-DRMN6TP,SMLF,IC,AKE33Z00600",,,SOIC8XH,6704.71,16687.83,270.000,NO,,,
U22,"TCA9548APWR-TCA9548APWR,SMLF,IC,AL009548K02",,,TSSOP24XA,9734.83,13261.66,180.000,YES,,,
U23,"74LVC1G08W57-74LVC1G08W5-7,SMLF,IC,AL1G0008020",,,SOT25-5_0-95_3X1-6,6045.00,4215.00,180.000,NO,,,
U24,"MOSFET_N_SMLF-BSS138K,BSS138K,IC,BAM138K0000",,,SOT23_GDSXD,6125.00,4510.00,0.000,NO,,,
U25,"GENOA_SP5-SOCKET6096_13568-001,SMLF,IO,DGA^6000030",SP5,,SOCKET6096_93-4X120-45XA,14168.03,10192.13,180.000,NO,,,
U26,"GENOA_SP5-SOCKET6096_13568-001,SMLF,IO,DGA^6000030",SP5,,SOCKET6096_93-4X120-45XA,4406.61,10192.14,180.000,NO,,,
U27,"PCA9617ADP-PCA9617ADP,SMLF,IC,AL009617K02",,,TSSOP8_3XB,7015.26,5974.97,270.000,NO,,,
U28,"SN74LVC1G07DBVR_SMLF-SN74LVC1G07DBVR,IC,AL1G0007024",,,SOT23-5,7927.28,3811.92,0.000,NO,,,
U29,"SN74LVC2G07DCKR_SMLF-SN74LVC2G07DCKR,IC,AL002G07006",,,SC70-6,15426.75,5512.78,90.000,NO,,,
U30,"SN74LVC1G07DBVR_SMLF-SN74LVC1G07DBVR,IC,AL1G0007024",,,SOT23-5,6590.00,3755.00,90.000,NO,,,
U31,"74LVC1G08W57-74LVC1G08W5-7,SMLF,IC,AL1G0008020",,,SOT25-5_0-95_3X1-6,2075.00,1525.00,0.000,NO,,,
U32,"MOSFET_N_SMLF-BSS138K,BSS138K,IC,BAM138K0000",,,SOT23_GDSXD,1825.00,1510.00,0.000,NO,,,
U33,"SN74LVC1G07DBVR_SMLF-SN74LVC1G07DBVR,IC,AL1G0007024",,,SOT23-5,3775.00,3075.00,0.000,NO,,,
U34,"SN74LVC1G07DBVR_SMLF-SN74LVC1G07DBVR,IC,AL1G0007024",,,SOT23-5,3310.00,2740.00,0.000,NO,,,
U35,"74LVC1G08W57-74LVC1G08W5-7,SMLF,IC,AL1G0008020",,,SOT25-5_0-95_3X1-6,2890.00,2325.00,270.000,NO,,,
U36,"TCA9548APWR-TCA9548APWR,SMLF,IC,AL009548K02",,,TSSOP24XA,11296.38,4693.19,0.000,NO,,,
U37,"74LVC1G32GW_SMLF-74LVC1G32GW,IC,ALVC1G32007",,,SOT353_Q,2750.00,2230.00,0.000,NO,,,
U38,"SN74LVC1G11DCKR-SN74LVC1G11DCKR,SMLF,IC,ALLVC1G1000",,,SC70-6_0-65_2X1-25,3871.84,4867.26,270.000,NO,,,
U39,"TCA9548APWR-TCA9548APWR,SMLF,IC,AL009548K02",,,TSSOP24XA,10400.59,4693.19,0.000,NO,,,
U40,"SN74LVC2G07DCKR_SMLF-SN74LVC2G07DCKR,IC,AL002G07006",,,SC70-6,3283.75,5563.34,90.000,NO,,,
U41,"PI3CSW12ZUAEX-PI3CSW12ZUAEX,SMLF,IC,AL3CSW12000",,,UQFN10_0-5_2X1-5,6631.75,16697.53,270.000,YES,,,
U42,"PI3CSW12ZUAEX-PI3CSW12ZUAEX,SMLF,IC,AL3CSW12000",,,UQFN10_0-5_2X1-5,4542.88,15801.33,180.000,NO,,,
U43,"PI3CSW12ZUAEX-PI3CSW12ZUAEX,SMLF,IC,AL3CSW12000",,,UQFN10_0-5_2X1-5,6303.28,16437.20,180.000,YES,,,
U44,"74LVC1G17GW-74LVC1G17GW,SMLF,IC,AL1G0017K01",,,TSSOP5,9350.68,2697.81,180.000,NO,,,
U45,"PI3CSW12ZUAEX-PI3CSW12ZUAEX,SMLF,IC,AL3CSW12000",,,UQFN10_0-5_2X1-5,3827.97,15842.19,0.000,NO,,,
U46,"PI3CSW12ZUAEX-PI3CSW12ZUAEX,SMLF,IC,AL3CSW12000",,,UQFN10_0-5_2X1-5,14729.59,16794.01,270.000,NO,,,
U47,"PI3CSW12ZUAEX-PI3CSW12ZUAEX,SMLF,IC,AL3CSW12000",,,UQFN10_0-5_2X1-5,16610.35,16801.81,0.000,YES,,,
U48,"PI3CSW12ZUAEX-PI3CSW12ZUAEX,SMLF,IC,AL3CSW12000",,,UQFN10_0-5_2X1-5,11452.37,15560.29,90.000,NO,,,
U49,"PI3CSW12ZUAEX-PI3CSW12ZUAEX,SMLF,IC,AL3CSW12000",,,UQFN10_0-5_2X1-5,11754.54,16743.66,0.000,YES,,,
U50,"MAX11617EEET-MAX11617EEE+T,SMLF,EMPTY,AL011617W00",,,QSOP16_0-635_4-9X3-89,9838.76,12819.43,0.000,YES,,,
U51,"ADC128D818CIMTXNOPB-ADC128D818CIMTX/NOPB,SMLF,IC,AA",,,TSSOP16XC,8756.23,12855.68,180.000,YES,,,
U52,"ISL28022FRZT-ISL28022FRZ-T,SMLF,IC,AL028022003",,,QFN16_TH_0-5_3X3XH,12799.02,4067.25,0.000,NO,,,
U53,"SN74AVC4T774PWR-SN74AVC4T774PWR,SMLF,IC,AL04T774K00",,,TSSOP16XC,10196.55,5235.44,180.000,NO,,,
U54,"PI4ULS3V304AZMAEX-PI4ULS3V304AZMAEX,SMLF,IC,AL0003A",,,UQFN12_0-4_2X1-7,10275.20,5466.49,180.000,NO,,,
U55,"ISL28022FRZT-ISL28022FRZ-T,SMLF,IC,AL028022003",,,QFN16_TH_0-5_3X3XH,15562.17,3004.16,0.000,NO,,,
U56,"ISL28022FRZT-ISL28022FRZ-T,SMLF,IC,AL028022003",,,QFN16_TH_0-5_3X3XH,914.54,1567.91,0.000,NO,,,
U57,"SCHOTTKY_DUAL_12A_3C-BAT54CW,SMLF,EMPTY,BCBAT54CZ13",,,SOT323,1600.50,4037.50,90.000,NO,,,
U58,"74LVC2G07DW7-74LVC2G07DW-7,SMLF,IC,AL002G07003",,,SOT363_0-65_2X1-25XC,510.00,3111.00,0.000,NO,,,
U59,"74LVC2G07DW7-74LVC2G07DW-7,SMLF,IC,AL002G07003",,,SOT363_0-65_2X1-25XC,510.40,2803.57,0.000,NO,,,
U60,"SCHOTTKY_DUAL_12A_3C-BAT54CW,SMLF,EMPTY,BCBAT54CZ13",,,SOT323,1868.30,4032.10,90.000,NO,,,
U64,"M24128BWMN6TP-M24128-BWMN6TP,SMLF,IC,AKE30Z00613",,,SOIC8XH,12281.02,4628.76,0.000,NO,,,
U66,"74LVC1G126SE7-74LVC1G126SE-7,SMLF,IC,AL1G0126009",,,SOT353_0-65_2X1-25,18093.69,3878.52,0.000,NO,,,
U67,"74CBTLV3126PW-74CBTLV3126PW,SMLF,IC,AL003126K08",,,TSSOP14,7764.77,3039.08,0.000,YES,,,
U75,"74LVC1G17GW-74LVC1G17GW,SMLF,IC,AL1G0017K01",,,TSSOP5,8253.08,4890.55,0.000,NO,,,
U82,"SN74LVC1G07DBVR_SMLF-SN74LVC1G07DBVR,IC,AL1G0007024",,,SOT23-5,15924.24,13410.33,0.000,YES,,,
U86,"SN74LVC1G07DBVR_SMLF-SN74LVC1G07DBVR,IC,AL1G0007024",,,SOT23-5,13643.69,1113.82,270.000,NO,,,
U90,"PI6CV304LE-PI6CV304LE,SMLF,IC,AL000304K01",,,TSSOP8,8438.76,699.48,270.000,NO,,,
U92,"SN74LVC1G07DBVR_SMLF-SN74LVC1G07DBVR,IC,AL1G0007024",,,SOT23-5,5996.71,4359.49,0.000,NO,,,
U96,"PCA9617ADP-PCA9617ADP,SMLF,IC,AL009617K02",,,TSSOP8_3XB,9590.00,8785.00,90.000,YES,,,
U98,"PCA9306DP1-PCA9306DP1,SMLF,IC,AL009306K04",,,TSSOP8_3,6040.02,1716.95,0.000,NO,,,
U99,"SN74LVC1G07DBVR_SMLF-SN74LVC1G07DBVR,EMPTY,AL1G000A",,,SOT23-5,12417.32,942.10,0.000,NO,,,
U100,"RT9818C44GV-RT9818C-44GV,SMLF,IC,AL009818001",,,SOT23_123_2-89X1-6,6685.00,5200.00,0.000,NO,,,
U101,"SN74LVC1G07DBVR_SMLF-SN74LVC1G07DBVR,IC,AL1G0007024",,,SOT23-5,15924.24,13555.13,0.000,YES,,,
U104,"74LVC1G07GV-74LVC1G07GV,SMLF,IC,AL1G0007001",,,SC-74A_2-9X1-5,14500.96,566.73,0.000,NO,,,
U105,"PI3CSW12ZUAEX-PI3CSW12ZUAEX,SMLF,IC,AL3CSW12000",,,UQFN10_0-5_2X1-5,11881.92,5823.22,180.000,NO,,,
U106,"PI3CSW12ZUAEX-PI3CSW12ZUAEX,SMLF,IC,AL3CSW12000",,,UQFN10_0-5_2X1-5,17263.34,6642.38,180.000,NO,,,
U107,"PI3CSW12ZUAEX-PI3CSW12ZUAEX,SMLF,IC,AL3CSW12000",,,UQFN10_0-5_2X1-5,1527.05,6770.89,180.000,NO,,,
U108,"PI3CSW12ZUAEX-PI3CSW12ZUAEX,SMLF,IC,AL3CSW12000",,,UQFN10_0-5_2X1-5,7201.29,6486.67,90.000,NO,,,
U116,"SN74AVC4T774PWR-SN74AVC4T774PWR,SMLF,IC,AL04T774K00",,,TSSOP16XC,14472.69,1458.42,270.000,NO,,,
U124,"SN74LVC1G07DBVR_SMLF-SN74LVC1G07DBVR,IC,AL1G0007024",,,SOT23-5,16734.35,2245.97,0.000,NO,,,
U134,"74LVC2G07DW7-74LVC2G07DW-7,SMLF,IC,AL002G07003",,,SOT363_0-65_2X1-25XC,10014.29,2930.75,0.000,NO,,,
U142,"LT6700CS61TRPBF-LT6700CS6-1#TRPBF,SMLF,EMPTY,AL006A",,,TSOT23-6_0-95_2-9X1-625,7053.66,16747.83,90.000,YES,,,
U143,"NCT7718W-NCT7718W,SMLF,IC,AL007718001",,,MSOP8_0-65_3X3XE,11229.06,15559.85,270.000,NO,,,
U146,"SN74AVC2T245RSWR-SN74AVC2T245RSWR,SMLF,IC,AL02T245A",,,UQFN10_0-4_1-8X1-4,4847.54,2156.52,90.000,NO,,,
U147,"SN74AVC2T245RSWR-SN74AVC2T245RSWR,SMLF,IC,AL02T245A",,,UQFN10_0-4_1-8X1-4,5758.85,2254.96,270.000,NO,,,
U148,"SN74AVC4T774PWR-SN74AVC4T774PWR,SMLF,IC,AL04T774K00",,,TSSOP16XC,10514.49,4206.61,180.000,NO,,,
U149,"SN74AVC4T774PWR-SN74AVC4T774PWR,SMLF,IC,AL04T774K00",,,TSSOP16XC,10510.69,3849.64,180.000,NO,,,
U150,"SN74AVC4T774PWR-SN74AVC4T774PWR,SMLF,IC,AL04T774K00",,,TSSOP16XC,9956.25,3900.23,270.000,NO,,,
U151,"SN74AVC4T774PWR-SN74AVC4T774PWR,SMLF,IC,AL04T774K00",,,TSSOP16XC,11081.35,3844.26,180.000,NO,,,
U152,"SN74AVC2T245RSWR-SN74AVC2T245RSWR,SMLF,IC,AL02T245A",,,UQFN10_0-4_1-8X1-4,5120.76,2132.85,180.000,NO,,,
U153,"SN74AUC2G66DCTR-SN74AUC2G66DCTR,SMLF,IC,AL2G0066C00",,,SSOP8,9241.72,5864.12,180.000,NO,,,
U154,"SN74AUC2G66DCTR-SN74AUC2G66DCTR,SMLF,IC,AL2G0066C00",,,SSOP8,9241.72,6299.12,180.000,NO,,,
U157,"74LVC1G07GV-74LVC1G07GV,SMLF,IC,AL1G0007001",,,SC-74A_2-9X1-5,6386.54,1327.71,90.000,NO,,,
U158,"MOSFET_NCH_GDS_ESD_PROTECTED-2N7002K,SMLF,IC,BAM70A",,,SOT23_GDSXC,8259.30,5398.72,180.000,NO,,,
U160,"74LV4052PW-74LV4052PW,SMLF,IC,ALLV4052K19",,,TSSOP16_0-65_5X4-4XH,4404.15,2316.03,0.000,NO,,,
U166,"SCHOTTKY_DUAL_12A_3C-BAT54CW,SMLF,IC,BCBAT54CZ13",,,SOT323,12146.81,1313.07,0.000,NO,,,
U167,"NCP698SQ15T1G-NCP698SQ15T1G,SMLF,EMPTY,AL000698000",,,SC82-AB-4_1-3_2X1-25,11744.13,797.48,270.000,NO,,,
U175,"LTC4307CMS8-LTC4307CMS8,SMLF,IC,AL004307000",,,MSOP8,6427.17,17009.45,90.000,NO,,,
U176,"LTC4307CMS8-LTC4307CMS8,SMLF,EMPTY,AL004307000",,,MSOP8,11376.78,16785.73,0.000,NO,,,
U181,"PCA9539RPW-PCA9539RPW,SMLF,IC,AL009539K07",,,TSSOP24XB,7257.37,16548.42,90.000,NO,,,
U190,"MOSFET_NCH_GDS_ESD_PROTECTED-2N7002K,SMLF,IC,BAM70A",,,SOT23_GDSXC,7612.97,16838.32,270.000,NO,,,
U192,"LTC4307CMS8-LTC4307CMS8,SMLF,IC,AL004307000",,,MSOP8,7019.82,16472.50,0.000,YES,,,
U193,"MAX11617EEET-MAX11617EEE+T,SMLF,EMPTY,AL011617W00",,,QSOP16_0-635_4-9X3-89,12702.88,1363.03,0.000,NO,,,
U194,"LTC4307CMS8-LTC4307CMS8,SMLF,IC,AL004307000",,,MSOP8,1113.18,17026.66,0.000,NO,,,
U195,"74LVC2G17GW-74LVC2G17GW,SMLF,IC,AL2G0017005",,,SOT363,6946.18,16316.36,180.000,YES,,,
U196,"74LVC2G17GW-74LVC2G17GW,SMLF,IC,AL2G0017005",,,SOT363,1855.00,17180.00,0.000,NO,,,
U200,"LTC4307CMS8-LTC4307CMS8,SMLF,IC,AL004307000",,,MSOP8,1113.72,17222.77,180.000,NO,,,
U204,"74LVC1G126SE7-74LVC1G126SE-7,SMLF,IC,AL1G0126009",,,SOT353_0-65_2X1-25,14161.81,16293.67,90.000,NO,,,
U206,"LT6700CS61TRPBF-LT6700CS6-1#TRPBF,SMLF,EMPTY,AL006A",,,TSOT23-6_0-95_2-9X1-625,6120.47,4650.88,180.000,NO,,,
U207,"74LVC1G17GW-74LVC1G17GW,SMLF,IC,AL1G0017K01",,,TSSOP5,3317.80,1748.90,270.000,NO,,,
U211,"74LVC2G07DW7-74LVC2G07DW-7,SMLF,IC,AL002G07003",,,SOT363_0-65_2X1-25XC,18019.08,4213.34,0.000,NO,,,
U212,"74LV4052PW-74LV4052PW,SMLF,IC,ALLV4052K19",,,TSSOP16_0-65_5X4-4XH,5184.61,2342.80,0.000,NO,,,
U213,"IML3112Y2B000NCG8-IML3112-Y2B000NCG8,SMLF,EMPTY,ALA",,,DFN8_TH_0-5_2X3XC,9099.94,9294.26,90.000,YES,,,
U217,"74LVC1G126SE7-74LVC1G126SE-7,SMLF,IC,AL1G0126009",,,SOT353_0-65_2X1-25,3878.95,1553.77,180.000,NO,,,
U218,"74LVC1G07GV-74LVC1G07GV,SMLF,IC,AL1G0007001",,,SC-74A_2-9X1-5,9974.02,4246.26,0.000,NO,,,
U219,"74LVC1G07GV-74LVC1G07GV,SMLF,IC,AL1G0007001",,,SC-74A_2-9X1-5,3757.23,1388.97,0.000,NO,,,
U222,"74CBTLV3126PW-74CBTLV3126PW,SMLF,IC,AL003126K08",,,TSSOP14,8239.99,3041.88,0.000,YES,,,
U223,"74CBTLV3126PW-74CBTLV3126PW,SMLF,IC,AL003126K08",,,TSSOP14,7813.95,2791.46,0.000,YES,,,
U224,"74LVC1G126SE7-74LVC1G126SE-7,SMLF,IC,AL1G0126009",,,SOT353_0-65_2X1-25,18088.09,3686.12,0.000,NO,,,
U225,"74LVC1G126SE7-74LVC1G126SE-7,SMLF,IC,AL1G0126009",,,SOT353_0-65_2X1-25,2056.20,1167.62,90.000,NO,,,
U235,"PCA9617ADP-PCA9617ADP,SMLF,IC,AL009617K02",,,TSSOP8_3XB,5808.60,1533.60,0.000,NO,,,
U236,"PCA9617ADP-PCA9617ADP,SMLF,IC,AL009617K02",,,TSSOP8_3XB,16031.00,2994.62,0.000,NO,,,
U237,"PI3EQX12902AZLEX-PI3EQX12902AZLEX,SMLF,IC,AL012902A",,,TQFN30_TH_0-4_4-5X2-5,1348.53,16720.87,180.000,NO,,,
U239,"74LVC1G126SE7-74LVC1G126SE-7,SMLF,IC,AL1G0126009",,,SOT353_0-65_2X1-25,6069.85,4042.87,0.000,NO,,,
U240,"74LVC2G08DP-74LVC2G08DP,SMLF,EMPTY,ALVC2G08K01",,,TSSOP8_0-65_3X3,16398.10,2258.77,0.000,NO,,,
U241,"74LVC2G08DP-74LVC2G08DP,SMLF,EMPTY,ALVC2G08K01",,,TSSOP8_0-65_3X3,210.80,2941.72,0.000,NO,,,
U242,"74LVC2G08DP-74LVC2G08DP,SMLF,EMPTY,ALVC2G08K01",,,TSSOP8_0-65_3X3,516.80,2941.72,0.000,NO,,,
U243,"NC7SB3157_SMLF-NC7SB3157P6X,NC7SB3157P6X,EMPTY,ALSA",,,SC70-6,6058.45,3872.27,0.000,NO,,,
U244,"NC7SB3157_SMLF-NC7SB3157P6X,NC7SB3157P6X,EMPTY,ALSA",,,SC70-6,6058.45,3764.27,0.000,NO,,,
U245,"NC7SB3157_SMLF-NC7SB3157P6X,NC7SB3157P6X,EMPTY,ALSA",,,SC70-6,5698.45,3764.27,0.000,NO,,,
U246,"NC7SB3157_SMLF-NC7SB3157P6X,NC7SB3157P6X,EMPTY,ALSA",,,SC70-6,5698.45,3872.27,0.000,NO,,,
U247,"9FGL0251DKILFT-9FGL0251DKILFT,SMLF,IC,AL000251002",,,VFQFPN24_TH_0-5_4X4XI,533.33,5277.13,0.000,NO,,,
U248,"74LVC1G32GW_SMLF-74LVC1G32GW,IC,ALVC1G32007",,,SOT353_Q,1273.11,5269.25,180.000,NO,,,
U252,"74LVC2G17GW-74LVC2G17GW,SMLF,IC,AL2G0017005",,,SOT363,2025.00,17150.00,0.000,NO,,,
U253,"74LVC2G17GW-74LVC2G17GW,SMLF,IC,AL2G0017005",,,SOT363,4703.09,16884.78,270.000,NO,,,
U255,"74LVC2G07DW7-74LVC2G07DW-7,SMLF,IC,AL002G07003",,,SOT363_0-65_2X1-25XC,4090.00,16660.00,270.000,NO,,,
U256,"74LVC2G17GW-74LVC2G17GW,SMLF,IC,AL2G0017005",,,SOT363,1590.00,17185.00,0.000,NO,,,
U257,"74LVC2G07DW7-74LVC2G07DW-7,SMLF,IC,AL002G07003",,,SOT363_0-65_2X1-25XC,4699.75,17237.93,270.000,NO,,,
U259,"SN74LVC2G07DCKR_SMLF-SN74LVC2G07DCKR,IC,AL002G07006",,,SC70-6,5698.45,4011.58,0.000,NO,,,
U263,"ISL28022FRZT-ISL28022FRZ-T,SMLF,IC,AL028022003",,,QFN16_TH_0-5_3X3XH,2862.53,1548.03,0.000,NO,,,
U264,"ISL28022FRZT-ISL28022FRZ-T,SMLF,IC,AL028022003",,,QFN16_TH_0-5_3X3XH,6102.29,2248.77,0.000,NO,,,
U265,"ISL28022FRZT-ISL28022FRZ-T,SMLF,IC,AL028022003",,,QFN16_TH_0-5_3X3XH,8235.14,1368.98,90.000,NO,,,
U266,"ISL28022FRZT-ISL28022FRZ-T,SMLF,IC,AL028022003",,,QFN16_TH_0-5_3X3XH,17349.92,3703.84,180.000,NO,,,
U268,"GL852GOHY60-GL852G-OHY60,SMLF,IC,AL000852001",,,QFN28_THXL,553.74,3903.01,270.000,NO,,,
U269,"ADC128D818CIMTXNOPB-ADC128D818CIMTX/NOPB,SMLF,IC,AA",,,TSSOP16XC,12312.02,1711.15,0.000,NO,,,
U270,"LM75BD-LM75BD,SMLF,IC,AL0075BD000",,,SO8_1-27_4-9X3-9,14480.79,16507.70,90.000,NO,,,
U271,"LM75BD-LM75BD,SMLF,IC,AL0075BD000",,,SO8_1-27_4-9X3-9,11589.19,606.86,0.000,NO,,,
U272,"LM75BD-LM75BD,SMLF,IC,AL0075BD000",,,SO8_1-27_4-9X3-9,3923.24,16445.87,90.000,NO,,,
U273,"LM75BD-LM75BD,SMLF,IC,AL0075BD000",,,SO8_1-27_4-9X3-9,4456.95,625.16,0.000,NO,,,
U276,"ISL28022FRZT-ISL28022FRZ-T,SMLF,IC,AL028022003",,,QFN16_TH_0-5_3X3XH,8474.79,2143.91,0.000,NO,,,
U278,"74LVC1G08W57-74LVC1G08W5-7,SMLF,IC,AL1G0008020",,,SOT25-5_0-95_3X1-6,7577.70,16462.83,90.000,NO,,,
U279,"PCA9617ADP-PCA9617ADP,SMLF,IC,AL009617K02",,,TSSOP8_3XB,8511.25,1721.98,180.000,NO,,,
U286,"74LVC1G126SE7-74LVC1G126SE-7,SMLF,IC,AL1G0126009",,,SOT353_0-65_2X1-25,1934.20,1167.62,90.000,NO,,,
U290,"MOSFET_NCH_GDS_ESD_PROTECTED-2N7002K,SMLF,IC,BAM70A",,,SOT23_GDSXC,10546.06,16521.59,270.000,NO,,,
U308,"74LVC2G07DW7-74LVC2G07DW-7,SMLF,IC,AL002G07003",,,SOT363_0-65_2X1-25XC,10954.89,17075.04,270.000,NO,,,
U314,"9ZXL0451EKILFT-9ZXL0451EKILFT,SMLF,IC,AL000451003",,,VFQFPN32_TH_0-5_5X5XD,11255.16,16469.41,0.000,NO,,,
U316,"74LVC2G17GW-74LVC2G17GW,SMLF,IC,AL2G0017005",,,SOT363,13876.20,17201.78,270.000,NO,,,
U320,"74LVC1G66GV-74LVC1G66GV,SMLF,IC,AL001G66000",,,SC74AXA,14976.20,1308.22,180.000,NO,,,
U321,"74LVC1G66GV-74LVC1G66GV,SMLF,IC,AL001G66000",,,SC74AXA,3524.96,1262.65,0.000,NO,,,
U324,"MOSFET_NCH_GDS_ESD_PROTECTED-2N7002K,SMLF,IC,BAM70A",,,SOT23_GDSXC,15558.24,6065.59,180.000,YES,,,
U325,"MOSFET_N_SMLF-BSS138K,BSS138K,EMPTY,BAM138K0000",,,SOT23_GDSXD,6118.88,4796.06,180.000,NO,,,
U326,"MPQ8633AGLEC807Z-MPQ8633AGLE-C807-Z,SMLF,IC,AL0086A",,,QFN14_4X3,16270.48,5542.64,0.000,NO,,,
U5201,"TUSB211IRWBR-TUSB211IRWBR,SMLF,EMPTY,AL000211007",,,X2QFN12_0-4_1-6X1-6,475.46,4422.02,270.000,YES,,,
U6000,"DS125BR111RTWR-DS125BR111RTWR,SMLF,IC,AL000125003",,,WQFN24_TH_0-5_4X4XA,654.46,16658.80,270.000,NO,,,
U6001,"CYUSB330468LTXI-CYUSB3304-68LTXI,SMLF,IC,AJ0330400A",,,QFN68_TH_0-4_8X8,5224.18,1451.71,180.000,NO,,,
U6002,"TUSB8042AIRGCR-TUSB8042AIRGCR,SMLF,IC,AL008042000",,,VQFN64_TH_0-5_9X9XC,4440.90,1240.07,90.000,NO,,,
U6003,"M24128BWMN6TP-M24128-BWMN6TP,SMLF,IC,AKE30Z00613",,,SOIC8XH,4407.56,2562.68,0.000,NO,,,
U6004,"MOSFET_NCH_GDS_ESD_PROTECTED-2N7002K,SMLF,EMPTY,BAA",,,SOT23_GDSXC,6905.00,16750.00,90.000,YES,,,
U6005,"ISL28022FRZT-ISL28022FRZ-T,SMLF,IC,AL028022003",,,QFN16_TH_0-5_3X3XH,16890.73,16862.45,90.000,NO,,,
U6006,"APX80929SAG7-APX809-29SAG-7,SMLF,IC,AL080929000",,,SOT23_123XI,4580.00,4935.00,0.000,NO,,,
U6010,"PT5161LRS-PT5161LRS,SMLF,IC,AJ051610U03",,,BGA354_8-9X22-8,12301.88,15579.71,0.000,NO,,,
U6011,"PT5161LRS-PT5161LRS,SMLF,IC,AJ051610U03",,,BGA354_8-9X22-8,13582.50,15579.71,0.000,NO,,,
U6012,"PT5161LRS-PT5161LRS,SMLF,IC,AJ051610U03",,,BGA354_8-9X22-8,16224.24,15579.71,0.000,NO,,,
U6013,"PT5161LRS-PT5161LRS,SMLF,IC,AJ051610U03",,,BGA354_8-9X22-8,14943.62,15579.71,0.000,NO,,,
U6014,"PT5161LRS-PT5161LRS,SMLF,IC,AJ051610U03",,,BGA354_8-9X22-8,2223.15,15249.71,0.000,NO,,,
U6015,"PT5161LRS-PT5161LRS,SMLF,IC,AJ051610U03",,,BGA354_8-9X22-8,3503.77,15249.71,0.000,NO,,,
U6016,"PT5161LRS-PT5161LRS,SMLF,IC,AJ051610U03",,,BGA354_8-9X22-8,6145.50,15249.71,0.000,NO,,,
U6017,"PT5161LRS-PT5161LRS,SMLF,IC,AJ051610U03",,,BGA354_8-9X22-8,4864.88,15249.71,0.000,NO,,,
U6020,"TCA9548APWR-TCA9548APWR,SMLF,IC,AL009548K02",,,TSSOP24XA,8831.11,13261.66,180.000,YES,,,
U8000,"NC7SB3157P6X-NC7SB3157P6X,SMLF,IC,ALSB3157000",,,SC70-6XA,7275.00,5685.00,180.000,YES,,,
U8001,"APX80929SAG7-APX809-29SAG-7,SMLF,IC,AL080929000",,,SOT23_123XI,16385.00,3915.00,270.000,NO,,,
U8002,"APX80929SAG7-APX809-29SAG-7,SMLF,IC,AL080929000",,,SOT23_123XI,3135.00,2520.00,270.000,NO,,,
U8003,"APX80929SAG7-APX809-29SAG-7,SMLF,IC,AL080929000",,,SOT23_123XI,8810.00,3155.00,270.000,NO,,,
U8004,"74LVC2G07DW7-74LVC2G07DW-7,SMLF,EMPTY,AL002G07003",,,SOT363_0-65_2X1-25XC,7915.00,5530.00,90.000,YES,,,
U8005,"LM4040AIM3X25NOPB-LM4040AIM3X-2.5/NOPB,SMLF,EMPTY,A",,,SOT23_123_2-92X1-3,7400.00,16490.00,90.000,YES,,,
U8006,"AP331AWG7-AP331AWG-7,SMLF,EMPTY,AL000331011",,,SOT25,7375.00,16780.00,270.000,YES,,,
U8007,"LM4040AIM3X25NOPB-LM4040AIM3X-2.5/NOPB,SMLF,IC,AL4A",,,SOT23_123_2-92X1-3,4920.00,4180.00,270.000,NO,,,
U8008,"AP331AWG7-AP331AWG-7,SMLF,IC,AL000331011",,,SOT25,5245.00,4420.00,0.000,NO,,,
U8009,"LM4040AIM3X25NOPB-LM4040AIM3X-2.5/NOPB,SMLF,IC,AL4A",,,SOT23_123_2-92X1-3,5520.00,4395.00,270.000,NO,,,
U8010,"AP331AWG7-AP331AWG-7,SMLF,IC,AL000331011",,,SOT25,5605.00,4625.00,180.000,NO,,,
U8082,"74LVC1G126SE7-74LVC1G126SE-7,SMLF,IC,AL1G0126009",,,SOT353_0-65_2X1-25,18065.40,1492.75,0.000,NO,,,
U9001,"74LVC1G08W57-74LVC1G08W5-7,SMLF,IC,AL1G0008020",,,SOT25-5_0-95_3X1-6,8485.00,4720.00,90.000,NO,,,
U9002,"74LVC1G32GW_SMLF-74LVC1G32GW,IC,ALVC1G32007",,,SOT353_Q,8490.00,3930.00,0.000,NO,,,
U9050,"74LVC1G08W57-74LVC1G08W5-7,SMLF,IC,AL1G0008020",,,SOT25-5_0-95_3X1-6,8661.40,4061.90,180.000,NO,,,
U9051,"74LVC1G08W57-74LVC1G08W5-7,SMLF,IC,AL1G0008020",,,SOT25-5_0-95_3X1-6,2454.32,2113.91,0.000,NO,,,
X1,"TP_TDR_4P_FTS_TH-TP_TDR_4P_DIP,EMPTY,TP15",,,MPKT4_H025P0200,20685.39,11747.41,90.000,NO,,,
X2,"TP_TDR_4P_FTS_TH-TP_TDR_4P_DIP,EMPTY,TP15",,,MPKT4_H025P0200,20364.52,5825.69,270.000,NO,,,
X3,"TP_TDR_4P_FTS_TH-TP_TDR_4P_DIP,EMPTY,TP15",,,MPKT4_H025P0200,19844.82,11745.89,90.000,NO,,,
X4,"TP_TDR_4P_FTS_TH-TP_TDR_4P_DIP,EMPTY,TP15",,,MPKT4_H025P0200,19523.95,5824.17,270.000,NO,,,
X5,"TP_TDR_4P_FTS_TH-TP_TDR_4P_DIP,EMPTY,TP15",,,MPKT4_H025P0200,20474.19,5825.31,90.000,YES,,,
X6,"TP_TDR_4P_FTS_TH-TP_TDR_4P_DIP,EMPTY,TP15",,,MPKT4_H025P0200,19213.95,5822.37,90.000,YES,,,
X7,"TP_TDR_4P_FTS_TH-TP_TDR_4P_DIP,EMPTY,TP15",,,MPKT4_H025P0200,20785.39,5825.41,270.000,NO,,,
X8,"TP_TDR_4P_FTS_TH-TP_TDR_4P_DIP,EMPTY,TP15",,,MPKT4_H025P0200,20264.52,11747.69,90.000,NO,,,
X9,"TP_TDR_4P_FTS_TH-TP_TDR_4P_DIP,EMPTY,TP15",,,MPKT4_H025P0200,19944.82,5823.89,270.000,NO,,,
X10,"TP_TDR_4P_FTS_TH-TP_TDR_4P_DIP,EMPTY,TP15",,,MPKT4_H025P0200,19423.95,11746.17,90.000,NO,,,
X11,"TP_TDR_4P_FTS_TH-TP_TDR_4P_DIP,EMPTY,TP15",,,MPKT4_H025P0200,20574.19,11747.31,270.000,YES,,,
X12,"TP_TDR_4P_FTS_TH-TP_TDR_4P_DIP,EMPTY,TP15",,,MPKT4_H025P0200,19313.95,11744.37,270.000,YES,,,
X25,"TP_TDR_4P_FTS_TH-TP_TDR_4P_DIP,EMPTY,TP15",,,MPKT4_H025P0200,20054.52,5823.89,90.000,YES,,,
X26,"TP_TDR_4P_FTS_TH-TP_TDR_4P_DIP,EMPTY,TP15",,,MPKT4_H025P0200,19733.62,11745.79,270.000,YES,,,
X27,"TP_TDR_4P_FTS_TH-TP_TDR_4P_DIP,EMPTY,TP15",,,MPKT4_H025P0200,20154.52,11745.89,270.000,YES,,,
X28,"TP_TDR_4P_FTS_TH-TP_TDR_4P_DIP,EMPTY,TP15",,,MPKT4_H025P0200,19633.62,5823.79,90.000,YES,,,
X8001,"TP_TDR_4P_FTS_TH-TP_TDR_4P_DIP,EMPTY,TP15",,,MPKT4_H025P0200,20574.19,-296.69,270.000,NO,,,
X8002,"TP_TDR_4P_FTS_TH-TP_TDR_4P_DIP,EMPTY,TP15",,,MPKT4_H025P0200,20154.52,-298.11,270.000,NO,,,
X8003,"TP_TDR_4P_FTS_TH-TP_TDR_4P_DIP,EMPTY,TP15",,,MPKT4_H025P0200,19633.62,5623.79,90.000,NO,,,
X8004,"TP_TDR_4P_FTS_TH-TP_TDR_4P_DIP,EMPTY,TP15",,,MPKT4_H025P0200,19313.95,-299.63,270.000,NO,,,
X8005,"TP_TDR_4P_FTS_TH-TP_TDR_4P_DIP,EMPTY,TP15",,,MPKT4_H025P0200,20264.52,-296.31,90.000,YES,,,
X8006,"TP_TDR_4P_FTS_TH-TP_TDR_4P_DIP,EMPTY,TP15",,,MPKT4_H025P0200,19002.75,-299.73,90.000,YES,,,
X8007,"TP_TDR_4P_FTS_TH-TP_TDR_4P_DIP,EMPTY,TP15",,,MPKT4_H025P0200,20474.19,5625.31,90.000,NO,,,
X8008,"TP_TDR_4P_FTS_TH-TP_TDR_4P_DIP,EMPTY,TP15",,,MPKT4_H025P0200,20054.52,5623.89,90.000,NO,,,
X8009,"TP_TDR_4P_FTS_TH-TP_TDR_4P_DIP,EMPTY,TP15",,,MPKT4_H025P0200,19733.62,-298.21,270.000,NO,,,
X8010,"TP_TDR_4P_FTS_TH-TP_TDR_4P_DIP,EMPTY,TP15",,,MPKT4_H025P0200,19213.95,5622.37,90.000,NO,,,
X8011,"TP_TDR_4P_FTS_TH-TP_TDR_4P_DIP,EMPTY,TP15",,,MPKT4_H025P0200,20364.52,5625.69,270.000,YES,,,
X8012,"TP_TDR_4P_FTS_TH-TP_TDR_4P_DIP,EMPTY,TP15",,,MPKT4_H025P0200,19102.75,5622.27,270.000,YES,,,
X8025,"TP_TDR_4P_FTS_TH-TP_TDR_4P_DIP,EMPTY,TP15",,,MPKT4_H025P0200,19844.82,-298.11,90.000,YES,,,
X8026,"TP_TDR_4P_FTS_TH-TP_TDR_4P_DIP,EMPTY,TP15",,,MPKT4_H025P0200,19423.95,-297.83,90.000,YES,,,
X8027,"TP_TDR_4P_FTS_TH-TP_TDR_4P_DIP,EMPTY,TP15",,,MPKT4_H025P0200,19944.82,5623.89,270.000,YES,,,
X8028,"TP_TDR_4P_FTS_TH-TP_TDR_4P_DIP,EMPTY,TP15",,,MPKT4_H025P0200,19523.95,5624.17,270.000,YES,,,
X9002,"TP_TDR_4P_FTS_TH-TP_TDR_4P_DIP,EMPTY,TP15",,,MPKT4_H025P0200,19928.56,12083.50,270.000,NO,,,
X9003,"TP_TDR_4P_FTS_TH-TP_TDR_4P_DIP,EMPTY,TP15",,,MPKT4_H025P0200,19508.86,12081.70,270.000,NO,,,
X9004,"TP_TDR_4P_FTS_TH-TP_TDR_4P_DIP,EMPTY,TP15",,,MPKT4_H025P0200,18987.99,18003.98,90.000,NO,,,
X9005,"TP_TDR_4P_FTS_TH-TP_TDR_4P_DIP,EMPTY,TP15",,,MPKT4_H025P0200,20038.23,12083.12,90.000,YES,,,
X9008,"TP_TDR_4P_FTS_TH-TP_TDR_4P_DIP,EMPTY,TP15",,,MPKT4_H025P0200,19828.56,18005.50,90.000,NO,,,
X9009,"TP_TDR_4P_FTS_TH-TP_TDR_4P_DIP,EMPTY,TP15",,,MPKT4_H025P0200,19408.86,18003.70,90.000,NO,,,
X9010,"TP_TDR_4P_FTS_TH-TP_TDR_4P_DIP,EMPTY,TP15",,,MPKT4_H025P0200,19087.99,12081.98,270.000,NO,,,
X9011,"TP_TDR_4P_FTS_TH-TP_TDR_4P_DIP,EMPTY,TP15",,,MPKT4_H025P0200,20138.23,18005.12,270.000,YES,,,
X9025,"TP_TDR_4P_FTS_TH-TP_TDR_4P_DIP,EMPTY,TP15",,,MPKT4_H025P0200,19618.56,12081.70,90.000,YES,,,
X9026,"TP_TDR_4P_FTS_TH-TP_TDR_4P_DIP,EMPTY,TP15",,,MPKT4_H025P0200,19297.66,18003.60,270.000,YES,,,
X9027,"TP_TDR_4P_FTS_TH-TP_TDR_4P_DIP,EMPTY,TP15",,,MPKT4_H025P0200,19718.56,18003.70,270.000,YES,,,
X9028,"TP_TDR_4P_FTS_TH-TP_TDR_4P_DIP,EMPTY,TP15",,,MPKT4_H025P0200,19197.66,12081.60,90.000,YES,,,
Y2,"Q_XTAL_4P_13BI_24GND-48MHZ,SMLF,MISC,BG648000076",,,X_4S_FL4000120_3-2X2-5,15643.03,12466.62,90.000,YES,,,
Y3,"Q_CRYSTAL_SMLF-32.768KHZ,IC,BG632768012",,,X_2S_XTL721,15813.03,12477.07,180.000,YES,,,
Y4,"Q_XTAL_4P_13BI_24GND-48MHZ,SMLF,MISC,BG648000076",,,X_4S_FL4000120_3-2X2-5,5869.59,12475.75,90.000,YES,,,
Y5,"Q_CRYSTAL_SMLF-32.768KHZ,EMPTY,BG632768012",,,X_2S_XTL721,6041.59,12540.75,180.000,YES,,,
Y9,"Q_XTAL_4P_13BI_24GND-26MHZ,SMLF,MISC,BG626000049",,,X_4S_8Z25000020_2-5X2,4900.00,1136.01,180.000,NO,,,
Y6000,"Q_XTAL_4P_13BI_24GND-24MHZ,SMLF,MISC,BG624000101",,,X_7MXA,4183.09,876.83,180.000,NO,,,
Y8003,"Q_XTAL_4P_13BI_24GND-25MHZ,SMLF,MISC,BG6250000L4",,,OSC4_E3FB,237.37,5330.24,0.000,NO,,,
Y8004,"Q_XTAL_4P_13BI_24GND-12MHZ,SMLF,MISC,BG6120000B0",,,X_4S_8Z25000020_2-5X2,280.48,3914.25,0.000,NO,,,
